G04 ================== begin FILE IDENTIFICATION RECORD ==================*
G04 Layout Name:  9127_F0T_Expander_BD_F_v02_0110_1240.brd*
G04 Film Name:    gnd3*
G04 File Format:  Gerber RS274X*
G04 File Origin:  Cadence Allegro 17.2-S081*
G04 Origin Date:  Wed Jan 11 16:06:29 2023*
G04 *
G04 Layer:  VIA CLASS/GND3*
G04 Layer:  PIN/GND3*
G04 Layer:  ETCH/GND3*
G04 Layer:  DRAWING FORMAT/TITLE_BLOCK_A*
G04 Layer:  PIN/SPECIAL_DRILL*
G04 Layer:  MANUFACTURING/PHOTOPLOT_OUTLINE*
G04 Layer:  DRAWING FORMAT/TITLE_BLOCK*
G04 Layer:  DRAWING FORMAT/TITLE_DATA_GND3*
G04 *
G04 Offset:    (0.00 0.00)*
G04 Mirror:    No*
G04 Mode:      Negative*
G04 Rotation:  0*
G04 FullContactRelief:  No*
G04 UndefLineWidth:     6.00*
G04 ================== end FILE IDENTIFICATION RECORD ====================*
%FSLAX25Y25*MOIN*%
%IR0*IPPOS*OFA0.00000B0.00000*MIA0B0*SFA1.00000B1.00000*%
%ADD15C,.03*%
%ADD53C,.06*%
%ADD23C,.024*%
%ADD54C,.061*%
%ADD33C,.0322*%
%ADD45C,.071*%
%AMMACRO29*
4,1,36,0.0,.01,
-.001736,.009848,
-.00342,.009397,
-.005,.00866,
-.006428,.00766,
-.00766,.006428,
-.00866,.005,
-.009397,.00342,
-.009848,.001736,
-.01,0.0,
-.009848,-.001736,
-.009397,-.00342,
-.00866,-.005,
-.00766,-.006428,
-.006428,-.00766,
-.005,-.00866,
-.00342,-.009397,
-.001736,-.009848,
0.0,-.01,
.001736,-.009848,
.00342,-.009397,
.005,-.00866,
.006428,-.00766,
.00766,-.006428,
.00866,-.005,
.009397,-.00342,
.009848,-.001736,
.01,0.0,
.009848,.001736,
.009397,.00342,
.00866,.005,
.00766,.006428,
.006428,.00766,
.005,.00866,
.00342,.009397,
.001736,.009848,
0.0,.01,
0.0*
%
%ADD29MACRO29*%
%ADD28C,.026*%
%ADD51C,.082*%
%ADD43C,.028*%
%AMMACRO39*
4,1,20,-.0075,-.05555,
-.0075,-.06273,
-.013677,-.060878,
-.019439,-.057981,
-.024611,-.054127,
-.029034,-.049434,
-.032576,-.044045,
-.035127,-.038122,
-.036612,-.031846,
-.037,-.0265,
-.037,-.0075,
-.03,-.0075,
-.03,-.0265,
-.029544,-.03171,
-.028191,-.036762,
-.02598,-.041502,
-.022981,-.045786,
-.019282,-.049484,
-.014998,-.052484,
-.010258,-.054694,
-.0075,-.05555,
270.*
4,1,20,.0075,-.06273,
.0075,-.05555,
.01243,-.053806,
.016983,-.051232,
.02102,-.047906,
.024418,-.043931,
.027073,-.039425,
.028906,-.034527,
.029861,-.029385,
.03,-.0265,
.03,-.0075,
.037,-.0075,
.037,-.0265,
.036438,-.032925,
.034769,-.039154,
.032043,-.044999,
.028344,-.050282,
.023784,-.054842,
.018501,-.058541,
.012656,-.061266,
.0075,-.06273,
270.*
4,1,20,-.0075,.06273,
-.0075,.05555,
-.01243,.053806,
-.016983,.051232,
-.02102,.047906,
-.024418,.043931,
-.027073,.039425,
-.028906,.034527,
-.029861,.029385,
-.03,.0265,
-.03,.0075,
-.037,.0075,
-.037,.0265,
-.036438,.032925,
-.034769,.039154,
-.032043,.044999,
-.028344,.050282,
-.023784,.054842,
-.018501,.058541,
-.012656,.061266,
-.0075,.06273,
270.*
4,1,20,.0075,.05555,
.0075,.06273,
.013677,.060878,
.019439,.057981,
.024611,.054127,
.029034,.049434,
.032576,.044045,
.035127,.038122,
.036612,.031846,
.037,.0265,
.037,.0075,
.03,.0075,
.03,.0265,
.029544,.03171,
.028191,.036762,
.02598,.041502,
.022981,.045786,
.019282,.049484,
.014998,.052484,
.010258,.054694,
.0075,.05555,
270.*
%
%ADD39MACRO39*%
%AMMACRO31*
4,1,36,.0025,0.0,
.002462,.000434,
.002349,.000855,
.002165,.00125,
.001915,.001607,
.001607,.001915,
.00125,.002165,
.000855,.002349,
.000434,.002462,
0.0,.0025,
-.000434,.002462,
-.000855,.002349,
-.00125,.002165,
-.001607,.001915,
-.001915,.001607,
-.002165,.00125,
-.002349,.000855,
-.002462,.000434,
-.0025,0.0,
-.002462,-.000434,
-.002349,-.000855,
-.002165,-.00125,
-.001915,-.001607,
-.001607,-.001915,
-.00125,-.002165,
-.000855,-.002349,
-.000434,-.002462,
0.0,-.0025,
.000434,-.002462,
.000855,-.002349,
.00125,-.002165,
.001607,-.001915,
.001915,-.001607,
.002165,-.00125,
.002349,-.000855,
.002462,-.000434,
.0025,0.0,
315.*
%
%ADD31MACRO31*%
%AMMACRO14*
4,1,36,.0025,0.0,
.002462,.000434,
.002349,.000855,
.002165,.00125,
.001915,.001607,
.001607,.001915,
.00125,.002165,
.000855,.002349,
.000434,.002462,
0.0,.0025,
-.000434,.002462,
-.000855,.002349,
-.00125,.002165,
-.001607,.001915,
-.001915,.001607,
-.002165,.00125,
-.002349,.000855,
-.002462,.000434,
-.0025,0.0,
-.002462,-.000434,
-.002349,-.000855,
-.002165,-.00125,
-.001915,-.001607,
-.001607,-.001915,
-.00125,-.002165,
-.000855,-.002349,
-.000434,-.002462,
0.0,-.0025,
.000434,-.002462,
.000855,-.002349,
.00125,-.002165,
.001607,-.001915,
.001915,-.001607,
.002165,-.00125,
.002349,-.000855,
.002462,-.000434,
.0025,0.0,
180.*
%
%ADD14MACRO14*%
%AMMACRO10*
4,1,36,.0025,0.0,
.002462,.000434,
.002349,.000855,
.002165,.00125,
.001915,.001607,
.001607,.001915,
.00125,.002165,
.000855,.002349,
.000434,.002462,
0.0,.0025,
-.000434,.002462,
-.000855,.002349,
-.00125,.002165,
-.001607,.001915,
-.001915,.001607,
-.002165,.00125,
-.002349,.000855,
-.002462,.000434,
-.0025,0.0,
-.002462,-.000434,
-.002349,-.000855,
-.002165,-.00125,
-.001915,-.001607,
-.001607,-.001915,
-.00125,-.002165,
-.000855,-.002349,
-.000434,-.002462,
0.0,-.0025,
.000434,-.002462,
.000855,-.002349,
.00125,-.002165,
.001607,-.001915,
.001915,-.001607,
.002165,-.00125,
.002349,-.000855,
.002462,-.000434,
.0025,0.0,
270.*
%
%ADD10MACRO10*%
%AMMACRO46*
4,1,36,-.0025,0.0,
-.002462,.000434,
-.002349,.000855,
-.002165,.00125,
-.001915,.001607,
-.001607,.001915,
-.00125,.002165,
-.000855,.002349,
-.000434,.002462,
0.0,.0025,
.000434,.002462,
.000855,.002349,
.00125,.002165,
.001607,.001915,
.001915,.001607,
.002165,.00125,
.002349,.000855,
.002462,.000434,
.0025,0.0,
.002462,-.000434,
.002349,-.000855,
.002165,-.00125,
.001915,-.001607,
.001607,-.001915,
.00125,-.002165,
.000855,-.002349,
.000434,-.002462,
0.0,-.0025,
-.000434,-.002462,
-.000855,-.002349,
-.00125,-.002165,
-.001607,-.001915,
-.001915,-.001607,
-.002165,-.00125,
-.002349,-.000855,
-.002462,-.000434,
-.0025,0.0,
180.*
%
%ADD46MACRO46*%
%AMMACRO37*
4,1,36,.003,0.0,
.002954,.000521,
.002819,.001026,
.002598,.0015,
.002298,.001928,
.001928,.002298,
.0015,.002598,
.001026,.002819,
.000521,.002954,
0.0,.003,
-.000521,.002954,
-.001026,.002819,
-.0015,.002598,
-.001928,.002298,
-.002298,.001928,
-.002598,.0015,
-.002819,.001026,
-.002954,.000521,
-.003,0.0,
-.002954,-.000521,
-.002819,-.001026,
-.002598,-.0015,
-.002298,-.001928,
-.001928,-.002298,
-.0015,-.002598,
-.001026,-.002819,
-.000521,-.002954,
0.0,-.003,
.000521,-.002954,
.001026,-.002819,
.0015,-.002598,
.001928,-.002298,
.002298,-.001928,
.002598,-.0015,
.002819,-.001026,
.002954,-.000521,
.003,0.0,
270.*
%
%ADD37MACRO37*%
%AMMACRO25*
4,1,36,.003,0.0,
.002954,.000521,
.002819,.001026,
.002598,.0015,
.002298,.001928,
.001928,.002298,
.0015,.002598,
.001026,.002819,
.000521,.002954,
0.0,.003,
-.000521,.002954,
-.001026,.002819,
-.0015,.002598,
-.001928,.002298,
-.002298,.001928,
-.002598,.0015,
-.002819,.001026,
-.002954,.000521,
-.003,0.0,
-.002954,-.000521,
-.002819,-.001026,
-.002598,-.0015,
-.002298,-.001928,
-.001928,-.002298,
-.0015,-.002598,
-.001026,-.002819,
-.000521,-.002954,
0.0,-.003,
.000521,-.002954,
.001026,-.002819,
.0015,-.002598,
.001928,-.002298,
.002298,-.001928,
.002598,-.0015,
.002819,-.001026,
.002954,-.000521,
.003,0.0,
180.*
%
%ADD25MACRO25*%
%ADD22C,.074*%
%AMMACRO42*
4,1,36,-.003,0.0,
-.002954,.000521,
-.002819,.001026,
-.002598,.0015,
-.002298,.001928,
-.001928,.002298,
-.0015,.002598,
-.001026,.002819,
-.000521,.002954,
0.0,.003,
.000521,.002954,
.001026,.002819,
.0015,.002598,
.001928,.002298,
.002298,.001928,
.002598,.0015,
.002819,.001026,
.002954,.000521,
.003,0.0,
.002954,-.000521,
.002819,-.001026,
.002598,-.0015,
.002298,-.001928,
.001928,-.002298,
.0015,-.002598,
.001026,-.002819,
.000521,-.002954,
0.0,-.003,
-.000521,-.002954,
-.001026,-.002819,
-.0015,-.002598,
-.001928,-.002298,
-.002298,-.001928,
-.002598,-.0015,
-.002819,-.001026,
-.002954,-.000521,
-.003,0.0,
180.*
%
%ADD42MACRO42*%
%ADD26C,.0435*%
%ADD35C,.0257*%
%ADD58C,.087*%
%ADD20C,.0277*%
%AMMACRO44*
4,1,18,.09673,.06845,
.107147,.050613,
.114308,.031238,
.117996,.010914,
.118098,-.009741,
.114613,-.030101,
.107644,-.049546,
.097406,-.067485,
.09673,-.06845,
.10175,-.07347,
.112962,-.054685,
.120742,-.034239,
.124853,-.012752,
.125171,.009122,
.121685,.030719,
.114502,.051383,
.10384,.070486,
.10175,.07347,
.09673,.06845,
90.*
4,1,18,.06845,-.09673,
.050613,-.107147,
.031238,-.114308,
.010914,-.117996,
-.009741,-.118098,
-.030101,-.114613,
-.049546,-.107644,
-.067485,-.097406,
-.06845,-.09673,
-.07347,-.10175,
-.054685,-.112962,
-.034239,-.120742,
-.012752,-.124853,
.009122,-.125171,
.030719,-.121685,
.051383,-.114502,
.070486,-.10384,
.07347,-.10175,
.06845,-.09673,
90.*
4,1,18,-.09673,-.06845,
-.107147,-.050613,
-.114308,-.031238,
-.117996,-.010914,
-.118098,.009741,
-.114613,.030101,
-.107644,.049546,
-.097406,.067485,
-.09673,.06845,
-.10175,.07347,
-.112962,.054685,
-.120742,.034239,
-.124853,.012752,
-.125171,-.009122,
-.121685,-.030719,
-.114502,-.051383,
-.10384,-.070486,
-.10175,-.07347,
-.09673,-.06845,
90.*
4,1,18,-.06845,.09673,
-.050613,.107147,
-.031238,.114308,
-.010914,.117996,
.009741,.118098,
.030101,.114613,
.049546,.107644,
.067485,.097406,
.06845,.09673,
.07347,.10175,
.054685,.112962,
.034239,.120742,
.012752,.124853,
-.009122,.125171,
-.030719,.121685,
-.051383,.114502,
-.070486,.10384,
-.07347,.10175,
-.06845,.09673,
90.*
%
%ADD44MACRO44*%
%AMMACRO11*
4,1,15,.06231,.03403,
.067273,.022693,
.070191,.010666,
.070977,-.001684,
.069606,-.013984,
.066121,-.025858,
.06231,-.03403,
.06745,-.03917,
.073227,-.026862,
.076779,-.013739,
.077998,-.000197,
.076848,.01335,
.073362,.026492,
.067647,.038828,
.06745,.03917,
.06231,.03403,
0.0*
4,1,15,.03403,-.06231,
.022693,-.067273,
.010666,-.070191,
-.001684,-.070977,
-.013984,-.069606,
-.025858,-.066121,
-.03403,-.06231,
-.03917,-.06745,
-.026862,-.073227,
-.013739,-.076779,
-.000197,-.077998,
.01335,-.076848,
.026492,-.073362,
.038828,-.067647,
.03917,-.06745,
.03403,-.06231,
0.0*
4,1,15,-.06231,-.03403,
-.067273,-.022693,
-.070191,-.010666,
-.070977,.001684,
-.069606,.013984,
-.066121,.025858,
-.06231,.03403,
-.06745,.03917,
-.073227,.026862,
-.076779,.013739,
-.077998,.000197,
-.076848,-.01335,
-.073362,-.026492,
-.067647,-.038828,
-.06745,-.03917,
-.06231,-.03403,
0.0*
4,1,15,-.03403,.06231,
-.022693,.067273,
-.010666,.070191,
.001684,.070977,
.013984,.069606,
.025858,.066121,
.03403,.06231,
.03917,.06745,
.026862,.073227,
.013739,.076779,
.000197,.077998,
-.01335,.076848,
-.026492,.073362,
-.038828,.067647,
-.03917,.06745,
-.03403,.06231,
0.0*
%
%ADD11MACRO11*%
%ADD19C,.099*%
%AMMACRO18*
4,1,18,.09673,.06845,
.107147,.050613,
.114308,.031238,
.117996,.010914,
.118098,-.009741,
.114613,-.030101,
.107644,-.049546,
.097406,-.067485,
.09673,-.06845,
.10175,-.07347,
.112962,-.054685,
.120742,-.034239,
.124853,-.012752,
.125171,.009122,
.121685,.030719,
.114502,.051383,
.10384,.070486,
.10175,.07347,
.09673,.06845,
0.0*
4,1,18,.06845,-.09673,
.050613,-.107147,
.031238,-.114308,
.010914,-.117996,
-.009741,-.118098,
-.030101,-.114613,
-.049546,-.107644,
-.067485,-.097406,
-.06845,-.09673,
-.07347,-.10175,
-.054685,-.112962,
-.034239,-.120742,
-.012752,-.124853,
.009122,-.125171,
.030719,-.121685,
.051383,-.114502,
.070486,-.10384,
.07347,-.10175,
.06845,-.09673,
0.0*
4,1,18,-.09673,-.06845,
-.107147,-.050613,
-.114308,-.031238,
-.117996,-.010914,
-.118098,.009741,
-.114613,.030101,
-.107644,.049546,
-.097406,.067485,
-.09673,.06845,
-.10175,.07347,
-.112962,.054685,
-.120742,.034239,
-.124853,.012752,
-.125171,-.009122,
-.121685,-.030719,
-.114502,-.051383,
-.10384,-.070486,
-.10175,-.07347,
-.09673,-.06845,
0.0*
4,1,18,-.06845,.09673,
-.050613,.107147,
-.031238,.114308,
-.010914,.117996,
.009741,.118098,
.030101,.114613,
.049546,.107644,
.067485,.097406,
.06845,.09673,
.07347,.10175,
.054685,.112962,
.034239,.120742,
.012752,.124853,
-.009122,.125171,
-.030719,.121685,
-.051383,.114502,
-.070486,.10384,
-.07347,.10175,
-.06845,.09673,
0.0*
%
%ADD18MACRO18*%
%ADD34C,.0299*%
%AMMACRO61*
4,1,19,-.0075,-.03785,
-.011528,-.036185,
-.015205,-.033846,
-.01842,-.030904,
-.021075,-.027448,
-.02309,-.023584,
-.024404,-.019428,
-.024975,-.015108,
-.025,-.014,
-.025,-.0075,
-.018,-.0075,
-.018,-.014,
-.017727,-.017125,
-.016915,-.020155,
-.015589,-.022998,
-.01379,-.025567,
-.011572,-.027785,
-.009002,-.029584,
-.0075,-.03036,
-.0075,-.03785,
180.*
4,1,19,.0075,-.03785,
.0075,-.03036,
.010227,-.02881,
.012643,-.02681,
.014676,-.024421,
.016262,-.021715,
.017355,-.018774,
.017921,-.015689,
.018,-.014,
.018,-.0075,
.025,-.0075,
.025,-.014,
.02462,-.018342,
.023492,-.022551,
.02165,-.026501,
.019151,-.030071,
.016069,-.033153,
.012499,-.035652,
.008549,-.037494,
.0075,-.03785,
180.*
4,1,19,-.025,.0075,
-.025,.014,
-.02462,.018342,
-.023492,.022551,
-.02165,.026501,
-.019151,.030071,
-.016069,.033153,
-.012499,.035652,
-.008549,.037494,
-.0075,.03785,
-.0075,.03036,
-.010227,.02881,
-.012643,.02681,
-.014676,.024421,
-.016262,.021715,
-.017355,.018774,
-.017921,.015689,
-.018,.014,
-.018,.0075,
-.025,.0075,
180.*
4,1,19,.018,.0075,
.018,.014,
.017727,.017125,
.016915,.020155,
.015589,.022998,
.01379,.025567,
.011572,.027785,
.009002,.029584,
.0075,.03036,
.0075,.03785,
.011528,.036185,
.015205,.033846,
.01842,.030904,
.021075,.027448,
.02309,.023584,
.024404,.019428,
.024975,.015108,
.025,.014,
.025,.0075,
.018,.0075,
180.*
%
%ADD61MACRO61*%
%AMMACRO38*
4,1,16,.02584,.01524,
.028094,.010521,
.029494,.005483,
.029998,.000278,
.029591,-.004935,
.028284,-.009999,
.026118,-.014758,
.02584,-.01524,
.03092,-.02032,
.033979,-.014642,
.036005,-.008519,
.036938,-.002138,
.036748,.004309,
.035441,.010625,
.033058,.016618,
.03092,.02032,
.02584,.01524,
0.0*
4,1,16,.01524,-.02584,
.010521,-.028094,
.005483,-.029494,
.000278,-.029998,
-.004935,-.029591,
-.009999,-.028284,
-.014758,-.026118,
-.01524,-.02584,
-.02032,-.03092,
-.014642,-.033979,
-.008519,-.036005,
-.002138,-.036938,
.004309,-.036748,
.010625,-.035441,
.016618,-.033058,
.02032,-.03092,
.01524,-.02584,
0.0*
4,1,16,-.02584,-.01524,
-.028094,-.010521,
-.029494,-.005483,
-.029998,-.000278,
-.029591,.004935,
-.028284,.009999,
-.026118,.014758,
-.02584,.01524,
-.03092,.02032,
-.033979,.014642,
-.036005,.008519,
-.036938,.002138,
-.036748,-.004309,
-.035441,-.010625,
-.033058,-.016618,
-.03092,-.02032,
-.02584,-.01524,
0.0*
4,1,16,-.01524,.02584,
-.010521,.028094,
-.005483,.029494,
-.000278,.029998,
.004935,.029591,
.009999,.028284,
.014758,.026118,
.01524,.02584,
.02032,.03092,
.014642,.033979,
.008519,.036005,
.002138,.036938,
-.004309,.036748,
-.010625,.035441,
-.016618,.033058,
-.02032,.03092,
-.01524,.02584,
0.0*
%
%ADD38MACRO38*%
%AMMACRO50*
4,1,15,.02142,.01082,
.022973,.006936,
.023829,.002841,
.02396,-.00134,
.023364,-.00548,
.022057,-.009454,
.02142,-.01082,
.02657,-.01597,
.02894,-.011114,
.03043,-.005919,
.030995,-.000545,
.030619,.004845,
.029313,.010088,
.027115,.015025,
.02657,.01597,
.02142,.01082,
90.*
4,1,15,.01082,-.02142,
.006936,-.022973,
.002841,-.023829,
-.00134,-.02396,
-.00548,-.023364,
-.009454,-.022057,
-.01082,-.02142,
-.01597,-.02657,
-.011114,-.02894,
-.005919,-.03043,
-.000545,-.030995,
.004845,-.030619,
.010088,-.029313,
.015025,-.027115,
.01597,-.02657,
.01082,-.02142,
90.*
4,1,15,-.02142,-.01082,
-.022973,-.006936,
-.023829,-.002841,
-.02396,.00134,
-.023364,.00548,
-.022057,.009454,
-.02142,.01082,
-.02657,.01597,
-.02894,.011114,
-.03043,.005919,
-.030995,.000545,
-.030619,-.004845,
-.029313,-.010088,
-.027115,-.015025,
-.02657,-.01597,
-.02142,-.01082,
90.*
4,1,15,-.01082,.02142,
-.006936,.022973,
-.002841,.023829,
.00134,.02396,
.00548,.023364,
.009454,.022057,
.01082,.02142,
.01597,.02657,
.011114,.02894,
.005919,.03043,
.000545,.030995,
-.004845,.030619,
-.010088,.029313,
-.015025,.027115,
-.01597,.02657,
-.01082,.02142,
90.*
%
%ADD50MACRO50*%
%AMMACRO48*
4,1,18,.07103,.05689,
.07983,.043691,
.086204,.029165,
.089959,.013753,
.09098,-.002077,
.089237,-.017844,
.084783,-.033069,
.077753,-.047289,
.07103,-.05689,
.07601,-.06186,
.085597,-.047721,
.092583,-.032132,
.096757,-.015567,
.09799,.001471,
.096246,.018464,
.091577,.034897,
.084126,.050269,
.07601,.06186,
.07103,.05689,
90.*
4,1,18,.05689,-.07103,
.043691,-.07983,
.029165,-.086204,
.013753,-.089959,
-.002077,-.09098,
-.017844,-.089237,
-.033069,-.084783,
-.047289,-.077753,
-.05689,-.07103,
-.06186,-.07601,
-.047721,-.085597,
-.032132,-.092583,
-.015567,-.096757,
.001471,-.09799,
.018464,-.096246,
.034897,-.091577,
.050269,-.084126,
.06186,-.07601,
.05689,-.07103,
90.*
4,1,18,-.07103,-.05689,
-.07983,-.043691,
-.086204,-.029165,
-.089959,-.013753,
-.09098,.002077,
-.089237,.017844,
-.084783,.033069,
-.077753,.047289,
-.07103,.05689,
-.07601,.06186,
-.085597,.047721,
-.092583,.032132,
-.096757,.015567,
-.09799,-.001471,
-.096246,-.018464,
-.091577,-.034897,
-.084126,-.050269,
-.07601,-.06186,
-.07103,-.05689,
90.*
4,1,18,-.05689,.07103,
-.043691,.07983,
-.029165,.086204,
-.013753,.089959,
.002077,.09098,
.017844,.089237,
.033069,.084783,
.047289,.077753,
.05689,.07103,
.06186,.07601,
.047721,.085597,
.032132,.092583,
.015567,.096757,
-.001471,.09799,
-.018464,.096246,
-.034897,.091577,
-.050269,.084126,
-.06186,.07601,
-.05689,.07103,
90.*
%
%ADD48MACRO48*%
%AMMACRO62*
4,1,19,-.0075,-.04535,
-.011528,-.043685,
-.015205,-.041346,
-.01842,-.038404,
-.021075,-.034948,
-.02309,-.031084,
-.024404,-.026928,
-.024975,-.022608,
-.025,-.0215,
-.025,-.0075,
-.018,-.0075,
-.018,-.0215,
-.017727,-.024625,
-.016915,-.027655,
-.015589,-.030498,
-.01379,-.033067,
-.011572,-.035285,
-.009002,-.037084,
-.0075,-.03786,
-.0075,-.04535,
180.*
4,1,19,.0075,-.04535,
.0075,-.03786,
.010227,-.03631,
.012643,-.03431,
.014676,-.031921,
.016262,-.029215,
.017355,-.026274,
.017921,-.023189,
.018,-.0215,
.018,-.0075,
.025,-.0075,
.025,-.0215,
.02462,-.025842,
.023492,-.030051,
.02165,-.034001,
.019151,-.037571,
.016069,-.040653,
.012499,-.043152,
.008549,-.044994,
.0075,-.04535,
180.*
4,1,19,-.025,.0075,
-.025,.0215,
-.02462,.025842,
-.023492,.030051,
-.02165,.034001,
-.019151,.037571,
-.016069,.040653,
-.012499,.043152,
-.008549,.044994,
-.0075,.04535,
-.0075,.03786,
-.010227,.03631,
-.012643,.03431,
-.014676,.031921,
-.016262,.029215,
-.017355,.026274,
-.017921,.023189,
-.018,.0215,
-.018,.0075,
-.025,.0075,
180.*
4,1,19,.018,.0075,
.018,.0215,
.017727,.024625,
.016915,.027655,
.015589,.030498,
.01379,.033067,
.011572,.035285,
.009002,.037084,
.0075,.03786,
.0075,.04535,
.011528,.043685,
.015205,.041346,
.01842,.038404,
.021075,.034948,
.02309,.031084,
.024404,.026928,
.024975,.022608,
.025,.0215,
.025,.0075,
.018,.0075,
180.*
%
%ADD62MACRO62*%
%AMMACRO55*
4,1,15,.02475,.01414,
.026829,.009627,
.028094,.004822,
.028504,-.000129,
.028049,-.005077,
.026741,-.009871,
.02475,-.01414,
.02984,-.01923,
.032726,-.013756,
.034617,-.007864,
.035457,-.001734,
.03522,.00445,
.033912,.010498,
.031574,.016227,
.02984,.01923,
.02475,.01414,
0.0*
4,1,15,.01414,-.02475,
.009627,-.026829,
.004822,-.028094,
-.000129,-.028504,
-.005077,-.028049,
-.009871,-.026741,
-.01414,-.02475,
-.01923,-.02984,
-.013756,-.032726,
-.007864,-.034617,
-.001734,-.035457,
.00445,-.03522,
.010498,-.033912,
.016227,-.031574,
.01923,-.02984,
.01414,-.02475,
0.0*
4,1,15,-.02475,-.01414,
-.026829,-.009627,
-.028094,-.004822,
-.028504,.000129,
-.028049,.005077,
-.026741,.009871,
-.02475,.01414,
-.02984,.01923,
-.032726,.013756,
-.034617,.007864,
-.035457,.001734,
-.03522,-.00445,
-.033912,-.010498,
-.031574,-.016227,
-.02984,-.01923,
-.02475,-.01414,
0.0*
4,1,15,-.01414,.02475,
-.009627,.026829,
-.004822,.028094,
.000129,.028504,
.005077,.028049,
.009871,.026741,
.01414,.02475,
.01923,.02984,
.013756,.032726,
.007864,.034617,
.001734,.035457,
-.00445,.03522,
-.010498,.033912,
-.016227,.031574,
-.01923,.02984,
-.01414,.02475,
0.0*
%
%ADD55MACRO55*%
%AMMACRO59*
4,1,15,.03682,.01914,
.039584,.012455,
.041146,.005393,
.041457,-.001834,
.040509,-.009005,
.03833,-.015903,
.03682,-.01914,
.04197,-.0243,
.045552,-.016643,
.04775,-.00848,
.048497,-.000059,
.047771,.008363,
.045593,.016531,
.042029,.024197,
.04197,.0243,
.03682,.01914,
90.*
4,1,15,.01914,-.03682,
.012455,-.039584,
.005393,-.041146,
-.001834,-.041457,
-.009005,-.040509,
-.015903,-.03833,
-.01914,-.03682,
-.0243,-.04197,
-.016643,-.045552,
-.00848,-.04775,
-.000059,-.048497,
.008363,-.047771,
.016531,-.045593,
.024197,-.042029,
.0243,-.04197,
.01914,-.03682,
90.*
4,1,15,-.03682,-.01914,
-.039584,-.012455,
-.041146,-.005393,
-.041457,.001834,
-.040509,.009005,
-.03833,.015903,
-.03682,.01914,
-.04197,.0243,
-.045552,.016643,
-.04775,.00848,
-.048497,.000059,
-.047771,-.008363,
-.045593,-.016531,
-.042029,-.024197,
-.04197,-.0243,
-.03682,-.01914,
90.*
4,1,15,-.01914,.03682,
-.012455,.039584,
-.005393,.041146,
.001834,.041457,
.009005,.040509,
.015903,.03833,
.01914,.03682,
.0243,.04197,
.016643,.045552,
.00848,.04775,
.000059,.048497,
-.008363,.047771,
-.016531,.045593,
-.024197,.042029,
-.0243,.04197,
-.01914,.03682,
90.*
%
%ADD59MACRO59*%
%AMMACRO60*
4,1,15,-.03682,.01914,
-.039584,.012455,
-.041146,.005393,
-.041457,-.001834,
-.040509,-.009005,
-.03833,-.015903,
-.03682,-.01914,
-.04197,-.0243,
-.045552,-.016643,
-.04775,-.00848,
-.048497,-.000059,
-.047771,.008363,
-.045593,.016531,
-.042029,.024197,
-.04197,.0243,
-.03682,.01914,
90.*
4,1,15,-.01914,-.03682,
-.012455,-.039584,
-.005393,-.041146,
.001834,-.041457,
.009005,-.040509,
.015903,-.03833,
.01914,-.03682,
.0243,-.04197,
.016643,-.045552,
.00848,-.04775,
.000059,-.048497,
-.008363,-.047771,
-.016531,-.045593,
-.024197,-.042029,
-.0243,-.04197,
-.01914,-.03682,
90.*
4,1,15,.03682,-.01914,
.039584,-.012455,
.041146,-.005393,
.041457,.001834,
.040509,.009005,
.03833,.015903,
.03682,.01914,
.04197,.0243,
.045552,.016643,
.04775,.00848,
.048497,.000059,
.047771,-.008363,
.045593,-.016531,
.042029,-.024197,
.04197,-.0243,
.03682,-.01914,
90.*
4,1,15,.01914,.03682,
.012455,.039584,
.005393,.041146,
-.001834,.041457,
-.009005,.040509,
-.015903,.03833,
-.01914,.03682,
-.0243,.04197,
-.016643,.045552,
-.00848,.04775,
-.000059,.048497,
.008363,.047771,
.016531,.045593,
.024197,.042029,
.0243,.04197,
.01914,.03682,
90.*
%
%ADD60MACRO60*%
%ADD63C,.142*%
%ADD13C,.125*%
%ADD30C,.208*%
%ADD47C,.164*%
%ADD17C,.155*%
%ADD40C,.256*%
%AMMACRO32*
4,1,36,0.0,.0085,
.001476,.008371,
.002907,.007987,
.00425,.007361,
.005464,.006511,
.006511,.005464,
.007361,.00425,
.007987,.002907,
.008371,.001476,
.0085,0.0,
.008371,-.001476,
.007987,-.002907,
.007361,-.00425,
.006511,-.005464,
.005464,-.006511,
.00425,-.007361,
.002907,-.007987,
.001476,-.008371,
0.0,-.0085,
-.001476,-.008371,
-.002907,-.007987,
-.00425,-.007361,
-.005464,-.006511,
-.006511,-.005464,
-.007361,-.00425,
-.007987,-.002907,
-.008371,-.001476,
-.0085,0.0,
-.008371,.001476,
-.007987,.002907,
-.007361,.00425,
-.006511,.005464,
-.005464,.006511,
-.00425,.007361,
-.002907,.007987,
-.001476,.008371,
0.0,.0085,
180.*
%
%ADD32MACRO32*%
%AMMACRO49*
4,1,36,0.0,.0185,
-.003212,.018219,
-.006327,.017384,
-.00925,.016021,
-.011892,.014172,
-.014172,.011892,
-.016021,.00925,
-.017384,.006327,
-.018219,.003212,
-.0185,0.0,
-.018219,-.003212,
-.017384,-.006327,
-.016021,-.00925,
-.014172,-.011892,
-.011892,-.014172,
-.00925,-.016021,
-.006327,-.017384,
-.003212,-.018219,
0.0,-.0185,
.003212,-.018219,
.006327,-.017384,
.00925,-.016021,
.011892,-.014172,
.014172,-.011892,
.016021,-.00925,
.017384,-.006327,
.018219,-.003212,
.0185,0.0,
.018219,.003212,
.017384,.006327,
.016021,.00925,
.014172,.011892,
.011892,.014172,
.00925,.016021,
.006327,.017384,
.003212,.018219,
0.0,.0185,
270.*
%
%ADD49MACRO49*%
%AMMACRO21*
4,1,20,-.0075,-.05555,
-.0075,-.06273,
-.013677,-.060878,
-.019439,-.057981,
-.024611,-.054127,
-.029034,-.049434,
-.032576,-.044045,
-.035127,-.038122,
-.036612,-.031846,
-.037,-.0265,
-.037,-.0075,
-.03,-.0075,
-.03,-.0265,
-.029544,-.03171,
-.028191,-.036762,
-.02598,-.041502,
-.022981,-.045786,
-.019282,-.049484,
-.014998,-.052484,
-.010258,-.054694,
-.0075,-.05555,
90.*
4,1,20,.0075,-.06273,
.0075,-.05555,
.01243,-.053806,
.016983,-.051232,
.02102,-.047906,
.024418,-.043931,
.027073,-.039425,
.028906,-.034527,
.029861,-.029385,
.03,-.0265,
.03,-.0075,
.037,-.0075,
.037,-.0265,
.036438,-.032925,
.034769,-.039154,
.032043,-.044999,
.028344,-.050282,
.023784,-.054842,
.018501,-.058541,
.012656,-.061266,
.0075,-.06273,
90.*
4,1,20,-.0075,.06273,
-.0075,.05555,
-.01243,.053806,
-.016983,.051232,
-.02102,.047906,
-.024418,.043931,
-.027073,.039425,
-.028906,.034527,
-.029861,.029385,
-.03,.0265,
-.03,.0075,
-.037,.0075,
-.037,.0265,
-.036438,.032925,
-.034769,.039154,
-.032043,.044999,
-.028344,.050282,
-.023784,.054842,
-.018501,.058541,
-.012656,.061266,
-.0075,.06273,
90.*
4,1,20,.0075,.05555,
.0075,.06273,
.013677,.060878,
.019439,.057981,
.024611,.054127,
.029034,.049434,
.032576,.044045,
.035127,.038122,
.036612,.031846,
.037,.0265,
.037,.0075,
.03,.0075,
.03,.0265,
.029544,.03171,
.028191,.036762,
.02598,.041502,
.022981,.045786,
.019282,.049484,
.014998,.052484,
.010258,.054694,
.0075,.05555,
90.*
%
%ADD21MACRO21*%
%AMMACRO16*
4,1,36,.0025,0.0,
.002462,.000434,
.002349,.000855,
.002165,.00125,
.001915,.001607,
.001607,.001915,
.00125,.002165,
.000855,.002349,
.000434,.002462,
0.0,.0025,
-.000434,.002462,
-.000855,.002349,
-.00125,.002165,
-.001607,.001915,
-.001915,.001607,
-.002165,.00125,
-.002349,.000855,
-.002462,.000434,
-.0025,0.0,
-.002462,-.000434,
-.002349,-.000855,
-.002165,-.00125,
-.001915,-.001607,
-.001607,-.001915,
-.00125,-.002165,
-.000855,-.002349,
-.000434,-.002462,
0.0,-.0025,
.000434,-.002462,
.000855,-.002349,
.00125,-.002165,
.001607,-.001915,
.001915,-.001607,
.002165,-.00125,
.002349,-.000855,
.002462,-.000434,
.0025,0.0,
90.*
%
%ADD16MACRO16*%
%AMMACRO36*
4,1,36,.003,0.0,
.002954,.000521,
.002819,.001026,
.002598,.0015,
.002298,.001928,
.001928,.002298,
.0015,.002598,
.001026,.002819,
.000521,.002954,
0.0,.003,
-.000521,.002954,
-.001026,.002819,
-.0015,.002598,
-.001928,.002298,
-.002298,.001928,
-.002598,.0015,
-.002819,.001026,
-.002954,.000521,
-.003,0.0,
-.002954,-.000521,
-.002819,-.001026,
-.002598,-.0015,
-.002298,-.001928,
-.001928,-.002298,
-.0015,-.002598,
-.001026,-.002819,
-.000521,-.002954,
0.0,-.003,
.000521,-.002954,
.001026,-.002819,
.0015,-.002598,
.001928,-.002298,
.002298,-.001928,
.002598,-.0015,
.002819,-.001026,
.002954,-.000521,
.003,0.0,
90.*
%
%ADD36MACRO36*%
%AMMACRO12*
4,1,36,.0025,0.0,
.002462,.000434,
.002349,.000855,
.002165,.00125,
.001915,.001607,
.001607,.001915,
.00125,.002165,
.000855,.002349,
.000434,.002462,
0.0,.0025,
-.000434,.002462,
-.000855,.002349,
-.00125,.002165,
-.001607,.001915,
-.001915,.001607,
-.002165,.00125,
-.002349,.000855,
-.002462,.000434,
-.0025,0.0,
-.002462,-.000434,
-.002349,-.000855,
-.002165,-.00125,
-.001915,-.001607,
-.001607,-.001915,
-.00125,-.002165,
-.000855,-.002349,
-.000434,-.002462,
0.0,-.0025,
.000434,-.002462,
.000855,-.002349,
.00125,-.002165,
.001607,-.001915,
.001915,-.001607,
.002165,-.00125,
.002349,-.000855,
.002462,-.000434,
.0025,0.0,
0.0*
%
%ADD12MACRO12*%
%AMMACRO52*
4,1,36,-.0025,0.0,
-.002462,.000434,
-.002349,.000855,
-.002165,.00125,
-.001915,.001607,
-.001607,.001915,
-.00125,.002165,
-.000855,.002349,
-.000434,.002462,
0.0,.0025,
.000434,.002462,
.000855,.002349,
.00125,.002165,
.001607,.001915,
.001915,.001607,
.002165,.00125,
.002349,.000855,
.002462,.000434,
.0025,0.0,
.002462,-.000434,
.002349,-.000855,
.002165,-.00125,
.001915,-.001607,
.001607,-.001915,
.00125,-.002165,
.000855,-.002349,
.000434,-.002462,
0.0,-.0025,
-.000434,-.002462,
-.000855,-.002349,
-.00125,-.002165,
-.001607,-.001915,
-.001915,-.001607,
-.002165,-.00125,
-.002349,-.000855,
-.002462,-.000434,
-.0025,0.0,
0.0*
%
%ADD52MACRO52*%
%AMMACRO27*
4,1,36,.003,0.0,
.002954,.000521,
.002819,.001026,
.002598,.0015,
.002298,.001928,
.001928,.002298,
.0015,.002598,
.001026,.002819,
.000521,.002954,
0.0,.003,
-.000521,.002954,
-.001026,.002819,
-.0015,.002598,
-.001928,.002298,
-.002298,.001928,
-.002598,.0015,
-.002819,.001026,
-.002954,.000521,
-.003,0.0,
-.002954,-.000521,
-.002819,-.001026,
-.002598,-.0015,
-.002298,-.001928,
-.001928,-.002298,
-.0015,-.002598,
-.001026,-.002819,
-.000521,-.002954,
0.0,-.003,
.000521,-.002954,
.001026,-.002819,
.0015,-.002598,
.001928,-.002298,
.002298,-.001928,
.002598,-.0015,
.002819,-.001026,
.002954,-.000521,
.003,0.0,
0.0*
%
%ADD27MACRO27*%
%AMMACRO24*
4,1,36,-.003,0.0,
-.002954,.000521,
-.002819,.001026,
-.002598,.0015,
-.002298,.001928,
-.001928,.002298,
-.0015,.002598,
-.001026,.002819,
-.000521,.002954,
0.0,.003,
.000521,.002954,
.001026,.002819,
.0015,.002598,
.001928,.002298,
.002298,.001928,
.002598,.0015,
.002819,.001026,
.002954,.000521,
.003,0.0,
.002954,-.000521,
.002819,-.001026,
.002598,-.0015,
.002298,-.001928,
.001928,-.002298,
.0015,-.002598,
.001026,-.002819,
.000521,-.002954,
0.0,-.003,
-.000521,-.002954,
-.001026,-.002819,
-.0015,-.002598,
-.001928,-.002298,
-.002298,-.001928,
-.002598,-.0015,
-.002819,-.001026,
-.002954,-.000521,
-.003,0.0,
0.0*
%
%ADD24MACRO24*%
%AMMACRO41*
4,1,16,.02584,.01524,
.028094,.010521,
.029494,.005483,
.029998,.000278,
.029591,-.004935,
.028284,-.009999,
.026118,-.014758,
.02584,-.01524,
.03092,-.02032,
.033979,-.014642,
.036005,-.008519,
.036938,-.002138,
.036748,.004309,
.035441,.010625,
.033058,.016618,
.03092,.02032,
.02584,.01524,
180.*
4,1,16,.01524,-.02584,
.010521,-.028094,
.005483,-.029494,
.000278,-.029998,
-.004935,-.029591,
-.009999,-.028284,
-.014758,-.026118,
-.01524,-.02584,
-.02032,-.03092,
-.014642,-.033979,
-.008519,-.036005,
-.002138,-.036938,
.004309,-.036748,
.010625,-.035441,
.016618,-.033058,
.02032,-.03092,
.01524,-.02584,
180.*
4,1,16,-.02584,-.01524,
-.028094,-.010521,
-.029494,-.005483,
-.029998,-.000278,
-.029591,.004935,
-.028284,.009999,
-.026118,.014758,
-.02584,.01524,
-.03092,.02032,
-.033979,.014642,
-.036005,.008519,
-.036938,.002138,
-.036748,-.004309,
-.035441,-.010625,
-.033058,-.016618,
-.03092,-.02032,
-.02584,-.01524,
180.*
4,1,16,-.01524,.02584,
-.010521,.028094,
-.005483,.029494,
-.000278,.029998,
.004935,.029591,
.009999,.028284,
.014758,.026118,
.01524,.02584,
.02032,.03092,
.014642,.033979,
.008519,.036005,
.002138,.036938,
-.004309,.036748,
-.010625,.035441,
-.016618,.033058,
-.02032,.03092,
-.01524,.02584,
180.*
%
%ADD41MACRO41*%
%AMMACRO56*
4,1,15,.03682,.01914,
.039584,.012455,
.041146,.005393,
.041457,-.001834,
.040509,-.009005,
.03833,-.015903,
.03682,-.01914,
.04197,-.0243,
.045552,-.016643,
.04775,-.00848,
.048497,-.000059,
.047771,.008363,
.045593,.016531,
.042029,.024197,
.04197,.0243,
.03682,.01914,
270.*
4,1,15,.01914,-.03682,
.012455,-.039584,
.005393,-.041146,
-.001834,-.041457,
-.009005,-.040509,
-.015903,-.03833,
-.01914,-.03682,
-.0243,-.04197,
-.016643,-.045552,
-.00848,-.04775,
-.000059,-.048497,
.008363,-.047771,
.016531,-.045593,
.024197,-.042029,
.0243,-.04197,
.01914,-.03682,
270.*
4,1,15,-.03682,-.01914,
-.039584,-.012455,
-.041146,-.005393,
-.041457,.001834,
-.040509,.009005,
-.03833,.015903,
-.03682,.01914,
-.04197,.0243,
-.045552,.016643,
-.04775,.00848,
-.048497,.000059,
-.047771,-.008363,
-.045593,-.016531,
-.042029,-.024197,
-.04197,-.0243,
-.03682,-.01914,
270.*
4,1,15,-.01914,.03682,
-.012455,.039584,
-.005393,.041146,
.001834,.041457,
.009005,.040509,
.015903,.03833,
.01914,.03682,
.0243,.04197,
.016643,.045552,
.00848,.04775,
.000059,.048497,
-.008363,.047771,
-.016531,.045593,
-.024197,.042029,
-.0243,.04197,
-.01914,.03682,
270.*
%
%ADD56MACRO56*%
%AMMACRO57*
4,1,15,-.03682,.01914,
-.039584,.012455,
-.041146,.005393,
-.041457,-.001834,
-.040509,-.009005,
-.03833,-.015903,
-.03682,-.01914,
-.04197,-.0243,
-.045552,-.016643,
-.04775,-.00848,
-.048497,-.000059,
-.047771,.008363,
-.045593,.016531,
-.042029,.024197,
-.04197,.0243,
-.03682,.01914,
270.*
4,1,15,-.01914,-.03682,
-.012455,-.039584,
-.005393,-.041146,
.001834,-.041457,
.009005,-.040509,
.015903,-.03833,
.01914,-.03682,
.0243,-.04197,
.016643,-.045552,
.00848,-.04775,
.000059,-.048497,
-.008363,-.047771,
-.016531,-.045593,
-.024197,-.042029,
-.0243,-.04197,
-.01914,-.03682,
270.*
4,1,15,.03682,-.01914,
.039584,-.012455,
.041146,-.005393,
.041457,.001834,
.040509,.009005,
.03833,.015903,
.03682,.01914,
.04197,.0243,
.045552,.016643,
.04775,.00848,
.048497,.000059,
.047771,-.008363,
.045593,-.016531,
.042029,-.024197,
.04197,-.0243,
.03682,-.01914,
270.*
4,1,15,.01914,.03682,
.012455,.039584,
.005393,.041146,
-.001834,.041457,
-.009005,.040509,
-.015903,.03833,
-.01914,.03682,
-.0243,.04197,
-.016643,.045552,
-.00848,.04775,
-.000059,.048497,
.008363,.047771,
.016531,.045593,
.024197,.042029,
.0243,.04197,
.01914,.03682,
270.*
%
%ADD57MACRO57*%
%ADD64C,.006*%
%ADD76C,.03006*%
%ADD82C,.02404*%
%ADD80C,.07005*%
%ADD73C,.08404*%
%ADD66C,.07306*%
%ADD79C,.09208*%
%ADD74C,.07606*%
%ADD72C,.08408*%
%ADD78C,.07608*%
%ADD71C,.08409*%
%ADD70O,.1621X.2251*%
%ADD69O,.03604X.07004*%
%ADD67O,.03006X.06406*%
%ADD81C,.16206*%
%ADD68O,.03606X.07006*%
%ADD77C,.17406*%
%ADD65C,.16506*%
%ADD75C,.21786*%
G75*
%LPD*%
G75*
G36*
G01X-1490433Y-1677216D02*
X4496476D01*
Y3837819D01*
X-1490433D01*
Y-1677216D01*
G37*
%LPC*%
G75*
G36*
G01X630370Y-100983D02*
G02X624496Y-95109I0J5874D01*
G01Y-32983D01*
G03X614622Y-23109I-9874J0D01*
G01X68874D01*
G03X59000Y-32983I0J-9874D01*
G01Y-95109D01*
G02X53126Y-100983I-5874J0D01*
G01X7874D01*
G02X2000Y-95109I0J5874D01*
G01Y-15748D01*
G02X7874Y-9874I5874J0D01*
G01X31358D01*
G03X41232Y0I0J9874D01*
G01Y34843D01*
G02X47106Y40717I5874J0D01*
G01X54980D01*
G02X60854Y34843I0J-5874D01*
G01Y0D01*
G03X70728Y-9874I9874J0D01*
G01X133720D01*
G03X143594Y0I0J9874D01*
G01Y34843D01*
G02X149468Y40717I5874J0D01*
G01X157343D01*
G02X163217Y34843I0J-5874D01*
G01Y0D01*
G03X173091Y-9874I9874J0D01*
G01X236083D01*
G03X245957Y0I0J9874D01*
G01Y34843D01*
G02X251831Y40717I5874J0D01*
G01X259705D01*
G02X265579Y34843I0J-5874D01*
G01Y0D01*
G03X275453Y-9874I9874J0D01*
G01X338445D01*
G03X348319Y0I0J9874D01*
G01Y34843D01*
G02X354193Y40717I5874J0D01*
G01X362067D01*
G02X367941Y34843I0J-5874D01*
G01Y0D01*
G03X377815Y-9874I9874J0D01*
G01X488445D01*
G03X498319Y0I0J9874D01*
G01Y34843D01*
G02X504193Y40717I5874J0D01*
G01X512067D01*
G02X517941Y34843I0J-5874D01*
G01Y0D01*
G03X527815Y-9874I9874J0D01*
G01X590807D01*
G03X600681Y0I0J9874D01*
G01Y34843D01*
G02X606555Y40717I5874J0D01*
G01X614429D01*
G02X620303Y34843I0J-5874D01*
G01Y0D01*
G03X630177Y-9874I9874J0D01*
G01X693169D01*
G03X703043Y0I0J9874D01*
G01Y34843D01*
G02X708917Y40717I5874J0D01*
G01X716791D01*
G02X722665Y34843I0J-5874D01*
G01Y0D01*
G03X732539Y-9874I9874J0D01*
G01X795531D01*
G03X805405Y0I0J9874D01*
G01Y34843D01*
G02X811279Y40717I5874J0D01*
G01X819154D01*
G02X825028Y34843I0J-5874D01*
G01Y0D01*
G03X834902Y-9874I9874J0D01*
G01X945531D01*
G03X955405Y0I0J9874D01*
G01Y34843D01*
G02X961279Y40717I5874J0D01*
G01X969154D01*
G02X975028Y34843I0J-5874D01*
G01Y0D01*
G03X984902Y-9874I9874J0D01*
G01X1047894D01*
G03X1057768Y0I0J9874D01*
G01Y34843D01*
G02X1063642Y40717I5874J0D01*
G01X1071516D01*
G02X1077390Y34843I0J-5874D01*
G01Y0D01*
G03X1087264Y-9874I9874J0D01*
G01X1150256D01*
G03X1160130Y0I0J9874D01*
G01Y34843D01*
G02X1166004Y40717I5874J0D01*
G01X1173878D01*
G02X1179752Y34843I0J-5874D01*
G01Y0D01*
G03X1189626Y-9874I9874J0D01*
G01X1252618D01*
G03X1262492Y0I0J9874D01*
G01Y34843D01*
G02X1268366Y40717I5874J0D01*
G01X1276240D01*
G02X1282114Y34843I0J-5874D01*
G01Y0D01*
G03X1291988Y-9874I9874J0D01*
G01X1402618D01*
G03X1412492Y0I0J9874D01*
G01Y34843D01*
G02X1418366Y40717I5874J0D01*
G01X1426240D01*
G02X1432114Y34843I0J-5874D01*
G01Y0D01*
G03X1441988Y-9874I9874J0D01*
G01X1504980D01*
G03X1514854Y0I0J9874D01*
G01Y34843D01*
G02X1520728Y40717I5874J0D01*
G01X1528602D01*
G02X1534476Y34843I0J-5874D01*
G01Y0D01*
G03X1544350Y-9874I9874J0D01*
G01X1607343D01*
G03X1617217Y0I0J9874D01*
G01Y34843D01*
G02X1623091Y40717I5874J0D01*
G01X1630965D01*
G02X1636839Y34843I0J-5874D01*
G01Y0D01*
G03X1646713Y-9874I9874J0D01*
G01X1709705D01*
G03X1719579Y0I0J9874D01*
G01Y34843D01*
G02X1725453Y40717I5874J0D01*
G01X1733327D01*
G02X1739201Y34843I0J-5874D01*
G01Y0D01*
G03X1749075Y-9874I9874J0D01*
G01X1833071D01*
G02X1838945Y-15748I0J-5874D01*
G01Y-95109D01*
G02X1833071Y-100983I-5874J0D01*
G01X630370D01*
G37*
G36*
G01X1833071Y1645992D02*
G02X1838945Y1640118I0J-5874D01*
G01Y970425D01*
G02X1837225Y966273I-5874J1D01*
G01X1826876Y955925D01*
G03X1823984Y948943I6982J-6982D01*
G01Y344836D01*
G03X1826876Y337855I9873J0D01*
G01X1837225Y327506D01*
G02X1838945Y323354I-4153J-4153D01*
G01Y7874D01*
G02X1833071Y2000I-5874J0D01*
G01X1756949D01*
G02X1751075Y7874I0J5874D01*
G01Y46654D01*
G03X1745138Y52591I-5937J0D01*
G01X1713642D01*
G03X1707705Y46654I0J-5937D01*
G01Y7874D01*
G02X1701831Y2000I-5874J0D01*
G01X1654587D01*
G02X1648713Y7874I0J5874D01*
G01Y46654D01*
G03X1642776Y52591I-5937J0D01*
G01X1611280D01*
G03X1605343Y46654I0J-5937D01*
G01Y7874D01*
G02X1599469Y2000I-5874J0D01*
G01X1552224D01*
G02X1546350Y7874I0J5874D01*
G01Y46654D01*
G03X1540413Y52591I-5937J0D01*
G01X1508917D01*
G03X1502980Y46654I0J-5937D01*
G01Y7874D01*
G02X1497106Y2000I-5874J0D01*
G01X1449862D01*
G02X1443988Y7874I0J5874D01*
G01Y46654D01*
G03X1438051Y52591I-5937J0D01*
G01X1406555D01*
G03X1400618Y46654I0J-5937D01*
G01Y7874D01*
G02X1394744Y2000I-5874J0D01*
G01X1299862D01*
G02X1293988Y7874I0J5874D01*
G01Y46654D01*
G03X1288051Y52591I-5937J0D01*
G01X1256555D01*
G03X1250618Y46654I0J-5937D01*
G01Y7874D01*
G02X1244744Y2000I-5874J0D01*
G01X1197500D01*
G02X1191626Y7874I0J5874D01*
G01Y46654D01*
G03X1185689Y52591I-5937J0D01*
G01X1154193D01*
G03X1148256Y46654I0J-5937D01*
G01Y7874D01*
G02X1142382Y2000I-5874J0D01*
G01X1095138D01*
G02X1089264Y7874I0J5874D01*
G01Y46654D01*
G03X1083327Y52591I-5937J0D01*
G01X1051831D01*
G03X1045894Y46654I0J-5937D01*
G01Y7874D01*
G02X1040020Y2000I-5874J0D01*
G01X992776D01*
G02X986902Y7874I0J5874D01*
G01Y46654D01*
G03X980965Y52591I-5937J0D01*
G01X949468D01*
G03X943531Y46654I0J-5937D01*
G01Y7874D01*
G02X937657Y2000I-5874J0D01*
G01X842776D01*
G02X836902Y7874I0J5874D01*
G01Y46654D01*
G03X830965Y52591I-5937J0D01*
G01X799468D01*
G03X793531Y46654I0J-5937D01*
G01Y7874D01*
G02X787657Y2000I-5874J0D01*
G01X740413D01*
G02X734539Y7874I0J5874D01*
G01Y46654D01*
G03X728602Y52591I-5937J0D01*
G01X697106D01*
G03X691169Y46654I0J-5937D01*
G01Y7874D01*
G02X685295Y2000I-5874J0D01*
G01X638051D01*
G02X632177Y7874I0J5874D01*
G01Y46654D01*
G03X626240Y52591I-5937J0D01*
G01X594744D01*
G03X588807Y46654I0J-5937D01*
G01Y7874D01*
G02X582933Y2000I-5874J0D01*
G01X535689D01*
G02X529815Y7874I0J5874D01*
G01Y46654D01*
G03X523878Y52591I-5937J0D01*
G01X492382D01*
G03X486445Y46654I0J-5937D01*
G01Y7874D01*
G02X480571Y2000I-5874J0D01*
G01X385689D01*
G02X379815Y7874I0J5874D01*
G01Y46654D01*
G03X373878Y52591I-5937J0D01*
G01X342382D01*
G03X336445Y46654I0J-5937D01*
G01Y7874D01*
G02X330571Y2000I-5874J0D01*
G01X283327D01*
G02X277453Y7874I0J5874D01*
G01Y46654D01*
G03X271516Y52591I-5937J0D01*
G01X240020D01*
G03X234083Y46654I0J-5937D01*
G01Y7874D01*
G02X228209Y2000I-5874J0D01*
G01X180965D01*
G02X175091Y7874I0J5874D01*
G01Y46654D01*
G03X169154Y52591I-5937J0D01*
G01X137657D01*
G03X131720Y46654I0J-5937D01*
G01Y7874D01*
G02X125846Y2000I-5874J0D01*
G01X78602D01*
G02X72728Y7874I0J5874D01*
G01Y46654D01*
G03X66791Y52591I-5937J0D01*
G01X35295D01*
G03X29358Y46654I0J-5937D01*
G01Y7874D01*
G02X23484Y2000I-5874J0D01*
G01X7874D01*
G02X2000Y7874I0J5874D01*
G01Y323354D01*
G02X3720Y327506I5873J-1D01*
G01X14068Y337855D01*
G03X16961Y344836I-6980J6983D01*
G01Y948943D01*
G03X14068Y955925I-9875J-1D01*
G01X3720Y966273D01*
G02X2000Y970425I4154J4153D01*
G01Y1640118D01*
G02X7874Y1645992I5874J0D01*
G01X789298D01*
G02X793649Y1644063I-1J-5873D01*
G03X800966Y1640819I7317J6631D01*
G01X1070058D01*
G03X1077374Y1644063I-1J9873D01*
G02X1081725Y1645992I4352J-3945D01*
G01X1833071D01*
G37*
G36*
G01Y1818880D02*
G02X1838945Y1813006I0J-5874D01*
G01Y1663740D01*
G02X1833071Y1657866I-5874J0D01*
G01X1763543D01*
G02X1757669Y1663740I0J5874D01*
G01Y1689331D01*
G03X1747795Y1699205I-9874J0D01*
G01X1461575D01*
G03X1451701Y1689331I0J-9874D01*
G01Y1663740D01*
G02X1445827Y1657866I-5874J0D01*
G01X1417087D01*
G02X1411213Y1663740I0J5874D01*
G01Y1689331D01*
G03X1401339Y1699205I-9874J0D01*
G01X1115118D01*
G03X1105244Y1689331I0J-9874D01*
G01Y1663740D01*
G02X1099370Y1657866I-5874J0D01*
G01X1090079D01*
G02X1084205Y1663740I0J5874D01*
G01Y1695110D01*
G03X1074331Y1704984I-9874J0D01*
G01X796693D01*
G03X786819Y1695110I0J-9874D01*
G01Y1663740D01*
G02X780945Y1657866I-5874J0D01*
G01X741575D01*
G02X735701Y1663740I0J5874D01*
G01Y1689331D01*
G03X725827Y1699205I-9874J0D01*
G01X439607D01*
G03X429733Y1689331I0J-9874D01*
G01Y1663740D01*
G02X423859Y1657866I-5874J0D01*
G01X395118D01*
G02X389244Y1663740I0J5874D01*
G01Y1689331D01*
G03X379370Y1699205I-9874J0D01*
G01X93150D01*
G03X83276Y1689331I0J-9874D01*
G01Y1663740D01*
G02X77402Y1657866I-5874J0D01*
G01X7874D01*
G02X2000Y1663740I0J5874D01*
G01Y1813006D01*
G02X7874Y1818880I5874J0D01*
G01X1833071D01*
G37*
%LPD*%
G75*
G36*
G01X607977Y1552080D02*
X555513D01*
G02X555210Y1552383I0J303D01*
G01Y1643194D01*
G02X555513Y1643498I303J1D01*
G01X608266D01*
G02X608570Y1643194I0J-304D01*
G01Y1552672D01*
X607977Y1552080D01*
G37*
G36*
G01X208954Y1643834D02*
G02X209256Y1644136I302J0D01*
G01X261611D01*
G02X261912Y1643834I-1J-302D01*
G01Y1642872D01*
Y1552470D01*
X261722Y1552280D01*
X208952D01*
Y1642872D01*
X208954D01*
Y1643834D01*
G37*
G36*
G01X1232576D02*
G02X1232878Y1644136I302J0D01*
G01X1285233D01*
G02X1285534Y1643834I-1J-302D01*
G01Y1643226D01*
Y1552461D01*
X1285353Y1552280D01*
X1232574D01*
Y1643226D01*
X1232576D01*
Y1643834D01*
G37*
G36*
G01X1579032D02*
G02X1579335Y1644136I303J-1D01*
G01X1631688D01*
G02X1631990Y1643834I0J-302D01*
G01Y1643174D01*
X1631992D01*
Y1552573D01*
X1631698Y1552280D01*
X1579032D01*
Y1643174D01*
Y1643834D01*
G37*
G36*
G01X177763Y1512216D02*
X180583D01*
G02X180786Y1512014I1J-202D01*
G01Y1511392D01*
G03X180836Y1511260I200J0D01*
G02Y1508348I-1664J-1456D01*
G03X180786Y1508216I150J-132D01*
G01Y1506273D01*
G03X180836Y1506141I200J0D01*
G02Y1503229I-1664J-1456D01*
G03X180786Y1503097I150J-132D01*
G01Y1502476D01*
G02X180583Y1502274I-203J1D01*
G01X177763D01*
G02X177560Y1502476I-1J202D01*
G01Y1503097D01*
G03X177510Y1503229I-200J0D01*
G02Y1506141I1664J1456D01*
G03X177560Y1506273I-150J132D01*
G01Y1508216D01*
G03X177510Y1508348I-200J0D01*
G02Y1511260I1664J1456D01*
G03X177560Y1511392I-150J132D01*
G01Y1512014D01*
G02X177763Y1512216I203J-1D01*
G37*
G36*
G01X350991D02*
X353811D01*
G02X354014Y1512014I1J-202D01*
G01Y1511392D01*
G03X354064Y1511260I200J0D01*
G02Y1508348I-1664J-1456D01*
G03X354014Y1508216I150J-132D01*
G01Y1506273D01*
G03X354064Y1506141I200J0D01*
G02Y1503229I-1664J-1456D01*
G03X354014Y1503097I150J-132D01*
G01Y1502476D01*
G02X353811Y1502274I-203J1D01*
G01X350991D01*
G02X350788Y1502476I-1J202D01*
G01Y1503097D01*
G03X350738Y1503229I-200J0D01*
G02Y1506141I1664J1456D01*
G03X350788Y1506273I-150J132D01*
G01Y1508216D01*
G03X350738Y1508348I-200J0D01*
G02Y1511260I1664J1456D01*
G03X350788Y1511392I-150J132D01*
G01Y1512014D01*
G02X350991Y1512216I203J-1D01*
G37*
G36*
G01X186425Y1516546D02*
X189245D01*
G02X189448Y1516344I1J-202D01*
G01Y1515722D01*
G03X189498Y1515590I200J0D01*
G02Y1512678I-1664J-1456D01*
G03X189448Y1512546I150J-132D01*
G01Y1510604D01*
G03X189498Y1510472I200J0D01*
G02Y1507560I-1664J-1456D01*
G03X189448Y1507428I150J-132D01*
G01Y1506806D01*
G02X189245Y1506604I-203J1D01*
G01X186425D01*
G02X186222Y1506806I-1J202D01*
G01Y1507428D01*
G03X186172Y1507560I-200J0D01*
G02Y1510472I1664J1456D01*
G03X186222Y1510604I-150J132D01*
G01Y1512546D01*
G03X186172Y1512678I-200J0D01*
G02Y1515590I1664J1456D01*
G03X186222Y1515722I-150J132D01*
G01Y1516344D01*
G02X186425Y1516546I203J-1D01*
G37*
G36*
G01X359653D02*
X362473D01*
G02X362676Y1516344I1J-202D01*
G01Y1515722D01*
G03X362726Y1515590I200J0D01*
G02Y1512678I-1664J-1456D01*
G03X362676Y1512546I150J-132D01*
G01Y1510604D01*
G03X362726Y1510472I200J0D01*
G02Y1507560I-1664J-1456D01*
G03X362676Y1507428I150J-132D01*
G01Y1506806D01*
G02X362473Y1506604I-203J1D01*
G01X359653D01*
G02X359450Y1506806I-1J202D01*
G01Y1507428D01*
G03X359400Y1507560I-200J0D01*
G02Y1510472I1664J1456D01*
G03X359450Y1510604I-150J132D01*
G01Y1512546D01*
G03X359400Y1512678I-200J0D01*
G02Y1515590I1664J1456D01*
G03X359450Y1515722I-150J132D01*
G01Y1516344D01*
G02X359653Y1516546I203J-1D01*
G37*
G36*
G01X177763Y1568516D02*
X180583D01*
G02X180786Y1568313I0J-203D01*
G01Y1567691D01*
G03X180836Y1567559I200J0D01*
G02Y1564647I-1664J-1456D01*
G03X180786Y1564515I150J-132D01*
G01Y1562573D01*
G03X180836Y1562441I200J0D01*
G02Y1559529I-1664J-1456D01*
G03X180786Y1559397I150J-132D01*
G01Y1558775D01*
G02X180583Y1558572I-203J0D01*
G01X177763D01*
G02X177560Y1558775I0J203D01*
G01Y1559397D01*
G03X177510Y1559529I-200J0D01*
G02Y1562441I1664J1456D01*
G03X177560Y1562573I-150J132D01*
G01Y1564515D01*
G03X177510Y1564647I-200J0D01*
G02Y1567559I1664J1456D01*
G03X177560Y1567691I-150J132D01*
G01Y1568313D01*
G02X177763Y1568516I203J0D01*
G37*
G36*
G01X350991D02*
X353811D01*
G02X354014Y1568313I0J-203D01*
G01Y1567691D01*
G03X354064Y1567559I200J0D01*
G02Y1564647I-1664J-1456D01*
G03X354014Y1564515I150J-132D01*
G01Y1562573D01*
G03X354064Y1562441I200J0D01*
G02Y1559529I-1664J-1456D01*
G03X354014Y1559397I150J-132D01*
G01Y1558775D01*
G02X353811Y1558572I-203J0D01*
G01X350991D01*
G02X350788Y1558775I0J203D01*
G01Y1559397D01*
G03X350738Y1559529I-200J0D01*
G02Y1562441I1664J1456D01*
G03X350788Y1562573I-150J132D01*
G01Y1564515D01*
G03X350738Y1564647I-200J0D01*
G02Y1567559I1664J1456D01*
G03X350788Y1567691I-150J132D01*
G01Y1568313D01*
G02X350991Y1568516I203J0D01*
G37*
G36*
G01X186425Y1572846D02*
X189245D01*
G02X189448Y1572644I1J-202D01*
G01Y1572022D01*
G03X189498Y1571890I200J0D01*
G02Y1568978I-1664J-1456D01*
G03X189448Y1568846I150J-132D01*
G01Y1566903D01*
G03X189498Y1566771I200J0D01*
G02Y1563859I-1664J-1456D01*
G03X189448Y1563727I150J-132D01*
G01Y1563106D01*
G02X189245Y1562904I-203J1D01*
G01X186425D01*
G02X186222Y1563106I-1J202D01*
G01Y1563727D01*
G03X186172Y1563859I-200J0D01*
G02Y1566771I1664J1456D01*
G03X186222Y1566903I-150J132D01*
G01Y1568846D01*
G03X186172Y1568978I-200J0D01*
G02Y1571890I1664J1456D01*
G03X186222Y1572022I-150J132D01*
G01Y1572644D01*
G02X186425Y1572846I203J-1D01*
G37*
G36*
G01X359653D02*
X362473D01*
G02X362676Y1572644I1J-202D01*
G01Y1572022D01*
G03X362726Y1571890I200J0D01*
G02Y1568978I-1664J-1456D01*
G03X362676Y1568846I150J-132D01*
G01Y1566903D01*
G03X362726Y1566771I200J0D01*
G02Y1563859I-1664J-1456D01*
G03X362676Y1563727I150J-132D01*
G01Y1563106D01*
G02X362473Y1562904I-203J1D01*
G01X359653D01*
G02X359450Y1563106I-1J202D01*
G01Y1563727D01*
G03X359400Y1563859I-200J0D01*
G02Y1566771I1664J1456D01*
G03X359450Y1566903I-150J132D01*
G01Y1568846D01*
G03X359400Y1568978I-200J0D01*
G02Y1571890I1664J1456D01*
G03X359450Y1572022I-150J132D01*
G01Y1572644D01*
G02X359653Y1572846I203J-1D01*
G37*
G36*
G01X177763Y1583870D02*
X180583D01*
G02X180786Y1583667I0J-203D01*
G01Y1583045D01*
G03X180836Y1582913I200J0D01*
G02Y1580001I-1664J-1456D01*
G03X180786Y1579869I150J-132D01*
G01Y1577927D01*
G03X180836Y1577795I200J0D01*
G02Y1574883I-1664J-1456D01*
G03X180786Y1574751I150J-132D01*
G01Y1574129D01*
G02X180583Y1573926I-203J0D01*
G01X177763D01*
G02X177560Y1574129I0J203D01*
G01Y1574751D01*
G03X177510Y1574883I-200J0D01*
G02Y1577795I1664J1456D01*
G03X177560Y1577927I-150J132D01*
G01Y1579869D01*
G03X177510Y1580001I-200J0D01*
G02Y1582913I1664J1456D01*
G03X177560Y1583045I-150J132D01*
G01Y1583667D01*
G02X177763Y1583870I203J0D01*
G37*
G36*
G01X404759Y1350874D02*
X408159D01*
G02Y1347270I0J-1802D01*
G01X404759D01*
G02Y1350874I0J1802D01*
G37*
G36*
G01X402489Y1419078D02*
X405889D01*
G02Y1415472I0J-1803D01*
G01X402489D01*
G02Y1419078I0J1803D01*
G37*
G36*
G01X1443660Y1308896D02*
X1440260D01*
G02Y1312500I0J1802D01*
G01X1443660D01*
G02Y1308896I0J-1802D01*
G37*
G36*
G01X970197Y665850D02*
X966797D01*
G02Y669456I0J1803D01*
G01X970197D01*
G02Y665850I0J-1803D01*
G37*
G36*
G01X501495Y772260D02*
X504895D01*
G02Y768654I0J-1803D01*
G01X501495D01*
G02Y772260I0J1803D01*
G37*
G36*
G01X909508Y623418D02*
X912908D01*
G02Y619814I0J-1802D01*
G01X909508D01*
G02Y623418I0J1802D01*
G37*
G36*
G01X900676Y623338D02*
X904076D01*
G02Y619734I0J-1802D01*
G01X900676D01*
G02Y623338I0J1802D01*
G37*
G36*
G01X526264Y665858D02*
X529664D01*
G02Y662254I0J-1802D01*
G01X526264D01*
G02Y665858I0J1802D01*
G37*
G36*
G01X534264Y663358D02*
X537664D01*
G02Y659754I0J-1802D01*
G01X534264D01*
G02Y663358I0J1802D01*
G37*
G36*
G01X538985Y734790D02*
X535585D01*
G02Y738396I0J1803D01*
G01X538985D01*
G02Y734790I0J-1803D01*
G37*
G36*
G01X530985Y739790D02*
X527585D01*
G02Y743396I0J1803D01*
G01X530985D01*
G02Y739790I0J-1803D01*
G37*
G36*
G01X517731Y742874D02*
X521131D01*
G02Y739268I0J-1803D01*
G01X517731D01*
G02Y742874I0J1803D01*
G37*
G36*
G01X511724Y739232D02*
X508324D01*
G02Y742838I0J1803D01*
G01X511724D01*
G02Y739232I0J-1803D01*
G37*
G36*
G01X415777Y306272D02*
X419177D01*
G02Y302668I0J-1802D01*
G01X415777D01*
G02Y306272I0J1802D01*
G37*
G36*
G01X423651Y309272D02*
X427051D01*
G02Y305668I0J-1802D01*
G01X423651D01*
G02Y309272I0J1802D01*
G37*
G36*
G01X431525Y306272D02*
X434925D01*
G02Y302668I0J-1802D01*
G01X431525D01*
G02Y306272I0J1802D01*
G37*
G36*
G01X434924Y368506D02*
X431524D01*
G02Y372112I0J1803D01*
G01X434924D01*
G02Y368506I0J-1803D01*
G37*
G36*
G01X933247Y1585829D02*
X940733Y1578343D01*
G03X940735Y1578341I142J140D01*
G03X940910Y1578270I174J178D01*
G01X956757D01*
G02X956899Y1578211I0J-200D01*
G01X960831Y1574278D01*
G02X960890Y1574136I-141J-142D01*
G01Y1543680D01*
G03X960963Y1543504I249J0D01*
G01X965002Y1539465D01*
G03X965004Y1539463I142J140D01*
G03X965179Y1539392I174J178D01*
G01X1020321D01*
G02X1020463Y1539333I0J-200D01*
G01X1032517Y1527279D01*
G02X1032576Y1527137I-141J-142D01*
G01Y1492489D01*
G02X1032517Y1492347I-200J0D01*
G01X1031783Y1491613D01*
G02X1031641Y1491554I-142J141D01*
G01X946768D01*
G02X946626Y1491613I0J200D01*
G01X944169Y1494071D01*
G03X944167Y1494073I-142J-140D01*
G03X943992Y1494144I-174J-178D01*
G01X933579D01*
G03X933404Y1494073I-1J-249D01*
G03X933402Y1494071I140J-142D01*
G01X917849Y1478518D01*
G03X917776Y1478342I176J-176D01*
G01Y1464605D01*
G02X917717Y1464463I-200J0D01*
G01X914897Y1461643D01*
G03X914895Y1461641I140J-142D01*
G03X914824Y1461466I178J-174D01*
G01Y1460513D01*
G02X914765Y1460371I-200J0D01*
G01X914235Y1459842D01*
G03X914162Y1459666I176J-176D01*
G01Y1446033D01*
G02X914104Y1445891I-200J-1D01*
G01X913370Y1445157D01*
G02X913228Y1445098I-142J141D01*
G01X900144D01*
G02X900002Y1445157I0J200D01*
G01X899268Y1445891D01*
G02X899210Y1446033I142J141D01*
G01Y1459640D01*
G03X899137Y1459816I-249J0D01*
G01X898531Y1460422D01*
G02X898472Y1460564I141J142D01*
G01Y1462024D01*
G03X898399Y1462200I-249J0D01*
G01X893401Y1467197D01*
G02X893342Y1467339I141J142D01*
G01Y1473096D01*
G03X893271Y1473271I-249J1D01*
G03X893269Y1473273I-142J-140D01*
G01X888245Y1478297D01*
G03X888069Y1478370I-176J-176D01*
G01X880504D01*
G03X880328Y1478297I0J-249D01*
G01X872973Y1470942D01*
G03X872900Y1470766I176J-176D01*
G01Y1460576D01*
G02X872841Y1460434I-200J0D01*
G01X872211Y1459804D01*
G03X872209Y1459802I140J-142D01*
G03X872138Y1459627I178J-174D01*
G01Y1446008D01*
G02X872079Y1445866I-200J0D01*
G01X871383Y1445170D01*
G02X871241Y1445112I-141J142D01*
G01X858287D01*
G02X858145Y1445171I0J200D01*
G01X857137Y1446178D01*
G02X857078Y1446320I141J142D01*
G01Y1459524D01*
G03X857007Y1459699I-249J1D01*
G03X857005Y1459701I-142J-140D01*
G01X852953Y1463753D01*
G03X852951Y1463755I-142J-140D01*
G03X852776Y1463826I-174J-178D01*
G01X828441D01*
G03X828266Y1463755I-1J-249D01*
G03X828264Y1463753I140J-142D01*
G01X827747Y1463236D01*
G03X827674Y1463060I176J-176D01*
G01Y1461432D01*
G02X827615Y1461290I-200J0D01*
G01X826986Y1460661D01*
G02X826844Y1460602I-142J141D01*
G01X825036D01*
G03X824860Y1460529I0J-249D01*
G01X821948Y1457617D01*
G02X821806Y1457558I-142J141D01*
G01X820451D01*
G03X820275Y1457485I0J-249D01*
G01X820069Y1457279D01*
G03X820067Y1457277I140J-142D01*
G03X819996Y1457102I178J-174D01*
G01Y1446047D01*
G02X819937Y1445905I-200J0D01*
G01X819241Y1445209D01*
G02X819099Y1445150I-142J141D01*
G01X805978D01*
G02X805836Y1445209I0J200D01*
G01X805061Y1445984D01*
G02X805002Y1446126I141J142D01*
G01Y1460243D01*
G02X805061Y1460385I200J0D01*
G01X805487Y1460810D01*
G03X805560Y1460986I-176J176D01*
G01Y1474724D01*
G02X805619Y1474866I200J0D01*
G01X805875Y1475122D01*
G03X805877Y1475124I-140J142D01*
G03X805948Y1475299I-178J174D01*
G01Y1524130D01*
G02X806007Y1524272I200J0D01*
G01X816121Y1534385D01*
G03X816123Y1534387I-140J142D01*
G03X816194Y1534562I-178J174D01*
G01Y1621268D01*
G02X816253Y1621410I200J0D01*
G01X822113Y1627269D01*
G02X822255Y1627328I142J-141D01*
G01X927980D01*
G02X928122Y1627269I0J-200D01*
G01X933115Y1622276D01*
G02X933174Y1622134I-141J-142D01*
G01Y1586005D01*
G03X933247Y1585829I249J0D01*
G37*
G36*
G01X1047661Y1451746D02*
X1045748Y1449833D01*
G02X1045606Y1449774I-142J141D01*
G01X955889D01*
G02X955747Y1449833I0J200D01*
G01X954749Y1450831D01*
G02X954690Y1450973I141J142D01*
G01Y1485726D01*
G02X954749Y1485868I200J0D01*
G01X956753Y1487871D01*
G02X956895Y1487930I142J-141D01*
G01X1046147D01*
G02X1046289Y1487871I0J-200D01*
G01X1047661Y1486500D01*
G02X1047720Y1486358I-141J-142D01*
G01Y1451888D01*
G02X1047661Y1451746I-200J0D01*
G37*
G36*
G01X952704Y1482405D02*
X953818Y1481291D01*
G03X953834Y1481276I178J174D01*
G01X954122Y1481036D01*
G02X954194Y1480882I-128J-154D01*
G01Y1451027D01*
G02X954135Y1450885I-200J0D01*
G01X953083Y1449833D01*
G02X952941Y1449774I-142J141D01*
G01X930177D01*
G02X930035Y1449833I0J200D01*
G01X928619Y1451249D01*
G02X928560Y1451391I141J142D01*
G01Y1481306D01*
G02X928619Y1481448I200J0D01*
G01X930003Y1482831D01*
G02X930145Y1482890I142J-141D01*
G01X952269D01*
G02X952435Y1482801I0J-200D01*
G01X952673Y1482443D01*
G03X952703Y1482406I207J137D01*
G01X952704Y1482405D01*
G37*
G36*
G01X26772Y1559218D02*
X20472D01*
G02Y1575428I0J8105D01*
G01X26772D01*
G02Y1559218I0J-8105D01*
G37*
G36*
G01X216125Y1441832D02*
X219525D01*
G02Y1438226I0J-1803D01*
G01X216125D01*
G02Y1441832I0J1803D01*
G37*
G36*
G01X413753Y1518690D02*
X417153D01*
G02Y1515084I0J-1803D01*
G01X413753D01*
G02Y1518690I0J1803D01*
G37*
G36*
G01X417334Y1475298D02*
X413934D01*
G02Y1478902I0J1802D01*
G01X417334D01*
G02Y1475298I0J-1802D01*
G37*
G36*
G01X919628Y334530D02*
X916228D01*
G02Y338136I0J1803D01*
G01X919628D01*
G02Y334530I0J-1803D01*
G37*
G36*
G01X905899Y304150D02*
X909299D01*
G02Y300544I0J-1803D01*
G01X905899D01*
G02Y304150I0J1803D01*
G37*
G36*
G01X1033891Y298096D02*
X1037291D01*
G02Y294490I0J-1803D01*
G01X1033891D01*
G02Y298096I0J1803D01*
G37*
G36*
G01X1318363Y312364D02*
X1321763D01*
G02Y308760I0J-1802D01*
G01X1318363D01*
G02Y312364I0J1802D01*
G37*
G36*
G01X1337508Y371598D02*
X1334108D01*
G02Y375204I0J1803D01*
G01X1337508D01*
G02Y371598I0J-1803D01*
G37*
G36*
G01X1326237Y309364D02*
X1329637D01*
G02Y305760I0J-1802D01*
G01X1326237D01*
G02Y309364I0J1802D01*
G37*
G36*
G01X1334111Y312364D02*
X1337511D01*
G02Y308760I0J-1802D01*
G01X1334111D01*
G02Y312364I0J1802D01*
G37*
G36*
G01X1518207Y1176748D02*
X1514467D01*
G02Y1179354I0J1303D01*
G01X1518207D01*
G02Y1176748I0J-1303D01*
G37*
G36*
G01Y1169268D02*
X1514467D01*
G02Y1171872I0J1302D01*
G01X1518207D01*
G02Y1169268I0J-1302D01*
G37*
G36*
G01X1513926Y907148D02*
X1510526D01*
G02Y910754I0J1803D01*
G01X1513926D01*
G02Y907148I0J-1803D01*
G37*
G36*
G01X1531299Y1174878D02*
X1527559D01*
G02Y1177482I0J1302D01*
G01X1531299D01*
G02Y1174878I0J-1302D01*
G37*
G36*
G01X146947Y1176748D02*
X143207D01*
G02Y1179354I0J1303D01*
G01X146947D01*
G02Y1176748I0J-1303D01*
G37*
G36*
G01Y1169268D02*
X143207D01*
G02Y1171872I0J1302D01*
G01X146947D01*
G02Y1169268I0J-1302D01*
G37*
G36*
G01X160039Y1174878D02*
X156299D01*
G02Y1177482I0J1302D01*
G01X160039D01*
G02Y1174878I0J-1302D01*
G37*
G36*
G01X604034Y1176748D02*
X600294D01*
G02Y1179354I0J1303D01*
G01X604034D01*
G02Y1176748I0J-1303D01*
G37*
G36*
G01Y1169268D02*
X600294D01*
G02Y1171872I0J1302D01*
G01X604034D01*
G02Y1169268I0J-1302D01*
G37*
G36*
G01X605733Y942940D02*
X609133D01*
G02Y939336I0J-1802D01*
G01X605733D01*
G02Y942940I0J1802D01*
G37*
G36*
G01X615256Y1176748D02*
X611516D01*
G02Y1179354I0J1303D01*
G01X615256D01*
G02Y1176748I0J-1303D01*
G37*
G36*
G01X1061120D02*
X1057380D01*
G02Y1179354I0J1303D01*
G01X1061120D01*
G02Y1176748I0J-1303D01*
G37*
G36*
G01Y1169268D02*
X1057380D01*
G02Y1171872I0J1302D01*
G01X1061120D01*
G02Y1169268I0J-1302D01*
G37*
G36*
G01X1769063Y921922D02*
X1765663D01*
G02Y925526I0J1802D01*
G01X1769063D01*
G02Y921922I0J-1802D01*
G37*
G36*
G01X1072342Y1176748D02*
X1068602D01*
G02Y1179354I0J1303D01*
G01X1072342D01*
G02Y1176748I0J-1303D01*
G37*
G36*
G01X647411Y379065D02*
X647412D01*
G02Y370659I0J-4203D01*
G01X647411D01*
G02Y379065I0J4203D01*
G37*
G36*
G01X111494Y1456412D02*
G02X111292Y1456210I-202J0D01*
G01X108472D01*
G02X108270Y1456413I1J203D01*
G01Y1457032D01*
G03X108220Y1457164I-200J0D01*
G02Y1460080I1661J1458D01*
G03X108270Y1460212I-150J132D01*
G01Y1462151D01*
G03X108220Y1462283I-200J0D01*
G02Y1465199I1661J1458D01*
G03X108270Y1465331I-150J132D01*
G01Y1465952D01*
G02X108472Y1466154I202J0D01*
G01X111292D01*
G02X111494Y1465951I-1J-203D01*
G01Y1465331D01*
G03X111544Y1465199I200J0D01*
G02Y1462283I-1661J-1458D01*
G03X111494Y1462151I150J-132D01*
G01Y1460212D01*
G03X111544Y1460080I200J0D01*
G02Y1457164I-1661J-1458D01*
G03X111494Y1457032I150J-132D01*
G01Y1456412D01*
G37*
G36*
G01X319368D02*
G02X319166Y1456210I-202J0D01*
G01X316346D01*
G02X316144Y1456413I1J203D01*
G01Y1457032D01*
G03X316094Y1457164I-200J0D01*
G02Y1460080I1661J1458D01*
G03X316144Y1460212I-150J132D01*
G01Y1462151D01*
G03X316094Y1462283I-200J0D01*
G02Y1465199I1661J1458D01*
G03X316144Y1465331I-150J132D01*
G01Y1465952D01*
G02X316346Y1466154I202J0D01*
G01X319166D01*
G02X319368Y1465951I-1J-203D01*
G01Y1465331D01*
G03X319418Y1465199I200J0D01*
G02Y1462283I-1661J-1458D01*
G03X319368Y1462151I150J-132D01*
G01Y1460212D01*
G03X319418Y1460080I200J0D01*
G02Y1457164I-1661J-1458D01*
G03X319368Y1457032I150J-132D01*
G01Y1456412D01*
G37*
G36*
G01X336690D02*
G02X336488Y1456210I-202J0D01*
G01X333668D01*
G02X333466Y1456413I1J203D01*
G01Y1457032D01*
G03X333416Y1457164I-200J0D01*
G02Y1460080I1661J1458D01*
G03X333466Y1460212I-150J132D01*
G01Y1462151D01*
G03X333416Y1462283I-200J0D01*
G02Y1465199I1661J1458D01*
G03X333466Y1465331I-150J132D01*
G01Y1465952D01*
G02X333668Y1466154I202J0D01*
G01X336488D01*
G02X336690Y1465951I-1J-203D01*
G01Y1465331D01*
G03X336740Y1465199I200J0D01*
G02Y1462283I-1661J-1458D01*
G03X336690Y1462151I150J-132D01*
G01Y1460212D01*
G03X336740Y1460080I200J0D01*
G02Y1457164I-1661J-1458D01*
G03X336690Y1457032I150J-132D01*
G01Y1456412D01*
G37*
G36*
G01X628157Y1466154D02*
X630977D01*
G02X631180Y1465951I0J-203D01*
G01Y1465329D01*
G03X631230Y1465197I200J0D01*
G02Y1462285I-1664J-1456D01*
G03X631180Y1462153I150J-132D01*
G01Y1460210D01*
G03X631230Y1460078I200J0D01*
G02Y1457166I-1664J-1456D01*
G03X631180Y1457034I150J-132D01*
G01Y1456413D01*
G02X630977Y1456210I-203J0D01*
G01X628157D01*
G02X627954Y1456413I0J203D01*
G01Y1457034D01*
G03X627904Y1457166I-200J0D01*
G02Y1460078I1664J1456D01*
G03X627954Y1460210I-150J132D01*
G01Y1462153D01*
G03X627904Y1462285I-200J0D01*
G02Y1465197I1664J1456D01*
G03X627954Y1465329I-150J132D01*
G01Y1465951D01*
G02X628157Y1466154I203J0D01*
G37*
G36*
G01X1133462Y1456412D02*
G02X1133260Y1456210I-202J0D01*
G01X1130440D01*
G02X1130238Y1456413I1J203D01*
G01Y1457032D01*
G03X1130188Y1457164I-200J0D01*
G02Y1460080I1661J1458D01*
G03X1130238Y1460212I-150J132D01*
G01Y1462151D01*
G03X1130188Y1462283I-200J0D01*
G02Y1465199I1661J1458D01*
G03X1130238Y1465331I-150J132D01*
G01Y1465952D01*
G02X1130440Y1466154I202J0D01*
G01X1133260D01*
G02X1133462Y1465951I-1J-203D01*
G01Y1465331D01*
G03X1133512Y1465199I200J0D01*
G02Y1462283I-1661J-1458D01*
G03X1133462Y1462151I150J-132D01*
G01Y1460212D01*
G03X1133512Y1460080I200J0D01*
G02Y1457164I-1661J-1458D01*
G03X1133462Y1457032I150J-132D01*
G01Y1456412D01*
G37*
G36*
G01X1147763Y1466154D02*
X1150583D01*
G02X1150786Y1465951I0J-203D01*
G01Y1465329D01*
G03X1150836Y1465197I200J0D01*
G02Y1462285I-1664J-1456D01*
G03X1150786Y1462153I150J-132D01*
G01Y1460210D01*
G03X1150836Y1460078I200J0D01*
G02Y1457166I-1664J-1456D01*
G03X1150786Y1457034I150J-132D01*
G01Y1456413D01*
G02X1150583Y1456210I-203J0D01*
G01X1147763D01*
G02X1147560Y1456413I0J203D01*
G01Y1457034D01*
G03X1147510Y1457166I-200J0D01*
G02Y1460078I1664J1456D01*
G03X1147560Y1460210I-150J132D01*
G01Y1462153D01*
G03X1147510Y1462285I-200J0D01*
G02Y1465197I1664J1456D01*
G03X1147560Y1465329I-150J132D01*
G01Y1465951D01*
G02X1147763Y1466154I203J0D01*
G37*
G36*
G01X1650125D02*
X1652945D01*
G02X1653148Y1465951I0J-203D01*
G01Y1465329D01*
G03X1653198Y1465197I200J0D01*
G02Y1462285I-1664J-1456D01*
G03X1653148Y1462153I150J-132D01*
G01Y1460210D01*
G03X1653198Y1460078I200J0D01*
G02Y1457166I-1664J-1456D01*
G03X1653148Y1457034I150J-132D01*
G01Y1456413D01*
G02X1652945Y1456210I-203J0D01*
G01X1650125D01*
G02X1649922Y1456413I0J203D01*
G01Y1457034D01*
G03X1649872Y1457166I-200J0D01*
G02Y1460078I1664J1456D01*
G03X1649922Y1460210I-150J132D01*
G01Y1462153D01*
G03X1649872Y1462285I-200J0D01*
G02Y1465197I1664J1456D01*
G03X1649922Y1465329I-150J132D01*
G01Y1465951D01*
G02X1650125Y1466154I203J0D01*
G37*
G36*
G01X1670470Y1456412D02*
G02X1670268Y1456210I-202J0D01*
G01X1667448D01*
G02X1667246Y1456413I1J203D01*
G01Y1457032D01*
G03X1667196Y1457164I-200J0D01*
G02Y1460080I1661J1458D01*
G03X1667246Y1460212I-150J132D01*
G01Y1462151D01*
G03X1667196Y1462283I-200J0D01*
G02Y1465199I1661J1458D01*
G03X1667246Y1465331I-150J132D01*
G01Y1465952D01*
G02X1667448Y1466154I202J0D01*
G01X1670268D01*
G02X1670470Y1465951I-1J-203D01*
G01Y1465331D01*
G03X1670520Y1465199I200J0D01*
G02Y1462283I-1661J-1458D01*
G03X1670470Y1462151I150J-132D01*
G01Y1460212D01*
G03X1670520Y1460080I200J0D01*
G02Y1457164I-1661J-1458D01*
G03X1670470Y1457032I150J-132D01*
G01Y1456412D01*
G37*
G36*
G01X117133Y1470484D02*
X119953D01*
G02X120156Y1470281I0J-203D01*
G01Y1469659D01*
G03X120206Y1469527I200J0D01*
G02Y1466615I-1664J-1456D01*
G03X120156Y1466483I150J-132D01*
G01Y1464541D01*
G03X120206Y1464409I200J0D01*
G02Y1461497I-1664J-1456D01*
G03X120156Y1461365I150J-132D01*
G01Y1460743D01*
G02X119953Y1460540I-203J0D01*
G01X117133D01*
G02X116930Y1460743I0J203D01*
G01Y1461365D01*
G03X116880Y1461497I-200J0D01*
G02Y1464409I1664J1456D01*
G03X116930Y1464541I-150J132D01*
G01Y1466483D01*
G03X116880Y1466615I-200J0D01*
G02Y1469527I1664J1456D01*
G03X116930Y1469659I-150J132D01*
G01Y1470281D01*
G02X117133Y1470484I203J0D01*
G37*
G36*
G01X310706Y1460742D02*
G02X310504Y1460540I-202J0D01*
G01X307684D01*
G02X307482Y1460743I1J203D01*
G01Y1461363D01*
G03X307432Y1461495I-200J0D01*
G02Y1464411I1661J1458D01*
G03X307482Y1464543I-150J132D01*
G01Y1466481D01*
G03X307432Y1466613I-200J0D01*
G02Y1469529I1661J1458D01*
G03X307482Y1469661I-150J132D01*
G01Y1470282D01*
G02X307684Y1470484I202J0D01*
G01X310504D01*
G02X310706Y1470281I-1J-203D01*
G01Y1469661D01*
G03X310756Y1469529I200J0D01*
G02Y1466613I-1661J-1458D01*
G03X310706Y1466481I150J-132D01*
G01Y1464543D01*
G03X310756Y1464411I200J0D01*
G02Y1461495I-1661J-1458D01*
G03X310706Y1461363I150J-132D01*
G01Y1460742D01*
G37*
G36*
G01X325007Y1470484D02*
X327827D01*
G02X328030Y1470281I0J-203D01*
G01Y1469659D01*
G03X328080Y1469527I200J0D01*
G02Y1466615I-1664J-1456D01*
G03X328030Y1466483I150J-132D01*
G01Y1464541D01*
G03X328080Y1464409I200J0D01*
G02Y1461497I-1664J-1456D01*
G03X328030Y1461365I150J-132D01*
G01Y1460743D01*
G02X327827Y1460540I-203J0D01*
G01X325007D01*
G02X324804Y1460743I0J203D01*
G01Y1461365D01*
G03X324754Y1461497I-200J0D01*
G02Y1464409I1664J1456D01*
G03X324804Y1464541I-150J132D01*
G01Y1466483D01*
G03X324754Y1466615I-200J0D01*
G02Y1469527I1664J1456D01*
G03X324804Y1469659I-150J132D01*
G01Y1470281D01*
G02X325007Y1470484I203J0D01*
G37*
G36*
G01X345352Y1460742D02*
G02X345150Y1460540I-202J0D01*
G01X342330D01*
G02X342128Y1460743I1J203D01*
G01Y1461363D01*
G03X342078Y1461495I-200J0D01*
G02Y1464411I1661J1458D01*
G03X342128Y1464543I-150J132D01*
G01Y1466481D01*
G03X342078Y1466613I-200J0D01*
G02Y1469529I1661J1458D01*
G03X342128Y1469661I-150J132D01*
G01Y1470282D01*
G02X342330Y1470484I202J0D01*
G01X345150D01*
G02X345352Y1470281I-1J-203D01*
G01Y1469661D01*
G03X345402Y1469529I200J0D01*
G02Y1466613I-1661J-1458D01*
G03X345352Y1466481I150J-132D01*
G01Y1464543D01*
G03X345402Y1464411I200J0D01*
G02Y1461495I-1661J-1458D01*
G03X345352Y1461363I150J-132D01*
G01Y1460742D01*
G37*
G36*
G01X639840D02*
G02X639638Y1460540I-202J0D01*
G01X636818D01*
G02X636616Y1460743I1J203D01*
G01Y1461363D01*
G03X636566Y1461495I-200J0D01*
G02Y1464411I1661J1458D01*
G03X636616Y1464543I-150J132D01*
G01Y1466481D01*
G03X636566Y1466613I-200J0D01*
G02Y1469529I1661J1458D01*
G03X636616Y1469661I-150J132D01*
G01Y1470282D01*
G02X636818Y1470484I202J0D01*
G01X639638D01*
G02X639840Y1470281I-1J-203D01*
G01Y1469661D01*
G03X639890Y1469529I200J0D01*
G02Y1466613I-1661J-1458D01*
G03X639840Y1466481I150J-132D01*
G01Y1464543D01*
G03X639890Y1464411I200J0D01*
G02Y1461495I-1661J-1458D01*
G03X639840Y1461363I150J-132D01*
G01Y1460742D01*
G37*
G36*
G01X1139101Y1470484D02*
X1141921D01*
G02X1142124Y1470281I0J-203D01*
G01Y1469659D01*
G03X1142174Y1469527I200J0D01*
G02Y1466615I-1664J-1456D01*
G03X1142124Y1466483I150J-132D01*
G01Y1464541D01*
G03X1142174Y1464409I200J0D01*
G02Y1461497I-1664J-1456D01*
G03X1142124Y1461365I150J-132D01*
G01Y1460743D01*
G02X1141921Y1460540I-203J0D01*
G01X1139101D01*
G02X1138898Y1460743I0J203D01*
G01Y1461365D01*
G03X1138848Y1461497I-200J0D01*
G02Y1464409I1664J1456D01*
G03X1138898Y1464541I-150J132D01*
G01Y1466483D01*
G03X1138848Y1466615I-200J0D01*
G02Y1469527I1664J1456D01*
G03X1138898Y1469659I-150J132D01*
G01Y1470281D01*
G02X1139101Y1470484I203J0D01*
G37*
G36*
G01X1159446Y1460742D02*
G02X1159244Y1460540I-202J0D01*
G01X1156424D01*
G02X1156222Y1460743I1J203D01*
G01Y1461363D01*
G03X1156172Y1461495I-200J0D01*
G02Y1464411I1661J1458D01*
G03X1156222Y1464543I-150J132D01*
G01Y1466481D01*
G03X1156172Y1466613I-200J0D01*
G02Y1469529I1661J1458D01*
G03X1156222Y1469661I-150J132D01*
G01Y1470282D01*
G02X1156424Y1470484I202J0D01*
G01X1159244D01*
G02X1159446Y1470281I-1J-203D01*
G01Y1469661D01*
G03X1159496Y1469529I200J0D01*
G02Y1466613I-1661J-1458D01*
G03X1159446Y1466481I150J-132D01*
G01Y1464543D01*
G03X1159496Y1464411I200J0D01*
G02Y1461495I-1661J-1458D01*
G03X1159446Y1461363I150J-132D01*
G01Y1460742D01*
G37*
G36*
G01X1661808D02*
G02X1661606Y1460540I-202J0D01*
G01X1658786D01*
G02X1658584Y1460743I1J203D01*
G01Y1461363D01*
G03X1658534Y1461495I-200J0D01*
G02Y1464411I1661J1458D01*
G03X1658584Y1464543I-150J132D01*
G01Y1466481D01*
G03X1658534Y1466613I-200J0D01*
G02Y1469529I1661J1458D01*
G03X1658584Y1469661I-150J132D01*
G01Y1470282D01*
G02X1658786Y1470484I202J0D01*
G01X1661606D01*
G02X1661808Y1470281I-1J-203D01*
G01Y1469661D01*
G03X1661858Y1469529I200J0D01*
G02Y1466613I-1661J-1458D01*
G03X1661808Y1466481I150J-132D01*
G01Y1464543D01*
G03X1661858Y1464411I200J0D01*
G02Y1461495I-1661J-1458D01*
G03X1661808Y1461363I150J-132D01*
G01Y1460742D01*
G37*
G36*
G01X1676109Y1470484D02*
X1678929D01*
G02X1679132Y1470281I0J-203D01*
G01Y1469659D01*
G03X1679182Y1469527I200J0D01*
G02Y1466615I-1664J-1456D01*
G03X1679132Y1466483I150J-132D01*
G01Y1464541D01*
G03X1679182Y1464409I200J0D01*
G02Y1461497I-1664J-1456D01*
G03X1679132Y1461365I150J-132D01*
G01Y1460743D01*
G02X1678929Y1460540I-203J0D01*
G01X1676109D01*
G02X1675906Y1460743I0J203D01*
G01Y1461365D01*
G03X1675856Y1461497I-200J0D01*
G02Y1464409I1664J1456D01*
G03X1675906Y1464541I-150J132D01*
G01Y1466483D01*
G03X1675856Y1466615I-200J0D01*
G02Y1469527I1664J1456D01*
G03X1675906Y1469659I-150J132D01*
G01Y1470281D01*
G02X1676109Y1470484I203J0D01*
G37*
G36*
G01X111494Y1471766D02*
G02X111292Y1471564I-202J0D01*
G01X108472D01*
G02X108270Y1471767I1J203D01*
G01Y1472387D01*
G03X108220Y1472519I-200J0D01*
G02Y1475435I1661J1458D01*
G03X108270Y1475567I-150J132D01*
G01Y1477505D01*
G03X108220Y1477637I-200J0D01*
G02Y1480553I1661J1458D01*
G03X108270Y1480685I-150J132D01*
G01Y1481306D01*
G02X108472Y1481508I202J0D01*
G01X111292D01*
G02X111494Y1481305I-1J-203D01*
G01Y1480685D01*
G03X111544Y1480553I200J0D01*
G02Y1477637I-1661J-1458D01*
G03X111494Y1477505I150J-132D01*
G01Y1475567D01*
G03X111544Y1475435I200J0D01*
G02Y1472519I-1661J-1458D01*
G03X111494Y1472387I150J-132D01*
G01Y1471766D01*
G37*
G36*
G01X319368D02*
G02X319166Y1471564I-202J0D01*
G01X316346D01*
G02X316144Y1471767I1J203D01*
G01Y1472387D01*
G03X316094Y1472519I-200J0D01*
G02Y1475435I1661J1458D01*
G03X316144Y1475567I-150J132D01*
G01Y1477505D01*
G03X316094Y1477637I-200J0D01*
G02Y1480553I1661J1458D01*
G03X316144Y1480685I-150J132D01*
G01Y1481306D01*
G02X316346Y1481508I202J0D01*
G01X319166D01*
G02X319368Y1481305I-1J-203D01*
G01Y1480685D01*
G03X319418Y1480553I200J0D01*
G02Y1477637I-1661J-1458D01*
G03X319368Y1477505I150J-132D01*
G01Y1475567D01*
G03X319418Y1475435I200J0D01*
G02Y1472519I-1661J-1458D01*
G03X319368Y1472387I150J-132D01*
G01Y1471766D01*
G37*
G36*
G01X336690D02*
G02X336488Y1471564I-202J0D01*
G01X333668D01*
G02X333466Y1471767I1J203D01*
G01Y1472387D01*
G03X333416Y1472519I-200J0D01*
G02Y1475435I1661J1458D01*
G03X333466Y1475567I-150J132D01*
G01Y1477505D01*
G03X333416Y1477637I-200J0D01*
G02Y1480553I1661J1458D01*
G03X333466Y1480685I-150J132D01*
G01Y1481306D01*
G02X333668Y1481508I202J0D01*
G01X336488D01*
G02X336690Y1481305I-1J-203D01*
G01Y1480685D01*
G03X336740Y1480553I200J0D01*
G02Y1477637I-1661J-1458D01*
G03X336690Y1477505I150J-132D01*
G01Y1475567D01*
G03X336740Y1475435I200J0D01*
G02Y1472519I-1661J-1458D01*
G03X336690Y1472387I150J-132D01*
G01Y1471766D01*
G37*
G36*
G01X628157Y1481508D02*
X630977D01*
G02X631180Y1481305I0J-203D01*
G01Y1480683D01*
G03X631230Y1480551I200J0D01*
G02Y1477639I-1664J-1456D01*
G03X631180Y1477507I150J-132D01*
G01Y1475565D01*
G03X631230Y1475433I200J0D01*
G02Y1472521I-1664J-1456D01*
G03X631180Y1472389I150J-132D01*
G01Y1471767D01*
G02X630977Y1471564I-203J0D01*
G01X628157D01*
G02X627954Y1471767I0J203D01*
G01Y1472389D01*
G03X627904Y1472521I-200J0D01*
G02Y1475433I1664J1456D01*
G03X627954Y1475565I-150J132D01*
G01Y1477507D01*
G03X627904Y1477639I-200J0D01*
G02Y1480551I1664J1456D01*
G03X627954Y1480683I-150J132D01*
G01Y1481305D01*
G02X628157Y1481508I203J0D01*
G37*
G36*
G01X1133462Y1471766D02*
G02X1133260Y1471564I-202J0D01*
G01X1130440D01*
G02X1130238Y1471767I1J203D01*
G01Y1472387D01*
G03X1130188Y1472519I-200J0D01*
G02Y1475435I1661J1458D01*
G03X1130238Y1475567I-150J132D01*
G01Y1477505D01*
G03X1130188Y1477637I-200J0D01*
G02Y1480553I1661J1458D01*
G03X1130238Y1480685I-150J132D01*
G01Y1481306D01*
G02X1130440Y1481508I202J0D01*
G01X1133260D01*
G02X1133462Y1481305I-1J-203D01*
G01Y1480685D01*
G03X1133512Y1480553I200J0D01*
G02Y1477637I-1661J-1458D01*
G03X1133462Y1477505I150J-132D01*
G01Y1475567D01*
G03X1133512Y1475435I200J0D01*
G02Y1472519I-1661J-1458D01*
G03X1133462Y1472387I150J-132D01*
G01Y1471766D01*
G37*
G36*
G01X1147763Y1481508D02*
X1150583D01*
G02X1150786Y1481305I0J-203D01*
G01Y1480683D01*
G03X1150836Y1480551I200J0D01*
G02Y1477639I-1664J-1456D01*
G03X1150786Y1477507I150J-132D01*
G01Y1475565D01*
G03X1150836Y1475433I200J0D01*
G02Y1472521I-1664J-1456D01*
G03X1150786Y1472389I150J-132D01*
G01Y1471767D01*
G02X1150583Y1471564I-203J0D01*
G01X1147763D01*
G02X1147560Y1471767I0J203D01*
G01Y1472389D01*
G03X1147510Y1472521I-200J0D01*
G02Y1475433I1664J1456D01*
G03X1147560Y1475565I-150J132D01*
G01Y1477507D01*
G03X1147510Y1477639I-200J0D01*
G02Y1480551I1664J1456D01*
G03X1147560Y1480683I-150J132D01*
G01Y1481305D01*
G02X1147763Y1481508I203J0D01*
G37*
G36*
G01X1650125D02*
X1652945D01*
G02X1653148Y1481305I0J-203D01*
G01Y1480683D01*
G03X1653198Y1480551I200J0D01*
G02Y1477639I-1664J-1456D01*
G03X1653148Y1477507I150J-132D01*
G01Y1475565D01*
G03X1653198Y1475433I200J0D01*
G02Y1472521I-1664J-1456D01*
G03X1653148Y1472389I150J-132D01*
G01Y1471767D01*
G02X1652945Y1471564I-203J0D01*
G01X1650125D01*
G02X1649922Y1471767I0J203D01*
G01Y1472389D01*
G03X1649872Y1472521I-200J0D01*
G02Y1475433I1664J1456D01*
G03X1649922Y1475565I-150J132D01*
G01Y1477507D01*
G03X1649872Y1477639I-200J0D01*
G02Y1480551I1664J1456D01*
G03X1649922Y1480683I-150J132D01*
G01Y1481305D01*
G02X1650125Y1481508I203J0D01*
G37*
G36*
G01X1670470Y1471766D02*
G02X1670268Y1471564I-202J0D01*
G01X1667448D01*
G02X1667246Y1471767I1J203D01*
G01Y1472387D01*
G03X1667196Y1472519I-200J0D01*
G02Y1475435I1661J1458D01*
G03X1667246Y1475567I-150J132D01*
G01Y1477505D01*
G03X1667196Y1477637I-200J0D01*
G02Y1480553I1661J1458D01*
G03X1667246Y1480685I-150J132D01*
G01Y1481306D01*
G02X1667448Y1481508I202J0D01*
G01X1670268D01*
G02X1670470Y1481305I-1J-203D01*
G01Y1480685D01*
G03X1670520Y1480553I200J0D01*
G02Y1477637I-1661J-1458D01*
G03X1670470Y1477505I150J-132D01*
G01Y1475567D01*
G03X1670520Y1475435I200J0D01*
G02Y1472519I-1661J-1458D01*
G03X1670470Y1472387I150J-132D01*
G01Y1471766D01*
G37*
G36*
G01X117133Y1485838D02*
X119953D01*
G02X120156Y1485635I0J-203D01*
G01Y1485014D01*
G03X120206Y1484882I200J0D01*
G02Y1481970I-1664J-1456D01*
G03X120156Y1481838I150J-132D01*
G01Y1479896D01*
G03X120206Y1479764I200J0D01*
G02Y1476852I-1664J-1456D01*
G03X120156Y1476720I150J-132D01*
G01Y1476097D01*
G02X119953Y1475894I-203J0D01*
G01X117133D01*
G02X116930Y1476097I0J203D01*
G01Y1476720D01*
G03X116880Y1476852I-200J0D01*
G02Y1479764I1664J1456D01*
G03X116930Y1479896I-150J132D01*
G01Y1481838D01*
G03X116880Y1481970I-200J0D01*
G02Y1484882I1664J1456D01*
G03X116930Y1485014I-150J132D01*
G01Y1485635D01*
G02X117133Y1485838I203J0D01*
G37*
G36*
G01X310706Y1476096D02*
G02X310504Y1475894I-202J0D01*
G01X307684D01*
G02X307482Y1476097I1J203D01*
G01Y1476718D01*
G03X307432Y1476850I-200J0D01*
G02Y1479766I1661J1458D01*
G03X307482Y1479898I-150J132D01*
G01Y1481836D01*
G03X307432Y1481968I-200J0D01*
G02Y1484884I1661J1458D01*
G03X307482Y1485016I-150J132D01*
G01Y1485636D01*
G02X307684Y1485838I202J0D01*
G01X310504D01*
G02X310706Y1485635I-1J-203D01*
G01Y1485016D01*
G03X310756Y1484884I200J0D01*
G02Y1481968I-1661J-1458D01*
G03X310706Y1481836I150J-132D01*
G01Y1479898D01*
G03X310756Y1479766I200J0D01*
G02Y1476850I-1661J-1458D01*
G03X310706Y1476718I150J-132D01*
G01Y1476096D01*
G37*
G36*
G01X325007Y1485838D02*
X327827D01*
G02X328030Y1485635I0J-203D01*
G01Y1485014D01*
G03X328080Y1484882I200J0D01*
G02Y1481970I-1664J-1456D01*
G03X328030Y1481838I150J-132D01*
G01Y1479896D01*
G03X328080Y1479764I200J0D01*
G02Y1476852I-1664J-1456D01*
G03X328030Y1476720I150J-132D01*
G01Y1476097D01*
G02X327827Y1475894I-203J0D01*
G01X325007D01*
G02X324804Y1476097I0J203D01*
G01Y1476720D01*
G03X324754Y1476852I-200J0D01*
G02Y1479764I1664J1456D01*
G03X324804Y1479896I-150J132D01*
G01Y1481838D01*
G03X324754Y1481970I-200J0D01*
G02Y1484882I1664J1456D01*
G03X324804Y1485014I-150J132D01*
G01Y1485635D01*
G02X325007Y1485838I203J0D01*
G37*
G36*
G01X345352Y1476096D02*
G02X345150Y1475894I-202J0D01*
G01X342330D01*
G02X342128Y1476097I1J203D01*
G01Y1476718D01*
G03X342078Y1476850I-200J0D01*
G02Y1479766I1661J1458D01*
G03X342128Y1479898I-150J132D01*
G01Y1481836D01*
G03X342078Y1481968I-200J0D01*
G02Y1484884I1661J1458D01*
G03X342128Y1485016I-150J132D01*
G01Y1485636D01*
G02X342330Y1485838I202J0D01*
G01X345150D01*
G02X345352Y1485635I-1J-203D01*
G01Y1485016D01*
G03X345402Y1484884I200J0D01*
G02Y1481968I-1661J-1458D01*
G03X345352Y1481836I150J-132D01*
G01Y1479898D01*
G03X345402Y1479766I200J0D01*
G02Y1476850I-1661J-1458D01*
G03X345352Y1476718I150J-132D01*
G01Y1476096D01*
G37*
G36*
G01X639840D02*
G02X639638Y1475894I-202J0D01*
G01X636818D01*
G02X636616Y1476097I1J203D01*
G01Y1476718D01*
G03X636566Y1476850I-200J0D01*
G02Y1479766I1661J1458D01*
G03X636616Y1479898I-150J132D01*
G01Y1481836D01*
G03X636566Y1481968I-200J0D01*
G02Y1484884I1661J1458D01*
G03X636616Y1485016I-150J132D01*
G01Y1485636D01*
G02X636818Y1485838I202J0D01*
G01X639638D01*
G02X639840Y1485635I-1J-203D01*
G01Y1485016D01*
G03X639890Y1484884I200J0D01*
G02Y1481968I-1661J-1458D01*
G03X639840Y1481836I150J-132D01*
G01Y1479898D01*
G03X639890Y1479766I200J0D01*
G02Y1476850I-1661J-1458D01*
G03X639840Y1476718I150J-132D01*
G01Y1476096D01*
G37*
G36*
G01X1139101Y1485838D02*
X1141921D01*
G02X1142124Y1485635I0J-203D01*
G01Y1485014D01*
G03X1142174Y1484882I200J0D01*
G02Y1481970I-1664J-1456D01*
G03X1142124Y1481838I150J-132D01*
G01Y1479896D01*
G03X1142174Y1479764I200J0D01*
G02Y1476852I-1664J-1456D01*
G03X1142124Y1476720I150J-132D01*
G01Y1476097D01*
G02X1141921Y1475894I-203J0D01*
G01X1139101D01*
G02X1138898Y1476097I0J203D01*
G01Y1476720D01*
G03X1138848Y1476852I-200J0D01*
G02Y1479764I1664J1456D01*
G03X1138898Y1479896I-150J132D01*
G01Y1481838D01*
G03X1138848Y1481970I-200J0D01*
G02Y1484882I1664J1456D01*
G03X1138898Y1485014I-150J132D01*
G01Y1485635D01*
G02X1139101Y1485838I203J0D01*
G37*
G36*
G01X1159446Y1476096D02*
G02X1159244Y1475894I-202J0D01*
G01X1156424D01*
G02X1156222Y1476097I1J203D01*
G01Y1476718D01*
G03X1156172Y1476850I-200J0D01*
G02Y1479766I1661J1458D01*
G03X1156222Y1479898I-150J132D01*
G01Y1481836D01*
G03X1156172Y1481968I-200J0D01*
G02Y1484884I1661J1458D01*
G03X1156222Y1485016I-150J132D01*
G01Y1485636D01*
G02X1156424Y1485838I202J0D01*
G01X1159244D01*
G02X1159446Y1485635I-1J-203D01*
G01Y1485016D01*
G03X1159496Y1484884I200J0D01*
G02Y1481968I-1661J-1458D01*
G03X1159446Y1481836I150J-132D01*
G01Y1479898D01*
G03X1159496Y1479766I200J0D01*
G02Y1476850I-1661J-1458D01*
G03X1159446Y1476718I150J-132D01*
G01Y1476096D01*
G37*
G36*
G01X1661808D02*
G02X1661606Y1475894I-202J0D01*
G01X1658786D01*
G02X1658584Y1476097I1J203D01*
G01Y1476718D01*
G03X1658534Y1476850I-200J0D01*
G02Y1479766I1661J1458D01*
G03X1658584Y1479898I-150J132D01*
G01Y1481836D01*
G03X1658534Y1481968I-200J0D01*
G02Y1484884I1661J1458D01*
G03X1658584Y1485016I-150J132D01*
G01Y1485636D01*
G02X1658786Y1485838I202J0D01*
G01X1661606D01*
G02X1661808Y1485635I-1J-203D01*
G01Y1485016D01*
G03X1661858Y1484884I200J0D01*
G02Y1481968I-1661J-1458D01*
G03X1661808Y1481836I150J-132D01*
G01Y1479898D01*
G03X1661858Y1479766I200J0D01*
G02Y1476850I-1661J-1458D01*
G03X1661808Y1476718I150J-132D01*
G01Y1476096D01*
G37*
G36*
G01X1676109Y1485838D02*
X1678929D01*
G02X1679132Y1485635I0J-203D01*
G01Y1485014D01*
G03X1679182Y1484882I200J0D01*
G02Y1481970I-1664J-1456D01*
G03X1679132Y1481838I150J-132D01*
G01Y1479896D01*
G03X1679182Y1479764I200J0D01*
G02Y1476852I-1664J-1456D01*
G03X1679132Y1476720I150J-132D01*
G01Y1476097D01*
G02X1678929Y1475894I-203J0D01*
G01X1676109D01*
G02X1675906Y1476097I0J203D01*
G01Y1476720D01*
G03X1675856Y1476852I-200J0D01*
G02Y1479764I1664J1456D01*
G03X1675906Y1479896I-150J132D01*
G01Y1481838D01*
G03X1675856Y1481970I-200J0D01*
G02Y1484882I1664J1456D01*
G03X1675906Y1485014I-150J132D01*
G01Y1485635D01*
G02X1676109Y1485838I203J0D01*
G37*
G36*
G01X111494Y1487120D02*
G02X111292Y1486918I-202J0D01*
G01X108472D01*
G02X108270Y1487121I1J203D01*
G01Y1487741D01*
G03X108220Y1487873I-200J0D01*
G02Y1490789I1661J1458D01*
G03X108270Y1490921I-150J132D01*
G01Y1492859D01*
G03X108220Y1492991I-200J0D01*
G02Y1495907I1661J1458D01*
G03X108270Y1496039I-150J132D01*
G01Y1496660D01*
G02X108472Y1496862I202J0D01*
G01X111292D01*
G02X111494Y1496659I-1J-203D01*
G01Y1496039D01*
G03X111544Y1495907I200J0D01*
G02Y1492991I-1661J-1458D01*
G03X111494Y1492859I150J-132D01*
G01Y1490921D01*
G03X111544Y1490789I200J0D01*
G02Y1487873I-1661J-1458D01*
G03X111494Y1487741I150J-132D01*
G01Y1487120D01*
G37*
G36*
G01X319368D02*
G02X319166Y1486918I-202J0D01*
G01X316346D01*
G02X316144Y1487121I1J203D01*
G01Y1487741D01*
G03X316094Y1487873I-200J0D01*
G02Y1490789I1661J1458D01*
G03X316144Y1490921I-150J132D01*
G01Y1492859D01*
G03X316094Y1492991I-200J0D01*
G02Y1495907I1661J1458D01*
G03X316144Y1496039I-150J132D01*
G01Y1496660D01*
G02X316346Y1496862I202J0D01*
G01X319166D01*
G02X319368Y1496659I-1J-203D01*
G01Y1496039D01*
G03X319418Y1495907I200J0D01*
G02Y1492991I-1661J-1458D01*
G03X319368Y1492859I150J-132D01*
G01Y1490921D01*
G03X319418Y1490789I200J0D01*
G02Y1487873I-1661J-1458D01*
G03X319368Y1487741I150J-132D01*
G01Y1487120D01*
G37*
G36*
G01X336690D02*
G02X336488Y1486918I-202J0D01*
G01X333668D01*
G02X333466Y1487121I1J203D01*
G01Y1487741D01*
G03X333416Y1487873I-200J0D01*
G02Y1490789I1661J1458D01*
G03X333466Y1490921I-150J132D01*
G01Y1492859D01*
G03X333416Y1492991I-200J0D01*
G02Y1495907I1661J1458D01*
G03X333466Y1496039I-150J132D01*
G01Y1496660D01*
G02X333668Y1496862I202J0D01*
G01X336488D01*
G02X336690Y1496659I-1J-203D01*
G01Y1496039D01*
G03X336740Y1495907I200J0D01*
G02Y1492991I-1661J-1458D01*
G03X336690Y1492859I150J-132D01*
G01Y1490921D01*
G03X336740Y1490789I200J0D01*
G02Y1487873I-1661J-1458D01*
G03X336690Y1487741I150J-132D01*
G01Y1487120D01*
G37*
G36*
G01X628157Y1496862D02*
X630977D01*
G02X631180Y1496659I0J-203D01*
G01Y1496037D01*
G03X631230Y1495905I200J0D01*
G02Y1492993I-1664J-1456D01*
G03X631180Y1492861I150J-132D01*
G01Y1490919D01*
G03X631230Y1490787I200J0D01*
G02Y1487875I-1664J-1456D01*
G03X631180Y1487743I150J-132D01*
G01Y1487121D01*
G02X630977Y1486918I-203J0D01*
G01X628157D01*
G02X627954Y1487121I0J203D01*
G01Y1487743D01*
G03X627904Y1487875I-200J0D01*
G02Y1490787I1664J1456D01*
G03X627954Y1490919I-150J132D01*
G01Y1492861D01*
G03X627904Y1492993I-200J0D01*
G02Y1495905I1664J1456D01*
G03X627954Y1496037I-150J132D01*
G01Y1496659D01*
G02X628157Y1496862I203J0D01*
G37*
G36*
G01X1133462Y1487120D02*
G02X1133260Y1486918I-202J0D01*
G01X1130440D01*
G02X1130238Y1487121I1J203D01*
G01Y1487741D01*
G03X1130188Y1487873I-200J0D01*
G02Y1490789I1661J1458D01*
G03X1130238Y1490921I-150J132D01*
G01Y1492859D01*
G03X1130188Y1492991I-200J0D01*
G02Y1495907I1661J1458D01*
G03X1130238Y1496039I-150J132D01*
G01Y1496660D01*
G02X1130440Y1496862I202J0D01*
G01X1133260D01*
G02X1133462Y1496659I-1J-203D01*
G01Y1496039D01*
G03X1133512Y1495907I200J0D01*
G02Y1492991I-1661J-1458D01*
G03X1133462Y1492859I150J-132D01*
G01Y1490921D01*
G03X1133512Y1490789I200J0D01*
G02Y1487873I-1661J-1458D01*
G03X1133462Y1487741I150J-132D01*
G01Y1487120D01*
G37*
G36*
G01X1147763Y1496862D02*
X1150583D01*
G02X1150786Y1496659I0J-203D01*
G01Y1496037D01*
G03X1150836Y1495905I200J0D01*
G02Y1492993I-1664J-1456D01*
G03X1150786Y1492861I150J-132D01*
G01Y1490919D01*
G03X1150836Y1490787I200J0D01*
G02Y1487875I-1664J-1456D01*
G03X1150786Y1487743I150J-132D01*
G01Y1487121D01*
G02X1150583Y1486918I-203J0D01*
G01X1147763D01*
G02X1147560Y1487121I0J203D01*
G01Y1487743D01*
G03X1147510Y1487875I-200J0D01*
G02Y1490787I1664J1456D01*
G03X1147560Y1490919I-150J132D01*
G01Y1492861D01*
G03X1147510Y1492993I-200J0D01*
G02Y1495905I1664J1456D01*
G03X1147560Y1496037I-150J132D01*
G01Y1496659D01*
G02X1147763Y1496862I203J0D01*
G37*
G36*
G01X1650125D02*
X1652945D01*
G02X1653148Y1496659I0J-203D01*
G01Y1496037D01*
G03X1653198Y1495905I200J0D01*
G02Y1492993I-1664J-1456D01*
G03X1653148Y1492861I150J-132D01*
G01Y1490919D01*
G03X1653198Y1490787I200J0D01*
G02Y1487875I-1664J-1456D01*
G03X1653148Y1487743I150J-132D01*
G01Y1487121D01*
G02X1652945Y1486918I-203J0D01*
G01X1650125D01*
G02X1649922Y1487121I0J203D01*
G01Y1487743D01*
G03X1649872Y1487875I-200J0D01*
G02Y1490787I1664J1456D01*
G03X1649922Y1490919I-150J132D01*
G01Y1492861D01*
G03X1649872Y1492993I-200J0D01*
G02Y1495905I1664J1456D01*
G03X1649922Y1496037I-150J132D01*
G01Y1496659D01*
G02X1650125Y1496862I203J0D01*
G37*
G36*
G01X1670470Y1487120D02*
G02X1670268Y1486918I-202J0D01*
G01X1667448D01*
G02X1667246Y1487121I1J203D01*
G01Y1487741D01*
G03X1667196Y1487873I-200J0D01*
G02Y1490789I1661J1458D01*
G03X1667246Y1490921I-150J132D01*
G01Y1492859D01*
G03X1667196Y1492991I-200J0D01*
G02Y1495907I1661J1458D01*
G03X1667246Y1496039I-150J132D01*
G01Y1496660D01*
G02X1667448Y1496862I202J0D01*
G01X1670268D01*
G02X1670470Y1496659I-1J-203D01*
G01Y1496039D01*
G03X1670520Y1495907I200J0D01*
G02Y1492991I-1661J-1458D01*
G03X1670470Y1492859I150J-132D01*
G01Y1490921D01*
G03X1670520Y1490789I200J0D01*
G02Y1487873I-1661J-1458D01*
G03X1670470Y1487741I150J-132D01*
G01Y1487120D01*
G37*
G36*
G01X117133Y1501192D02*
X119953D01*
G02X120156Y1500989I0J-203D01*
G01Y1500368D01*
G03X120206Y1500236I200J0D01*
G02Y1497324I-1664J-1456D01*
G03X120156Y1497192I150J-132D01*
G01Y1495250D01*
G03X120206Y1495118I200J0D01*
G02Y1492206I-1664J-1456D01*
G03X120156Y1492074I150J-132D01*
G01Y1491451D01*
G02X119953Y1491248I-203J0D01*
G01X117133D01*
G02X116930Y1491451I0J203D01*
G01Y1492074D01*
G03X116880Y1492206I-200J0D01*
G02Y1495118I1664J1456D01*
G03X116930Y1495250I-150J132D01*
G01Y1497192D01*
G03X116880Y1497324I-200J0D01*
G02Y1500236I1664J1456D01*
G03X116930Y1500368I-150J132D01*
G01Y1500989D01*
G02X117133Y1501192I203J0D01*
G37*
G36*
G01X310706Y1491450D02*
G02X310504Y1491248I-202J0D01*
G01X307684D01*
G02X307482Y1491451I1J203D01*
G01Y1492072D01*
G03X307432Y1492204I-200J0D01*
G02Y1495120I1661J1458D01*
G03X307482Y1495252I-150J132D01*
G01Y1497190D01*
G03X307432Y1497322I-200J0D01*
G02Y1500238I1661J1458D01*
G03X307482Y1500370I-150J132D01*
G01Y1500990D01*
G02X307684Y1501192I202J0D01*
G01X310504D01*
G02X310706Y1500989I-1J-203D01*
G01Y1500370D01*
G03X310756Y1500238I200J0D01*
G02Y1497322I-1661J-1458D01*
G03X310706Y1497190I150J-132D01*
G01Y1495252D01*
G03X310756Y1495120I200J0D01*
G02Y1492204I-1661J-1458D01*
G03X310706Y1492072I150J-132D01*
G01Y1491450D01*
G37*
G36*
G01X325007Y1501192D02*
X327827D01*
G02X328030Y1500989I0J-203D01*
G01Y1500368D01*
G03X328080Y1500236I200J0D01*
G02Y1497324I-1664J-1456D01*
G03X328030Y1497192I150J-132D01*
G01Y1495250D01*
G03X328080Y1495118I200J0D01*
G02Y1492206I-1664J-1456D01*
G03X328030Y1492074I150J-132D01*
G01Y1491451D01*
G02X327827Y1491248I-203J0D01*
G01X325007D01*
G02X324804Y1491451I0J203D01*
G01Y1492074D01*
G03X324754Y1492206I-200J0D01*
G02Y1495118I1664J1456D01*
G03X324804Y1495250I-150J132D01*
G01Y1497192D01*
G03X324754Y1497324I-200J0D01*
G02Y1500236I1664J1456D01*
G03X324804Y1500368I-150J132D01*
G01Y1500989D01*
G02X325007Y1501192I203J0D01*
G37*
G36*
G01X345352Y1491450D02*
G02X345150Y1491248I-202J0D01*
G01X342330D01*
G02X342128Y1491451I1J203D01*
G01Y1492072D01*
G03X342078Y1492204I-200J0D01*
G02Y1495120I1661J1458D01*
G03X342128Y1495252I-150J132D01*
G01Y1497190D01*
G03X342078Y1497322I-200J0D01*
G02Y1500238I1661J1458D01*
G03X342128Y1500370I-150J132D01*
G01Y1500990D01*
G02X342330Y1501192I202J0D01*
G01X345150D01*
G02X345352Y1500989I-1J-203D01*
G01Y1500370D01*
G03X345402Y1500238I200J0D01*
G02Y1497322I-1661J-1458D01*
G03X345352Y1497190I150J-132D01*
G01Y1495252D01*
G03X345402Y1495120I200J0D01*
G02Y1492204I-1661J-1458D01*
G03X345352Y1492072I150J-132D01*
G01Y1491450D01*
G37*
G36*
G01X639840D02*
G02X639638Y1491248I-202J0D01*
G01X636818D01*
G02X636616Y1491451I1J203D01*
G01Y1492072D01*
G03X636566Y1492204I-200J0D01*
G02Y1495120I1661J1458D01*
G03X636616Y1495252I-150J132D01*
G01Y1497190D01*
G03X636566Y1497322I-200J0D01*
G02Y1500238I1661J1458D01*
G03X636616Y1500370I-150J132D01*
G01Y1500990D01*
G02X636818Y1501192I202J0D01*
G01X639638D01*
G02X639840Y1500989I-1J-203D01*
G01Y1500370D01*
G03X639890Y1500238I200J0D01*
G02Y1497322I-1661J-1458D01*
G03X639840Y1497190I150J-132D01*
G01Y1495252D01*
G03X639890Y1495120I200J0D01*
G02Y1492204I-1661J-1458D01*
G03X639840Y1492072I150J-132D01*
G01Y1491450D01*
G37*
G36*
G01X1139101Y1501192D02*
X1141921D01*
G02X1142124Y1500989I0J-203D01*
G01Y1500368D01*
G03X1142174Y1500236I200J0D01*
G02Y1497324I-1664J-1456D01*
G03X1142124Y1497192I150J-132D01*
G01Y1495250D01*
G03X1142174Y1495118I200J0D01*
G02Y1492206I-1664J-1456D01*
G03X1142124Y1492074I150J-132D01*
G01Y1491451D01*
G02X1141921Y1491248I-203J0D01*
G01X1139101D01*
G02X1138898Y1491451I0J203D01*
G01Y1492074D01*
G03X1138848Y1492206I-200J0D01*
G02Y1495118I1664J1456D01*
G03X1138898Y1495250I-150J132D01*
G01Y1497192D01*
G03X1138848Y1497324I-200J0D01*
G02Y1500236I1664J1456D01*
G03X1138898Y1500368I-150J132D01*
G01Y1500989D01*
G02X1139101Y1501192I203J0D01*
G37*
G36*
G01X1159446Y1491450D02*
G02X1159244Y1491248I-202J0D01*
G01X1156424D01*
G02X1156222Y1491451I1J203D01*
G01Y1492072D01*
G03X1156172Y1492204I-200J0D01*
G02Y1495120I1661J1458D01*
G03X1156222Y1495252I-150J132D01*
G01Y1497190D01*
G03X1156172Y1497322I-200J0D01*
G02Y1500238I1661J1458D01*
G03X1156222Y1500370I-150J132D01*
G01Y1500990D01*
G02X1156424Y1501192I202J0D01*
G01X1159244D01*
G02X1159446Y1500989I-1J-203D01*
G01Y1500370D01*
G03X1159496Y1500238I200J0D01*
G02Y1497322I-1661J-1458D01*
G03X1159446Y1497190I150J-132D01*
G01Y1495252D01*
G03X1159496Y1495120I200J0D01*
G02Y1492204I-1661J-1458D01*
G03X1159446Y1492072I150J-132D01*
G01Y1491450D01*
G37*
G36*
G01X1661808D02*
G02X1661606Y1491248I-202J0D01*
G01X1658786D01*
G02X1658584Y1491451I1J203D01*
G01Y1492072D01*
G03X1658534Y1492204I-200J0D01*
G02Y1495120I1661J1458D01*
G03X1658584Y1495252I-150J132D01*
G01Y1497190D01*
G03X1658534Y1497322I-200J0D01*
G02Y1500238I1661J1458D01*
G03X1658584Y1500370I-150J132D01*
G01Y1500990D01*
G02X1658786Y1501192I202J0D01*
G01X1661606D01*
G02X1661808Y1500989I-1J-203D01*
G01Y1500370D01*
G03X1661858Y1500238I200J0D01*
G02Y1497322I-1661J-1458D01*
G03X1661808Y1497190I150J-132D01*
G01Y1495252D01*
G03X1661858Y1495120I200J0D01*
G02Y1492204I-1661J-1458D01*
G03X1661808Y1492072I150J-132D01*
G01Y1491450D01*
G37*
G36*
G01X1676109Y1501192D02*
X1678929D01*
G02X1679132Y1500989I0J-203D01*
G01Y1500368D01*
G03X1679182Y1500236I200J0D01*
G02Y1497324I-1664J-1456D01*
G03X1679132Y1497192I150J-132D01*
G01Y1495250D01*
G03X1679182Y1495118I200J0D01*
G02Y1492206I-1664J-1456D01*
G03X1679132Y1492074I150J-132D01*
G01Y1491451D01*
G02X1678929Y1491248I-203J0D01*
G01X1676109D01*
G02X1675906Y1491451I0J203D01*
G01Y1492074D01*
G03X1675856Y1492206I-200J0D01*
G02Y1495118I1664J1456D01*
G03X1675906Y1495250I-150J132D01*
G01Y1497192D01*
G03X1675856Y1497324I-200J0D01*
G02Y1500236I1664J1456D01*
G03X1675906Y1500368I-150J132D01*
G01Y1500989D01*
G02X1676109Y1501192I203J0D01*
G37*
G36*
G01X108472Y1512216D02*
X111292D01*
G02X111494Y1512014I0J-202D01*
G01Y1511394D01*
G03X111544Y1511262I200J0D01*
G02Y1508346I-1661J-1458D01*
G03X111494Y1508214I150J-132D01*
G01Y1506275D01*
G03X111544Y1506143I200J0D01*
G02Y1503227I-1661J-1458D01*
G03X111494Y1503095I150J-132D01*
G01Y1502476D01*
G02X111292Y1502274I-202J0D01*
G01X108472D01*
G02X108270Y1502476I0J202D01*
G01Y1503095D01*
G03X108220Y1503227I-200J0D01*
G02Y1506143I1661J1458D01*
G03X108270Y1506275I-150J132D01*
G01Y1508214D01*
G03X108220Y1508346I-200J0D01*
G02Y1511262I1661J1458D01*
G03X108270Y1511394I-150J132D01*
G01Y1512014D01*
G02X108472Y1512216I202J0D01*
G37*
G36*
G01X316346D02*
X319166D01*
G02X319368Y1512014I0J-202D01*
G01Y1511394D01*
G03X319418Y1511262I200J0D01*
G02Y1508346I-1661J-1458D01*
G03X319368Y1508214I150J-132D01*
G01Y1506275D01*
G03X319418Y1506143I200J0D01*
G02Y1503227I-1661J-1458D01*
G03X319368Y1503095I150J-132D01*
G01Y1502476D01*
G02X319166Y1502274I-202J0D01*
G01X316346D01*
G02X316144Y1502476I0J202D01*
G01Y1503095D01*
G03X316094Y1503227I-200J0D01*
G02Y1506143I1661J1458D01*
G03X316144Y1506275I-150J132D01*
G01Y1508214D01*
G03X316094Y1508346I-200J0D01*
G02Y1511262I1661J1458D01*
G03X316144Y1511394I-150J132D01*
G01Y1512014D01*
G02X316346Y1512216I202J0D01*
G37*
G36*
G01X333668D02*
X336488D01*
G02X336690Y1512014I0J-202D01*
G01Y1511394D01*
G03X336740Y1511262I200J0D01*
G02Y1508346I-1661J-1458D01*
G03X336690Y1508214I150J-132D01*
G01Y1506275D01*
G03X336740Y1506143I200J0D01*
G02Y1503227I-1661J-1458D01*
G03X336690Y1503095I150J-132D01*
G01Y1502476D01*
G02X336488Y1502274I-202J0D01*
G01X333668D01*
G02X333466Y1502476I0J202D01*
G01Y1503095D01*
G03X333416Y1503227I-200J0D01*
G02Y1506143I1661J1458D01*
G03X333466Y1506275I-150J132D01*
G01Y1508214D01*
G03X333416Y1508346I-200J0D01*
G02Y1511262I1661J1458D01*
G03X333466Y1511394I-150J132D01*
G01Y1512014D01*
G02X333668Y1512216I202J0D01*
G37*
G36*
G01X1130440D02*
X1133260D01*
G02X1133462Y1512014I0J-202D01*
G01Y1511394D01*
G03X1133512Y1511262I200J0D01*
G02Y1508346I-1661J-1458D01*
G03X1133462Y1508214I150J-132D01*
G01Y1506275D01*
G03X1133512Y1506143I200J0D01*
G02Y1503227I-1661J-1458D01*
G03X1133462Y1503095I150J-132D01*
G01Y1502476D01*
G02X1133260Y1502274I-202J0D01*
G01X1130440D01*
G02X1130238Y1502476I0J202D01*
G01Y1503095D01*
G03X1130188Y1503227I-200J0D01*
G02Y1506143I1661J1458D01*
G03X1130238Y1506275I-150J132D01*
G01Y1508214D01*
G03X1130188Y1508346I-200J0D01*
G02Y1511262I1661J1458D01*
G03X1130238Y1511394I-150J132D01*
G01Y1512014D01*
G02X1130440Y1512216I202J0D01*
G37*
G36*
G01X1667448D02*
X1670268D01*
G02X1670470Y1512014I0J-202D01*
G01Y1511394D01*
G03X1670520Y1511262I200J0D01*
G02Y1508346I-1661J-1458D01*
G03X1670470Y1508214I150J-132D01*
G01Y1506275D01*
G03X1670520Y1506143I200J0D01*
G02Y1503227I-1661J-1458D01*
G03X1670470Y1503095I150J-132D01*
G01Y1502476D01*
G02X1670268Y1502274I-202J0D01*
G01X1667448D01*
G02X1667246Y1502476I0J202D01*
G01Y1503095D01*
G03X1667196Y1503227I-200J0D01*
G02Y1506143I1661J1458D01*
G03X1667246Y1506275I-150J132D01*
G01Y1508214D01*
G03X1667196Y1508346I-200J0D01*
G02Y1511262I1661J1458D01*
G03X1667246Y1511394I-150J132D01*
G01Y1512014D01*
G02X1667448Y1512216I202J0D01*
G37*
G36*
G01X628156Y1502274D02*
G02X627954Y1502476I0J202D01*
G01Y1503097D01*
G03X627904Y1503229I-200J0D01*
G02Y1506141I1664J1456D01*
G03X627954Y1506273I-150J132D01*
G01Y1508216D01*
G03X627904Y1508348I-200J0D01*
G02Y1511260I1664J1456D01*
G03X627954Y1511392I-150J132D01*
G01Y1512014D01*
G02X628157Y1512216I203J-1D01*
G01X630978D01*
G02X631180Y1512014I0J-202D01*
G01Y1511392D01*
G03X631230Y1511260I200J0D01*
G02Y1508348I-1664J-1456D01*
G03X631180Y1508216I150J-132D01*
G01Y1506273D01*
G03X631230Y1506141I200J0D01*
G02Y1503229I-1664J-1456D01*
G03X631180Y1503097I150J-132D01*
G01Y1502476D01*
G02X630977Y1502274I-203J1D01*
G01X628156D01*
G37*
G36*
G01X1147762D02*
G02X1147560Y1502476I0J202D01*
G01Y1503097D01*
G03X1147510Y1503229I-200J0D01*
G02Y1506141I1664J1456D01*
G03X1147560Y1506273I-150J132D01*
G01Y1508216D01*
G03X1147510Y1508348I-200J0D01*
G02Y1511260I1664J1456D01*
G03X1147560Y1511392I-150J132D01*
G01Y1512014D01*
G02X1147763Y1512216I203J-1D01*
G01X1150584D01*
G02X1150786Y1512014I0J-202D01*
G01Y1511392D01*
G03X1150836Y1511260I200J0D01*
G02Y1508348I-1664J-1456D01*
G03X1150786Y1508216I150J-132D01*
G01Y1506273D01*
G03X1150836Y1506141I200J0D01*
G02Y1503229I-1664J-1456D01*
G03X1150786Y1503097I150J-132D01*
G01Y1502476D01*
G02X1150583Y1502274I-203J1D01*
G01X1147762D01*
G37*
G36*
G01X1650124D02*
G02X1649922Y1502476I0J202D01*
G01Y1503097D01*
G03X1649872Y1503229I-200J0D01*
G02Y1506141I1664J1456D01*
G03X1649922Y1506273I-150J132D01*
G01Y1508216D01*
G03X1649872Y1508348I-200J0D01*
G02Y1511260I1664J1456D01*
G03X1649922Y1511392I-150J132D01*
G01Y1512014D01*
G02X1650125Y1512216I203J-1D01*
G01X1652946D01*
G02X1653148Y1512014I0J-202D01*
G01Y1511392D01*
G03X1653198Y1511260I200J0D01*
G02Y1508348I-1664J-1456D01*
G03X1653148Y1508216I150J-132D01*
G01Y1506273D01*
G03X1653198Y1506141I200J0D01*
G02Y1503229I-1664J-1456D01*
G03X1653148Y1503097I150J-132D01*
G01Y1502476D01*
G02X1652945Y1502274I-203J1D01*
G01X1650124D01*
G37*
G36*
G01X307684Y1516546D02*
X310504D01*
G02X310706Y1516344I0J-202D01*
G01Y1515724D01*
G03X310756Y1515592I200J0D01*
G02Y1512676I-1661J-1458D01*
G03X310706Y1512544I150J-132D01*
G01Y1510606D01*
G03X310756Y1510474I200J0D01*
G02Y1507558I-1661J-1458D01*
G03X310706Y1507426I150J-132D01*
G01Y1506806D01*
G02X310504Y1506604I-202J0D01*
G01X307684D01*
G02X307482Y1506806I0J202D01*
G01Y1507426D01*
G03X307432Y1507558I-200J0D01*
G02Y1510474I1661J1458D01*
G03X307482Y1510606I-150J132D01*
G01Y1512544D01*
G03X307432Y1512676I-200J0D01*
G02Y1515592I1661J1458D01*
G03X307482Y1515724I-150J132D01*
G01Y1516344D01*
G02X307684Y1516546I202J0D01*
G37*
G36*
G01X342330D02*
X345150D01*
G02X345352Y1516344I0J-202D01*
G01Y1515724D01*
G03X345402Y1515592I200J0D01*
G02Y1512676I-1661J-1458D01*
G03X345352Y1512544I150J-132D01*
G01Y1510606D01*
G03X345402Y1510474I200J0D01*
G02Y1507558I-1661J-1458D01*
G03X345352Y1507426I150J-132D01*
G01Y1506806D01*
G02X345150Y1506604I-202J0D01*
G01X342330D01*
G02X342128Y1506806I0J202D01*
G01Y1507426D01*
G03X342078Y1507558I-200J0D01*
G02Y1510474I1661J1458D01*
G03X342128Y1510606I-150J132D01*
G01Y1512544D01*
G03X342078Y1512676I-200J0D01*
G02Y1515592I1661J1458D01*
G03X342128Y1515724I-150J132D01*
G01Y1516344D01*
G02X342330Y1516546I202J0D01*
G37*
G36*
G01X636818D02*
X639638D01*
G02X639840Y1516344I0J-202D01*
G01Y1515724D01*
G03X639890Y1515592I200J0D01*
G02Y1512676I-1661J-1458D01*
G03X639840Y1512544I150J-132D01*
G01Y1510606D01*
G03X639890Y1510474I200J0D01*
G02Y1507558I-1661J-1458D01*
G03X639840Y1507426I150J-132D01*
G01Y1506806D01*
G02X639638Y1506604I-202J0D01*
G01X636818D01*
G02X636616Y1506806I0J202D01*
G01Y1507426D01*
G03X636566Y1507558I-200J0D01*
G02Y1510474I1661J1458D01*
G03X636616Y1510606I-150J132D01*
G01Y1512544D01*
G03X636566Y1512676I-200J0D01*
G02Y1515592I1661J1458D01*
G03X636616Y1515724I-150J132D01*
G01Y1516344D01*
G02X636818Y1516546I202J0D01*
G37*
G36*
G01X1156424D02*
X1159244D01*
G02X1159446Y1516344I0J-202D01*
G01Y1515724D01*
G03X1159496Y1515592I200J0D01*
G02Y1512676I-1661J-1458D01*
G03X1159446Y1512544I150J-132D01*
G01Y1510606D01*
G03X1159496Y1510474I200J0D01*
G02Y1507558I-1661J-1458D01*
G03X1159446Y1507426I150J-132D01*
G01Y1506806D01*
G02X1159244Y1506604I-202J0D01*
G01X1156424D01*
G02X1156222Y1506806I0J202D01*
G01Y1507426D01*
G03X1156172Y1507558I-200J0D01*
G02Y1510474I1661J1458D01*
G03X1156222Y1510606I-150J132D01*
G01Y1512544D01*
G03X1156172Y1512676I-200J0D01*
G02Y1515592I1661J1458D01*
G03X1156222Y1515724I-150J132D01*
G01Y1516344D01*
G02X1156424Y1516546I202J0D01*
G37*
G36*
G01X1658786D02*
X1661606D01*
G02X1661808Y1516344I0J-202D01*
G01Y1515724D01*
G03X1661858Y1515592I200J0D01*
G02Y1512676I-1661J-1458D01*
G03X1661808Y1512544I150J-132D01*
G01Y1510606D01*
G03X1661858Y1510474I200J0D01*
G02Y1507558I-1661J-1458D01*
G03X1661808Y1507426I150J-132D01*
G01Y1506806D01*
G02X1661606Y1506604I-202J0D01*
G01X1658786D01*
G02X1658584Y1506806I0J202D01*
G01Y1507426D01*
G03X1658534Y1507558I-200J0D01*
G02Y1510474I1661J1458D01*
G03X1658584Y1510606I-150J132D01*
G01Y1512544D01*
G03X1658534Y1512676I-200J0D01*
G02Y1515592I1661J1458D01*
G03X1658584Y1515724I-150J132D01*
G01Y1516344D01*
G02X1658786Y1516546I202J0D01*
G37*
G36*
G01X117132Y1506604D02*
G02X116930Y1506806I0J202D01*
G01Y1507428D01*
G03X116880Y1507560I-200J0D01*
G02Y1510472I1664J1456D01*
G03X116930Y1510604I-150J132D01*
G01Y1512546D01*
G03X116880Y1512678I-200J0D01*
G02Y1515590I1664J1456D01*
G03X116930Y1515722I-150J132D01*
G01Y1516344D01*
G02X117133Y1516546I203J-1D01*
G01X119954D01*
G02X120156Y1516344I0J-202D01*
G01Y1515722D01*
G03X120206Y1515590I200J0D01*
G02Y1512678I-1664J-1456D01*
G03X120156Y1512546I150J-132D01*
G01Y1510604D01*
G03X120206Y1510472I200J0D01*
G02Y1507560I-1664J-1456D01*
G03X120156Y1507428I150J-132D01*
G01Y1506806D01*
G02X119953Y1506604I-203J1D01*
G01X117132D01*
G37*
G36*
G01X325006D02*
G02X324804Y1506806I0J202D01*
G01Y1507428D01*
G03X324754Y1507560I-200J0D01*
G02Y1510472I1664J1456D01*
G03X324804Y1510604I-150J132D01*
G01Y1512546D01*
G03X324754Y1512678I-200J0D01*
G02Y1515590I1664J1456D01*
G03X324804Y1515722I-150J132D01*
G01Y1516344D01*
G02X325007Y1516546I203J-1D01*
G01X327828D01*
G02X328030Y1516344I0J-202D01*
G01Y1515722D01*
G03X328080Y1515590I200J0D01*
G02Y1512678I-1664J-1456D01*
G03X328030Y1512546I150J-132D01*
G01Y1510604D01*
G03X328080Y1510472I200J0D01*
G02Y1507560I-1664J-1456D01*
G03X328030Y1507428I150J-132D01*
G01Y1506806D01*
G02X327827Y1506604I-203J1D01*
G01X325006D01*
G37*
G36*
G01X1139100D02*
G02X1138898Y1506806I0J202D01*
G01Y1507428D01*
G03X1138848Y1507560I-200J0D01*
G02Y1510472I1664J1456D01*
G03X1138898Y1510604I-150J132D01*
G01Y1512546D01*
G03X1138848Y1512678I-200J0D01*
G02Y1515590I1664J1456D01*
G03X1138898Y1515722I-150J132D01*
G01Y1516344D01*
G02X1139101Y1516546I203J-1D01*
G01X1141922D01*
G02X1142124Y1516344I0J-202D01*
G01Y1515722D01*
G03X1142174Y1515590I200J0D01*
G02Y1512678I-1664J-1456D01*
G03X1142124Y1512546I150J-132D01*
G01Y1510604D01*
G03X1142174Y1510472I200J0D01*
G02Y1507560I-1664J-1456D01*
G03X1142124Y1507428I150J-132D01*
G01Y1506806D01*
G02X1141921Y1506604I-203J1D01*
G01X1139100D01*
G37*
G36*
G01X1676108D02*
G02X1675906Y1506806I0J202D01*
G01Y1507428D01*
G03X1675856Y1507560I-200J0D01*
G02Y1510472I1664J1456D01*
G03X1675906Y1510604I-150J132D01*
G01Y1512546D01*
G03X1675856Y1512678I-200J0D01*
G02Y1515590I1664J1456D01*
G03X1675906Y1515722I-150J132D01*
G01Y1516344D01*
G02X1676109Y1516546I203J-1D01*
G01X1678930D01*
G02X1679132Y1516344I0J-202D01*
G01Y1515722D01*
G03X1679182Y1515590I200J0D01*
G02Y1512678I-1664J-1456D01*
G03X1679132Y1512546I150J-132D01*
G01Y1510604D01*
G03X1679182Y1510472I200J0D01*
G02Y1507560I-1664J-1456D01*
G03X1679132Y1507428I150J-132D01*
G01Y1506806D01*
G02X1678929Y1506604I-203J1D01*
G01X1676108D01*
G37*
G36*
G01X454929Y1568516D02*
X457749D01*
G02X457952Y1568313I0J-203D01*
G01Y1567691D01*
G03X458002Y1567559I200J0D01*
G02Y1564647I-1664J-1456D01*
G03X457952Y1564515I150J-132D01*
G01Y1562573D01*
G03X458002Y1562441I200J0D01*
G02Y1559529I-1664J-1456D01*
G03X457952Y1559397I150J-132D01*
G01Y1558775D01*
G02X457749Y1558572I-203J0D01*
G01X454929D01*
G02X454726Y1558775I0J203D01*
G01Y1559397D01*
G03X454676Y1559529I-200J0D01*
G02Y1562441I1664J1456D01*
G03X454726Y1562573I-150J132D01*
G01Y1564515D01*
G03X454676Y1564647I-200J0D01*
G02Y1567559I1664J1456D01*
G03X454726Y1567691I-150J132D01*
G01Y1568313D01*
G02X454929Y1568516I203J0D01*
G37*
G36*
G01X475274Y1558774D02*
G02X475072Y1558572I-202J0D01*
G01X472252D01*
G02X472050Y1558775I1J203D01*
G01Y1559395D01*
G03X472000Y1559527I-200J0D01*
G02Y1562443I1661J1458D01*
G03X472050Y1562575I-150J132D01*
G01Y1564513D01*
G03X472000Y1564645I-200J0D01*
G02Y1567561I1661J1458D01*
G03X472050Y1567693I-150J132D01*
G01Y1568314D01*
G02X472252Y1568516I202J0D01*
G01X475072D01*
G02X475274Y1568313I-1J-203D01*
G01Y1567693D01*
G03X475324Y1567561I200J0D01*
G02Y1564645I-1661J-1458D01*
G03X475274Y1564513I150J-132D01*
G01Y1562575D01*
G03X475324Y1562443I200J0D01*
G02Y1559527I-1661J-1458D01*
G03X475274Y1559395I150J-132D01*
G01Y1558774D01*
G37*
G36*
G01X489575Y1568516D02*
X492395D01*
G02X492598Y1568313I0J-203D01*
G01Y1567691D01*
G03X492648Y1567559I200J0D01*
G02Y1564647I-1664J-1456D01*
G03X492598Y1564515I150J-132D01*
G01Y1562573D01*
G03X492648Y1562441I200J0D01*
G02Y1559529I-1664J-1456D01*
G03X492598Y1559397I150J-132D01*
G01Y1558775D01*
G02X492395Y1558572I-203J0D01*
G01X489575D01*
G02X489372Y1558775I0J203D01*
G01Y1559397D01*
G03X489322Y1559529I-200J0D01*
G02Y1562441I1664J1456D01*
G03X489372Y1562573I-150J132D01*
G01Y1564515D01*
G03X489322Y1564647I-200J0D01*
G02Y1567559I1664J1456D01*
G03X489372Y1567691I-150J132D01*
G01Y1568313D01*
G02X489575Y1568516I203J0D01*
G37*
G36*
G01X506897D02*
X509717D01*
G02X509920Y1568313I0J-203D01*
G01Y1567691D01*
G03X509970Y1567559I200J0D01*
G02Y1564647I-1664J-1456D01*
G03X509920Y1564515I150J-132D01*
G01Y1562573D01*
G03X509970Y1562441I200J0D01*
G02Y1559529I-1664J-1456D01*
G03X509920Y1559397I150J-132D01*
G01Y1558775D01*
G02X509717Y1558572I-203J0D01*
G01X506897D01*
G02X506694Y1558775I0J203D01*
G01Y1559397D01*
G03X506644Y1559529I-200J0D01*
G02Y1562441I1664J1456D01*
G03X506694Y1562573I-150J132D01*
G01Y1564515D01*
G03X506644Y1564647I-200J0D01*
G02Y1567559I1664J1456D01*
G03X506694Y1567691I-150J132D01*
G01Y1568313D01*
G02X506897Y1568516I203J0D01*
G37*
G36*
G01X1497242Y1558774D02*
G02X1497040Y1558572I-202J0D01*
G01X1494220D01*
G02X1494018Y1558775I1J203D01*
G01Y1559395D01*
G03X1493968Y1559527I-200J0D01*
G02Y1562443I1661J1458D01*
G03X1494018Y1562575I-150J132D01*
G01Y1564513D01*
G03X1493968Y1564645I-200J0D01*
G02Y1567561I1661J1458D01*
G03X1494018Y1567693I-150J132D01*
G01Y1568314D01*
G02X1494220Y1568516I202J0D01*
G01X1497040D01*
G02X1497242Y1568313I-1J-203D01*
G01Y1567693D01*
G03X1497292Y1567561I200J0D01*
G02Y1564645I-1661J-1458D01*
G03X1497242Y1564513I150J-132D01*
G01Y1562575D01*
G03X1497292Y1562443I200J0D01*
G02Y1559527I-1661J-1458D01*
G03X1497242Y1559395I150J-132D01*
G01Y1558774D01*
G37*
G36*
G01X1511543Y1568516D02*
X1514363D01*
G02X1514566Y1568313I0J-203D01*
G01Y1567691D01*
G03X1514616Y1567559I200J0D01*
G02Y1564647I-1664J-1456D01*
G03X1514566Y1564515I150J-132D01*
G01Y1562573D01*
G03X1514616Y1562441I200J0D01*
G02Y1559529I-1664J-1456D01*
G03X1514566Y1559397I150J-132D01*
G01Y1558775D01*
G02X1514363Y1558572I-203J0D01*
G01X1511543D01*
G02X1511340Y1558775I0J203D01*
G01Y1559397D01*
G03X1511290Y1559529I-200J0D01*
G02Y1562441I1664J1456D01*
G03X1511340Y1562573I-150J132D01*
G01Y1564515D01*
G03X1511290Y1564647I-200J0D01*
G02Y1567559I1664J1456D01*
G03X1511340Y1567691I-150J132D01*
G01Y1568313D01*
G02X1511543Y1568516I203J0D01*
G37*
G36*
G01X1528865D02*
X1531685D01*
G02X1531888Y1568313I0J-203D01*
G01Y1567691D01*
G03X1531938Y1567559I200J0D01*
G02Y1564647I-1664J-1456D01*
G03X1531888Y1564515I150J-132D01*
G01Y1562573D01*
G03X1531938Y1562441I200J0D01*
G02Y1559529I-1664J-1456D01*
G03X1531888Y1559397I150J-132D01*
G01Y1558775D01*
G02X1531685Y1558572I-203J0D01*
G01X1528865D01*
G02X1528662Y1558775I0J203D01*
G01Y1559397D01*
G03X1528612Y1559529I-200J0D01*
G02Y1562441I1664J1456D01*
G03X1528662Y1562573I-150J132D01*
G01Y1564515D01*
G03X1528612Y1564647I-200J0D01*
G02Y1567559I1664J1456D01*
G03X1528662Y1567691I-150J132D01*
G01Y1568313D01*
G02X1528865Y1568516I203J0D01*
G37*
G36*
G01X463590Y1572846D02*
X466410D01*
G02X466612Y1572644I0J-202D01*
G01Y1572024D01*
G03X466662Y1571892I200J0D01*
G02Y1568976I-1661J-1458D01*
G03X466612Y1568844I150J-132D01*
G01Y1566905D01*
G03X466662Y1566773I200J0D01*
G02Y1563857I-1661J-1458D01*
G03X466612Y1563725I150J-132D01*
G01Y1563106D01*
G02X466410Y1562904I-202J0D01*
G01X463590D01*
G02X463388Y1563106I0J202D01*
G01Y1563725D01*
G03X463338Y1563857I-200J0D01*
G02Y1566773I1661J1458D01*
G03X463388Y1566905I-150J132D01*
G01Y1568844D01*
G03X463338Y1568976I-200J0D01*
G02Y1571892I1661J1458D01*
G03X463388Y1572024I-150J132D01*
G01Y1572644D01*
G02X463590Y1572846I202J0D01*
G37*
G36*
G01X498236D02*
X501056D01*
G02X501258Y1572644I0J-202D01*
G01Y1572024D01*
G03X501308Y1571892I200J0D01*
G02Y1568976I-1661J-1458D01*
G03X501258Y1568844I150J-132D01*
G01Y1566905D01*
G03X501308Y1566773I200J0D01*
G02Y1563857I-1661J-1458D01*
G03X501258Y1563725I150J-132D01*
G01Y1563106D01*
G02X501056Y1562904I-202J0D01*
G01X498236D01*
G02X498034Y1563106I0J202D01*
G01Y1563725D01*
G03X497984Y1563857I-200J0D01*
G02Y1566773I1661J1458D01*
G03X498034Y1566905I-150J132D01*
G01Y1568844D01*
G03X497984Y1568976I-200J0D01*
G02Y1571892I1661J1458D01*
G03X498034Y1572024I-150J132D01*
G01Y1572644D01*
G02X498236Y1572846I202J0D01*
G37*
G36*
G01X1485558D02*
X1488378D01*
G02X1488580Y1572644I0J-202D01*
G01Y1572024D01*
G03X1488630Y1571892I200J0D01*
G02Y1568976I-1661J-1458D01*
G03X1488580Y1568844I150J-132D01*
G01Y1566905D01*
G03X1488630Y1566773I200J0D01*
G02Y1563857I-1661J-1458D01*
G03X1488580Y1563725I150J-132D01*
G01Y1563106D01*
G02X1488378Y1562904I-202J0D01*
G01X1485558D01*
G02X1485356Y1563106I0J202D01*
G01Y1563725D01*
G03X1485306Y1563857I-200J0D01*
G02Y1566773I1661J1458D01*
G03X1485356Y1566905I-150J132D01*
G01Y1568844D01*
G03X1485306Y1568976I-200J0D01*
G02Y1571892I1661J1458D01*
G03X1485356Y1572024I-150J132D01*
G01Y1572644D01*
G02X1485558Y1572846I202J0D01*
G37*
G36*
G01X1520204D02*
X1523024D01*
G02X1523226Y1572644I0J-202D01*
G01Y1572024D01*
G03X1523276Y1571892I200J0D01*
G02Y1568976I-1661J-1458D01*
G03X1523226Y1568844I150J-132D01*
G01Y1566905D01*
G03X1523276Y1566773I200J0D01*
G02Y1563857I-1661J-1458D01*
G03X1523226Y1563725I150J-132D01*
G01Y1563106D01*
G02X1523024Y1562904I-202J0D01*
G01X1520204D01*
G02X1520002Y1563106I0J202D01*
G01Y1563725D01*
G03X1519952Y1563857I-200J0D01*
G02Y1566773I1661J1458D01*
G03X1520002Y1566905I-150J132D01*
G01Y1568844D01*
G03X1519952Y1568976I-200J0D01*
G02Y1571892I1661J1458D01*
G03X1520002Y1572024I-150J132D01*
G01Y1572644D01*
G02X1520204Y1572846I202J0D01*
G37*
G36*
G01X480912Y1562904D02*
G02X480710Y1563106I0J202D01*
G01Y1563727D01*
G03X480660Y1563859I-200J0D01*
G02Y1566771I1664J1456D01*
G03X480710Y1566903I-150J132D01*
G01Y1568846D01*
G03X480660Y1568978I-200J0D01*
G02Y1571890I1664J1456D01*
G03X480710Y1572022I-150J132D01*
G01Y1572644D01*
G02X480913Y1572846I203J-1D01*
G01X483734D01*
G02X483936Y1572644I0J-202D01*
G01Y1572022D01*
G03X483986Y1571890I200J0D01*
G02Y1568978I-1664J-1456D01*
G03X483936Y1568846I150J-132D01*
G01Y1566903D01*
G03X483986Y1566771I200J0D01*
G02Y1563859I-1664J-1456D01*
G03X483936Y1563727I150J-132D01*
G01Y1563106D01*
G02X483733Y1562904I-203J1D01*
G01X480912D01*
G37*
G36*
G01X1502880D02*
G02X1502678Y1563106I0J202D01*
G01Y1563727D01*
G03X1502628Y1563859I-200J0D01*
G02Y1566771I1664J1456D01*
G03X1502678Y1566903I-150J132D01*
G01Y1568846D01*
G03X1502628Y1568978I-200J0D01*
G02Y1571890I1664J1456D01*
G03X1502678Y1572022I-150J132D01*
G01Y1572644D01*
G02X1502881Y1572846I203J-1D01*
G01X1505702D01*
G02X1505904Y1572644I0J-202D01*
G01Y1572022D01*
G03X1505954Y1571890I200J0D01*
G02Y1568978I-1664J-1456D01*
G03X1505904Y1568846I150J-132D01*
G01Y1566903D01*
G03X1505954Y1566771I200J0D01*
G02Y1563859I-1664J-1456D01*
G03X1505904Y1563727I150J-132D01*
G01Y1563106D01*
G02X1505701Y1562904I-203J1D01*
G01X1502880D01*
G37*
G36*
G01X1537526D02*
G02X1537324Y1563106I0J202D01*
G01Y1563727D01*
G03X1537274Y1563859I-200J0D01*
G02Y1566771I1664J1456D01*
G03X1537324Y1566903I-150J132D01*
G01Y1568846D01*
G03X1537274Y1568978I-200J0D01*
G02Y1571890I1664J1456D01*
G03X1537324Y1572022I-150J132D01*
G01Y1572644D01*
G02X1537527Y1572846I203J-1D01*
G01X1540348D01*
G02X1540550Y1572644I0J-202D01*
G01Y1572022D01*
G03X1540600Y1571890I200J0D01*
G02Y1568978I-1664J-1456D01*
G03X1540550Y1568846I150J-132D01*
G01Y1566903D01*
G03X1540600Y1566771I200J0D01*
G02Y1563859I-1664J-1456D01*
G03X1540550Y1563727I150J-132D01*
G01Y1563106D01*
G02X1540347Y1562904I-203J1D01*
G01X1537526D01*
G37*
G36*
G01X454929Y1583870D02*
X457749D01*
G02X457952Y1583667I0J-203D01*
G01Y1583045D01*
G03X458002Y1582913I200J0D01*
G02Y1580001I-1664J-1456D01*
G03X457952Y1579869I150J-132D01*
G01Y1577927D01*
G03X458002Y1577795I200J0D01*
G02Y1574883I-1664J-1456D01*
G03X457952Y1574751I150J-132D01*
G01Y1574129D01*
G02X457749Y1573926I-203J0D01*
G01X454929D01*
G02X454726Y1574129I0J203D01*
G01Y1574751D01*
G03X454676Y1574883I-200J0D01*
G02Y1577795I1664J1456D01*
G03X454726Y1577927I-150J132D01*
G01Y1579869D01*
G03X454676Y1580001I-200J0D01*
G02Y1582913I1664J1456D01*
G03X454726Y1583045I-150J132D01*
G01Y1583667D01*
G02X454929Y1583870I203J0D01*
G37*
G36*
G01X475274Y1574128D02*
G02X475072Y1573926I-202J0D01*
G01X472252D01*
G02X472050Y1574129I1J203D01*
G01Y1574749D01*
G03X472000Y1574881I-200J0D01*
G02Y1577797I1661J1458D01*
G03X472050Y1577929I-150J132D01*
G01Y1579867D01*
G03X472000Y1579999I-200J0D01*
G02Y1582915I1661J1458D01*
G03X472050Y1583047I-150J132D01*
G01Y1583668D01*
G02X472252Y1583870I202J0D01*
G01X475072D01*
G02X475274Y1583667I-1J-203D01*
G01Y1583047D01*
G03X475324Y1582915I200J0D01*
G02Y1579999I-1661J-1458D01*
G03X475274Y1579867I150J-132D01*
G01Y1577929D01*
G03X475324Y1577797I200J0D01*
G02Y1574881I-1661J-1458D01*
G03X475274Y1574749I150J-132D01*
G01Y1574128D01*
G37*
G36*
G01X489575Y1583870D02*
X492395D01*
G02X492598Y1583667I0J-203D01*
G01Y1583045D01*
G03X492648Y1582913I200J0D01*
G02Y1580001I-1664J-1456D01*
G03X492598Y1579869I150J-132D01*
G01Y1577927D01*
G03X492648Y1577795I200J0D01*
G02Y1574883I-1664J-1456D01*
G03X492598Y1574751I150J-132D01*
G01Y1574129D01*
G02X492395Y1573926I-203J0D01*
G01X489575D01*
G02X489372Y1574129I0J203D01*
G01Y1574751D01*
G03X489322Y1574883I-200J0D01*
G02Y1577795I1664J1456D01*
G03X489372Y1577927I-150J132D01*
G01Y1579869D01*
G03X489322Y1580001I-200J0D01*
G02Y1582913I1664J1456D01*
G03X489372Y1583045I-150J132D01*
G01Y1583667D01*
G02X489575Y1583870I203J0D01*
G37*
G36*
G01X506897D02*
X509717D01*
G02X509920Y1583667I0J-203D01*
G01Y1583045D01*
G03X509970Y1582913I200J0D01*
G02Y1580001I-1664J-1456D01*
G03X509920Y1579869I150J-132D01*
G01Y1577927D01*
G03X509970Y1577795I200J0D01*
G02Y1574883I-1664J-1456D01*
G03X509920Y1574751I150J-132D01*
G01Y1574129D01*
G02X509717Y1573926I-203J0D01*
G01X506897D01*
G02X506694Y1574129I0J203D01*
G01Y1574751D01*
G03X506644Y1574883I-200J0D01*
G02Y1577795I1664J1456D01*
G03X506694Y1577927I-150J132D01*
G01Y1579869D01*
G03X506644Y1580001I-200J0D01*
G02Y1582913I1664J1456D01*
G03X506694Y1583045I-150J132D01*
G01Y1583667D01*
G02X506897Y1583870I203J0D01*
G37*
G36*
G01X1497242Y1574128D02*
G02X1497040Y1573926I-202J0D01*
G01X1494220D01*
G02X1494018Y1574129I1J203D01*
G01Y1574749D01*
G03X1493968Y1574881I-200J0D01*
G02Y1577797I1661J1458D01*
G03X1494018Y1577929I-150J132D01*
G01Y1579867D01*
G03X1493968Y1579999I-200J0D01*
G02Y1582915I1661J1458D01*
G03X1494018Y1583047I-150J132D01*
G01Y1583668D01*
G02X1494220Y1583870I202J0D01*
G01X1497040D01*
G02X1497242Y1583667I-1J-203D01*
G01Y1583047D01*
G03X1497292Y1582915I200J0D01*
G02Y1579999I-1661J-1458D01*
G03X1497242Y1579867I150J-132D01*
G01Y1577929D01*
G03X1497292Y1577797I200J0D01*
G02Y1574881I-1661J-1458D01*
G03X1497242Y1574749I150J-132D01*
G01Y1574128D01*
G37*
G36*
G01X1511543Y1583870D02*
X1514363D01*
G02X1514566Y1583667I0J-203D01*
G01Y1583045D01*
G03X1514616Y1582913I200J0D01*
G02Y1580001I-1664J-1456D01*
G03X1514566Y1579869I150J-132D01*
G01Y1577927D01*
G03X1514616Y1577795I200J0D01*
G02Y1574883I-1664J-1456D01*
G03X1514566Y1574751I150J-132D01*
G01Y1574129D01*
G02X1514363Y1573926I-203J0D01*
G01X1511543D01*
G02X1511340Y1574129I0J203D01*
G01Y1574751D01*
G03X1511290Y1574883I-200J0D01*
G02Y1577795I1664J1456D01*
G03X1511340Y1577927I-150J132D01*
G01Y1579869D01*
G03X1511290Y1580001I-200J0D01*
G02Y1582913I1664J1456D01*
G03X1511340Y1583045I-150J132D01*
G01Y1583667D01*
G02X1511543Y1583870I203J0D01*
G37*
G36*
G01X1528865D02*
X1531685D01*
G02X1531888Y1583667I0J-203D01*
G01Y1583045D01*
G03X1531938Y1582913I200J0D01*
G02Y1580001I-1664J-1456D01*
G03X1531888Y1579869I150J-132D01*
G01Y1577927D01*
G03X1531938Y1577795I200J0D01*
G02Y1574883I-1664J-1456D01*
G03X1531888Y1574751I150J-132D01*
G01Y1574129D01*
G02X1531685Y1573926I-203J0D01*
G01X1528865D01*
G02X1528662Y1574129I0J203D01*
G01Y1574751D01*
G03X1528612Y1574883I-200J0D01*
G02Y1577795I1664J1456D01*
G03X1528662Y1577927I-150J132D01*
G01Y1579869D01*
G03X1528612Y1580001I-200J0D01*
G02Y1582913I1664J1456D01*
G03X1528662Y1583045I-150J132D01*
G01Y1583667D01*
G02X1528865Y1583870I203J0D01*
G37*
G36*
G01X463590Y1588200D02*
X466410D01*
G02X466612Y1587998I0J-202D01*
G01Y1587378D01*
G03X466662Y1587246I200J0D01*
G02Y1584330I-1661J-1458D01*
G03X466612Y1584198I150J-132D01*
G01Y1582260D01*
G03X466662Y1582128I200J0D01*
G02Y1579212I-1661J-1458D01*
G03X466612Y1579080I150J-132D01*
G01Y1578460D01*
G02X466410Y1578258I-202J0D01*
G01X463590D01*
G02X463388Y1578460I0J202D01*
G01Y1579080D01*
G03X463338Y1579212I-200J0D01*
G02Y1582128I1661J1458D01*
G03X463388Y1582260I-150J132D01*
G01Y1584198D01*
G03X463338Y1584330I-200J0D01*
G02Y1587246I1661J1458D01*
G03X463388Y1587378I-150J132D01*
G01Y1587998D01*
G02X463590Y1588200I202J0D01*
G37*
G36*
G01X498236D02*
X501056D01*
G02X501258Y1587998I0J-202D01*
G01Y1587378D01*
G03X501308Y1587246I200J0D01*
G02Y1584330I-1661J-1458D01*
G03X501258Y1584198I150J-132D01*
G01Y1582260D01*
G03X501308Y1582128I200J0D01*
G02Y1579212I-1661J-1458D01*
G03X501258Y1579080I150J-132D01*
G01Y1578460D01*
G02X501056Y1578258I-202J0D01*
G01X498236D01*
G02X498034Y1578460I0J202D01*
G01Y1579080D01*
G03X497984Y1579212I-200J0D01*
G02Y1582128I1661J1458D01*
G03X498034Y1582260I-150J132D01*
G01Y1584198D01*
G03X497984Y1584330I-200J0D01*
G02Y1587246I1661J1458D01*
G03X498034Y1587378I-150J132D01*
G01Y1587998D01*
G02X498236Y1588200I202J0D01*
G37*
G36*
G01X1485558D02*
X1488378D01*
G02X1488580Y1587998I0J-202D01*
G01Y1587378D01*
G03X1488630Y1587246I200J0D01*
G02Y1584330I-1661J-1458D01*
G03X1488580Y1584198I150J-132D01*
G01Y1582260D01*
G03X1488630Y1582128I200J0D01*
G02Y1579212I-1661J-1458D01*
G03X1488580Y1579080I150J-132D01*
G01Y1578460D01*
G02X1488378Y1578258I-202J0D01*
G01X1485558D01*
G02X1485356Y1578460I0J202D01*
G01Y1579080D01*
G03X1485306Y1579212I-200J0D01*
G02Y1582128I1661J1458D01*
G03X1485356Y1582260I-150J132D01*
G01Y1584198D01*
G03X1485306Y1584330I-200J0D01*
G02Y1587246I1661J1458D01*
G03X1485356Y1587378I-150J132D01*
G01Y1587998D01*
G02X1485558Y1588200I202J0D01*
G37*
G36*
G01X1520204D02*
X1523024D01*
G02X1523226Y1587998I0J-202D01*
G01Y1587378D01*
G03X1523276Y1587246I200J0D01*
G02Y1584330I-1661J-1458D01*
G03X1523226Y1584198I150J-132D01*
G01Y1582260D01*
G03X1523276Y1582128I200J0D01*
G02Y1579212I-1661J-1458D01*
G03X1523226Y1579080I150J-132D01*
G01Y1578460D01*
G02X1523024Y1578258I-202J0D01*
G01X1520204D01*
G02X1520002Y1578460I0J202D01*
G01Y1579080D01*
G03X1519952Y1579212I-200J0D01*
G02Y1582128I1661J1458D01*
G03X1520002Y1582260I-150J132D01*
G01Y1584198D01*
G03X1519952Y1584330I-200J0D01*
G02Y1587246I1661J1458D01*
G03X1520002Y1587378I-150J132D01*
G01Y1587998D01*
G02X1520204Y1588200I202J0D01*
G37*
G36*
G01X480912Y1578258D02*
G02X480710Y1578460I0J202D01*
G01Y1579082D01*
G03X480660Y1579214I-200J0D01*
G02Y1582126I1664J1456D01*
G03X480710Y1582258I-150J132D01*
G01Y1584200D01*
G03X480660Y1584332I-200J0D01*
G02Y1587244I1664J1456D01*
G03X480710Y1587376I-150J132D01*
G01Y1587998D01*
G02X480913Y1588200I203J-1D01*
G01X483734D01*
G02X483936Y1587998I0J-202D01*
G01Y1587376D01*
G03X483986Y1587244I200J0D01*
G02Y1584332I-1664J-1456D01*
G03X483936Y1584200I150J-132D01*
G01Y1582258D01*
G03X483986Y1582126I200J0D01*
G02Y1579214I-1664J-1456D01*
G03X483936Y1579082I150J-132D01*
G01Y1578460D01*
G02X483733Y1578258I-203J1D01*
G01X480912D01*
G37*
G36*
G01X1502880D02*
G02X1502678Y1578460I0J202D01*
G01Y1579082D01*
G03X1502628Y1579214I-200J0D01*
G02Y1582126I1664J1456D01*
G03X1502678Y1582258I-150J132D01*
G01Y1584200D01*
G03X1502628Y1584332I-200J0D01*
G02Y1587244I1664J1456D01*
G03X1502678Y1587376I-150J132D01*
G01Y1587998D01*
G02X1502881Y1588200I203J-1D01*
G01X1505702D01*
G02X1505904Y1587998I0J-202D01*
G01Y1587376D01*
G03X1505954Y1587244I200J0D01*
G02Y1584332I-1664J-1456D01*
G03X1505904Y1584200I150J-132D01*
G01Y1582258D01*
G03X1505954Y1582126I200J0D01*
G02Y1579214I-1664J-1456D01*
G03X1505904Y1579082I150J-132D01*
G01Y1578460D01*
G02X1505701Y1578258I-203J1D01*
G01X1502880D01*
G37*
G36*
G01X1537526D02*
G02X1537324Y1578460I0J202D01*
G01Y1579082D01*
G03X1537274Y1579214I-200J0D01*
G02Y1582126I1664J1456D01*
G03X1537324Y1582258I-150J132D01*
G01Y1584200D01*
G03X1537274Y1584332I-200J0D01*
G02Y1587244I1664J1456D01*
G03X1537324Y1587376I-150J132D01*
G01Y1587998D01*
G02X1537527Y1588200I203J-1D01*
G01X1540348D01*
G02X1540550Y1587998I0J-202D01*
G01Y1587376D01*
G03X1540600Y1587244I200J0D01*
G02Y1584332I-1664J-1456D01*
G03X1540550Y1584200I150J-132D01*
G01Y1582258D01*
G03X1540600Y1582126I200J0D01*
G02Y1579214I-1664J-1456D01*
G03X1540550Y1579082I150J-132D01*
G01Y1578460D01*
G02X1540347Y1578258I-203J1D01*
G01X1537526D01*
G37*
G36*
G01X454929Y1599224D02*
X457749D01*
G02X457952Y1599021I0J-203D01*
G01Y1598399D01*
G03X458002Y1598267I200J0D01*
G02Y1595355I-1664J-1456D01*
G03X457952Y1595223I150J-132D01*
G01Y1593281D01*
G03X458002Y1593149I200J0D01*
G02Y1590237I-1664J-1456D01*
G03X457952Y1590105I150J-132D01*
G01Y1589483D01*
G02X457749Y1589280I-203J0D01*
G01X454929D01*
G02X454726Y1589483I0J203D01*
G01Y1590105D01*
G03X454676Y1590237I-200J0D01*
G02Y1593149I1664J1456D01*
G03X454726Y1593281I-150J132D01*
G01Y1595223D01*
G03X454676Y1595355I-200J0D01*
G02Y1598267I1664J1456D01*
G03X454726Y1598399I-150J132D01*
G01Y1599021D01*
G02X454929Y1599224I203J0D01*
G37*
G36*
G01X475274Y1589482D02*
G02X475072Y1589280I-202J0D01*
G01X472252D01*
G02X472050Y1589483I1J203D01*
G01Y1590103D01*
G03X472000Y1590235I-200J0D01*
G02Y1593151I1661J1458D01*
G03X472050Y1593283I-150J132D01*
G01Y1595221D01*
G03X472000Y1595353I-200J0D01*
G02Y1598269I1661J1458D01*
G03X472050Y1598401I-150J132D01*
G01Y1599022D01*
G02X472252Y1599224I202J0D01*
G01X475072D01*
G02X475274Y1599021I-1J-203D01*
G01Y1598401D01*
G03X475324Y1598269I200J0D01*
G02Y1595353I-1661J-1458D01*
G03X475274Y1595221I150J-132D01*
G01Y1593283D01*
G03X475324Y1593151I200J0D01*
G02Y1590235I-1661J-1458D01*
G03X475274Y1590103I150J-132D01*
G01Y1589482D01*
G37*
G36*
G01X489575Y1599224D02*
X492395D01*
G02X492598Y1599021I0J-203D01*
G01Y1598399D01*
G03X492648Y1598267I200J0D01*
G02Y1595355I-1664J-1456D01*
G03X492598Y1595223I150J-132D01*
G01Y1593281D01*
G03X492648Y1593149I200J0D01*
G02Y1590237I-1664J-1456D01*
G03X492598Y1590105I150J-132D01*
G01Y1589483D01*
G02X492395Y1589280I-203J0D01*
G01X489575D01*
G02X489372Y1589483I0J203D01*
G01Y1590105D01*
G03X489322Y1590237I-200J0D01*
G02Y1593149I1664J1456D01*
G03X489372Y1593281I-150J132D01*
G01Y1595223D01*
G03X489322Y1595355I-200J0D01*
G02Y1598267I1664J1456D01*
G03X489372Y1598399I-150J132D01*
G01Y1599021D01*
G02X489575Y1599224I203J0D01*
G37*
G36*
G01X506897D02*
X509717D01*
G02X509920Y1599021I0J-203D01*
G01Y1598399D01*
G03X509970Y1598267I200J0D01*
G02Y1595355I-1664J-1456D01*
G03X509920Y1595223I150J-132D01*
G01Y1593281D01*
G03X509970Y1593149I200J0D01*
G02Y1590237I-1664J-1456D01*
G03X509920Y1590105I150J-132D01*
G01Y1589483D01*
G02X509717Y1589280I-203J0D01*
G01X506897D01*
G02X506694Y1589483I0J203D01*
G01Y1590105D01*
G03X506644Y1590237I-200J0D01*
G02Y1593149I1664J1456D01*
G03X506694Y1593281I-150J132D01*
G01Y1595223D01*
G03X506644Y1595355I-200J0D01*
G02Y1598267I1664J1456D01*
G03X506694Y1598399I-150J132D01*
G01Y1599021D01*
G02X506897Y1599224I203J0D01*
G37*
G36*
G01X1497242Y1589482D02*
G02X1497040Y1589280I-202J0D01*
G01X1494220D01*
G02X1494018Y1589483I1J203D01*
G01Y1590103D01*
G03X1493968Y1590235I-200J0D01*
G02Y1593151I1661J1458D01*
G03X1494018Y1593283I-150J132D01*
G01Y1595221D01*
G03X1493968Y1595353I-200J0D01*
G02Y1598269I1661J1458D01*
G03X1494018Y1598401I-150J132D01*
G01Y1599022D01*
G02X1494220Y1599224I202J0D01*
G01X1497040D01*
G02X1497242Y1599021I-1J-203D01*
G01Y1598401D01*
G03X1497292Y1598269I200J0D01*
G02Y1595353I-1661J-1458D01*
G03X1497242Y1595221I150J-132D01*
G01Y1593283D01*
G03X1497292Y1593151I200J0D01*
G02Y1590235I-1661J-1458D01*
G03X1497242Y1590103I150J-132D01*
G01Y1589482D01*
G37*
G36*
G01X1511543Y1599224D02*
X1514363D01*
G02X1514566Y1599021I0J-203D01*
G01Y1598399D01*
G03X1514616Y1598267I200J0D01*
G02Y1595355I-1664J-1456D01*
G03X1514566Y1595223I150J-132D01*
G01Y1593281D01*
G03X1514616Y1593149I200J0D01*
G02Y1590237I-1664J-1456D01*
G03X1514566Y1590105I150J-132D01*
G01Y1589483D01*
G02X1514363Y1589280I-203J0D01*
G01X1511543D01*
G02X1511340Y1589483I0J203D01*
G01Y1590105D01*
G03X1511290Y1590237I-200J0D01*
G02Y1593149I1664J1456D01*
G03X1511340Y1593281I-150J132D01*
G01Y1595223D01*
G03X1511290Y1595355I-200J0D01*
G02Y1598267I1664J1456D01*
G03X1511340Y1598399I-150J132D01*
G01Y1599021D01*
G02X1511543Y1599224I203J0D01*
G37*
G36*
G01X1528865D02*
X1531685D01*
G02X1531888Y1599021I0J-203D01*
G01Y1598399D01*
G03X1531938Y1598267I200J0D01*
G02Y1595355I-1664J-1456D01*
G03X1531888Y1595223I150J-132D01*
G01Y1593281D01*
G03X1531938Y1593149I200J0D01*
G02Y1590237I-1664J-1456D01*
G03X1531888Y1590105I150J-132D01*
G01Y1589483D01*
G02X1531685Y1589280I-203J0D01*
G01X1528865D01*
G02X1528662Y1589483I0J203D01*
G01Y1590105D01*
G03X1528612Y1590237I-200J0D01*
G02Y1593149I1664J1456D01*
G03X1528662Y1593281I-150J132D01*
G01Y1595223D01*
G03X1528612Y1595355I-200J0D01*
G02Y1598267I1664J1456D01*
G03X1528662Y1598399I-150J132D01*
G01Y1599021D01*
G02X1528865Y1599224I203J0D01*
G37*
G36*
G01X463590Y1603554D02*
X466410D01*
G02X466612Y1603352I0J-202D01*
G01Y1602732D01*
G03X466662Y1602600I200J0D01*
G02Y1599684I-1661J-1458D01*
G03X466612Y1599552I150J-132D01*
G01Y1597614D01*
G03X466662Y1597482I200J0D01*
G02Y1594566I-1661J-1458D01*
G03X466612Y1594434I150J-132D01*
G01Y1593814D01*
G02X466410Y1593612I-202J0D01*
G01X463590D01*
G02X463388Y1593814I0J202D01*
G01Y1594434D01*
G03X463338Y1594566I-200J0D01*
G02Y1597482I1661J1458D01*
G03X463388Y1597614I-150J132D01*
G01Y1599552D01*
G03X463338Y1599684I-200J0D01*
G02Y1602600I1661J1458D01*
G03X463388Y1602732I-150J132D01*
G01Y1603352D01*
G02X463590Y1603554I202J0D01*
G37*
G36*
G01X498236D02*
X501056D01*
G02X501258Y1603352I0J-202D01*
G01Y1602732D01*
G03X501308Y1602600I200J0D01*
G02Y1599684I-1661J-1458D01*
G03X501258Y1599552I150J-132D01*
G01Y1597614D01*
G03X501308Y1597482I200J0D01*
G02Y1594566I-1661J-1458D01*
G03X501258Y1594434I150J-132D01*
G01Y1593814D01*
G02X501056Y1593612I-202J0D01*
G01X498236D01*
G02X498034Y1593814I0J202D01*
G01Y1594434D01*
G03X497984Y1594566I-200J0D01*
G02Y1597482I1661J1458D01*
G03X498034Y1597614I-150J132D01*
G01Y1599552D01*
G03X497984Y1599684I-200J0D01*
G02Y1602600I1661J1458D01*
G03X498034Y1602732I-150J132D01*
G01Y1603352D01*
G02X498236Y1603554I202J0D01*
G37*
G36*
G01X1485558D02*
X1488378D01*
G02X1488580Y1603352I0J-202D01*
G01Y1602732D01*
G03X1488630Y1602600I200J0D01*
G02Y1599684I-1661J-1458D01*
G03X1488580Y1599552I150J-132D01*
G01Y1597614D01*
G03X1488630Y1597482I200J0D01*
G02Y1594566I-1661J-1458D01*
G03X1488580Y1594434I150J-132D01*
G01Y1593814D01*
G02X1488378Y1593612I-202J0D01*
G01X1485558D01*
G02X1485356Y1593814I0J202D01*
G01Y1594434D01*
G03X1485306Y1594566I-200J0D01*
G02Y1597482I1661J1458D01*
G03X1485356Y1597614I-150J132D01*
G01Y1599552D01*
G03X1485306Y1599684I-200J0D01*
G02Y1602600I1661J1458D01*
G03X1485356Y1602732I-150J132D01*
G01Y1603352D01*
G02X1485558Y1603554I202J0D01*
G37*
G36*
G01X1520204D02*
X1523024D01*
G02X1523226Y1603352I0J-202D01*
G01Y1602732D01*
G03X1523276Y1602600I200J0D01*
G02Y1599684I-1661J-1458D01*
G03X1523226Y1599552I150J-132D01*
G01Y1597614D01*
G03X1523276Y1597482I200J0D01*
G02Y1594566I-1661J-1458D01*
G03X1523226Y1594434I150J-132D01*
G01Y1593814D01*
G02X1523024Y1593612I-202J0D01*
G01X1520204D01*
G02X1520002Y1593814I0J202D01*
G01Y1594434D01*
G03X1519952Y1594566I-200J0D01*
G02Y1597482I1661J1458D01*
G03X1520002Y1597614I-150J132D01*
G01Y1599552D01*
G03X1519952Y1599684I-200J0D01*
G02Y1602600I1661J1458D01*
G03X1520002Y1602732I-150J132D01*
G01Y1603352D01*
G02X1520204Y1603554I202J0D01*
G37*
G36*
G01X480912Y1593612D02*
G02X480710Y1593814I0J202D01*
G01Y1594436D01*
G03X480660Y1594568I-200J0D01*
G02Y1597480I1664J1456D01*
G03X480710Y1597612I-150J132D01*
G01Y1599554D01*
G03X480660Y1599686I-200J0D01*
G02Y1602598I1664J1456D01*
G03X480710Y1602730I-150J132D01*
G01Y1603352D01*
G02X480913Y1603554I203J-1D01*
G01X483734D01*
G02X483936Y1603352I0J-202D01*
G01Y1602730D01*
G03X483986Y1602598I200J0D01*
G02Y1599686I-1664J-1456D01*
G03X483936Y1599554I150J-132D01*
G01Y1597612D01*
G03X483986Y1597480I200J0D01*
G02Y1594568I-1664J-1456D01*
G03X483936Y1594436I150J-132D01*
G01Y1593814D01*
G02X483733Y1593612I-203J1D01*
G01X480912D01*
G37*
G36*
G01X1502880D02*
G02X1502678Y1593814I0J202D01*
G01Y1594436D01*
G03X1502628Y1594568I-200J0D01*
G02Y1597480I1664J1456D01*
G03X1502678Y1597612I-150J132D01*
G01Y1599554D01*
G03X1502628Y1599686I-200J0D01*
G02Y1602598I1664J1456D01*
G03X1502678Y1602730I-150J132D01*
G01Y1603352D01*
G02X1502881Y1603554I203J-1D01*
G01X1505702D01*
G02X1505904Y1603352I0J-202D01*
G01Y1602730D01*
G03X1505954Y1602598I200J0D01*
G02Y1599686I-1664J-1456D01*
G03X1505904Y1599554I150J-132D01*
G01Y1597612D01*
G03X1505954Y1597480I200J0D01*
G02Y1594568I-1664J-1456D01*
G03X1505904Y1594436I150J-132D01*
G01Y1593814D01*
G02X1505701Y1593612I-203J1D01*
G01X1502880D01*
G37*
G36*
G01X1537526D02*
G02X1537324Y1593814I0J202D01*
G01Y1594436D01*
G03X1537274Y1594568I-200J0D01*
G02Y1597480I1664J1456D01*
G03X1537324Y1597612I-150J132D01*
G01Y1599554D01*
G03X1537274Y1599686I-200J0D01*
G02Y1602598I1664J1456D01*
G03X1537324Y1602730I-150J132D01*
G01Y1603352D01*
G02X1537527Y1603554I203J-1D01*
G01X1540348D01*
G02X1540550Y1603352I0J-202D01*
G01Y1602730D01*
G03X1540600Y1602598I200J0D01*
G02Y1599686I-1664J-1456D01*
G03X1540550Y1599554I150J-132D01*
G01Y1597612D01*
G03X1540600Y1597480I200J0D01*
G02Y1594568I-1664J-1456D01*
G03X1540550Y1594436I150J-132D01*
G01Y1593814D01*
G02X1540347Y1593612I-203J1D01*
G01X1537526D01*
G37*
G36*
G01X472252Y1614578D02*
X475072D01*
G02X475274Y1614376I0J-202D01*
G01Y1613756D01*
G03X475324Y1613624I200J0D01*
G02Y1610708I-1661J-1458D01*
G03X475274Y1610576I150J-132D01*
G01Y1608638D01*
G03X475324Y1608506I200J0D01*
G02Y1605590I-1661J-1458D01*
G03X475274Y1605458I150J-132D01*
G01Y1604838D01*
G02X475072Y1604636I-202J0D01*
G01X472252D01*
G02X472050Y1604838I0J202D01*
G01Y1605458D01*
G03X472000Y1605590I-200J0D01*
G02Y1608506I1661J1458D01*
G03X472050Y1608638I-150J132D01*
G01Y1610576D01*
G03X472000Y1610708I-200J0D01*
G02Y1613624I1661J1458D01*
G03X472050Y1613756I-150J132D01*
G01Y1614376D01*
G02X472252Y1614578I202J0D01*
G37*
G36*
G01X1494220D02*
X1497040D01*
G02X1497242Y1614376I0J-202D01*
G01Y1613756D01*
G03X1497292Y1613624I200J0D01*
G02Y1610708I-1661J-1458D01*
G03X1497242Y1610576I150J-132D01*
G01Y1608638D01*
G03X1497292Y1608506I200J0D01*
G02Y1605590I-1661J-1458D01*
G03X1497242Y1605458I150J-132D01*
G01Y1604838D01*
G02X1497040Y1604636I-202J0D01*
G01X1494220D01*
G02X1494018Y1604838I0J202D01*
G01Y1605458D01*
G03X1493968Y1605590I-200J0D01*
G02Y1608506I1661J1458D01*
G03X1494018Y1608638I-150J132D01*
G01Y1610576D01*
G03X1493968Y1610708I-200J0D01*
G02Y1613624I1661J1458D01*
G03X1494018Y1613756I-150J132D01*
G01Y1614376D01*
G02X1494220Y1614578I202J0D01*
G37*
G36*
G01X454928Y1604636D02*
G02X454726Y1604838I0J202D01*
G01Y1605460D01*
G03X454676Y1605592I-200J0D01*
G02Y1608504I1664J1456D01*
G03X454726Y1608636I-150J132D01*
G01Y1610578D01*
G03X454676Y1610710I-200J0D01*
G02Y1613622I1664J1456D01*
G03X454726Y1613754I-150J132D01*
G01Y1614376D01*
G02X454929Y1614578I203J-1D01*
G01X457750D01*
G02X457952Y1614376I0J-202D01*
G01Y1613754D01*
G03X458002Y1613622I200J0D01*
G02Y1610710I-1664J-1456D01*
G03X457952Y1610578I150J-132D01*
G01Y1608636D01*
G03X458002Y1608504I200J0D01*
G02Y1605592I-1664J-1456D01*
G03X457952Y1605460I150J-132D01*
G01Y1604838D01*
G02X457749Y1604636I-203J1D01*
G01X454928D01*
G37*
G36*
G01X489574D02*
G02X489372Y1604838I0J202D01*
G01Y1605460D01*
G03X489322Y1605592I-200J0D01*
G02Y1608504I1664J1456D01*
G03X489372Y1608636I-150J132D01*
G01Y1610578D01*
G03X489322Y1610710I-200J0D01*
G02Y1613622I1664J1456D01*
G03X489372Y1613754I-150J132D01*
G01Y1614376D01*
G02X489575Y1614578I203J-1D01*
G01X492396D01*
G02X492598Y1614376I0J-202D01*
G01Y1613754D01*
G03X492648Y1613622I200J0D01*
G02Y1610710I-1664J-1456D01*
G03X492598Y1610578I150J-132D01*
G01Y1608636D01*
G03X492648Y1608504I200J0D01*
G02Y1605592I-1664J-1456D01*
G03X492598Y1605460I150J-132D01*
G01Y1604838D01*
G02X492395Y1604636I-203J1D01*
G01X489574D01*
G37*
G36*
G01X506896D02*
G02X506694Y1604838I0J202D01*
G01Y1605460D01*
G03X506644Y1605592I-200J0D01*
G02Y1608504I1664J1456D01*
G03X506694Y1608636I-150J132D01*
G01Y1610578D01*
G03X506644Y1610710I-200J0D01*
G02Y1613622I1664J1456D01*
G03X506694Y1613754I-150J132D01*
G01Y1614376D01*
G02X506897Y1614578I203J-1D01*
G01X509718D01*
G02X509920Y1614376I0J-202D01*
G01Y1613754D01*
G03X509970Y1613622I200J0D01*
G02Y1610710I-1664J-1456D01*
G03X509920Y1610578I150J-132D01*
G01Y1608636D01*
G03X509970Y1608504I200J0D01*
G02Y1605592I-1664J-1456D01*
G03X509920Y1605460I150J-132D01*
G01Y1604838D01*
G02X509717Y1604636I-203J1D01*
G01X506896D01*
G37*
G36*
G01X1511542D02*
G02X1511340Y1604838I0J202D01*
G01Y1605460D01*
G03X1511290Y1605592I-200J0D01*
G02Y1608504I1664J1456D01*
G03X1511340Y1608636I-150J132D01*
G01Y1610578D01*
G03X1511290Y1610710I-200J0D01*
G02Y1613622I1664J1456D01*
G03X1511340Y1613754I-150J132D01*
G01Y1614376D01*
G02X1511543Y1614578I203J-1D01*
G01X1514364D01*
G02X1514566Y1614376I0J-202D01*
G01Y1613754D01*
G03X1514616Y1613622I200J0D01*
G02Y1610710I-1664J-1456D01*
G03X1514566Y1610578I150J-132D01*
G01Y1608636D01*
G03X1514616Y1608504I200J0D01*
G02Y1605592I-1664J-1456D01*
G03X1514566Y1605460I150J-132D01*
G01Y1604838D01*
G02X1514363Y1604636I-203J1D01*
G01X1511542D01*
G37*
G36*
G01X1528864D02*
G02X1528662Y1604838I0J202D01*
G01Y1605460D01*
G03X1528612Y1605592I-200J0D01*
G02Y1608504I1664J1456D01*
G03X1528662Y1608636I-150J132D01*
G01Y1610578D01*
G03X1528612Y1610710I-200J0D01*
G02Y1613622I1664J1456D01*
G03X1528662Y1613754I-150J132D01*
G01Y1614376D01*
G02X1528865Y1614578I203J-1D01*
G01X1531686D01*
G02X1531888Y1614376I0J-202D01*
G01Y1613754D01*
G03X1531938Y1613622I200J0D01*
G02Y1610710I-1664J-1456D01*
G03X1531888Y1610578I150J-132D01*
G01Y1608636D01*
G03X1531938Y1608504I200J0D01*
G02Y1605592I-1664J-1456D01*
G03X1531888Y1605460I150J-132D01*
G01Y1604838D01*
G02X1531685Y1604636I-203J1D01*
G01X1528864D01*
G37*
G36*
G01X463590Y1618908D02*
X466410D01*
G02X466612Y1618706I0J-202D01*
G01Y1618086D01*
G03X466662Y1617954I200J0D01*
G02Y1615038I-1661J-1458D01*
G03X466612Y1614906I150J-132D01*
G01Y1612968D01*
G03X466662Y1612836I200J0D01*
G02Y1609920I-1661J-1458D01*
G03X466612Y1609788I150J-132D01*
G01Y1609168D01*
G02X466410Y1608966I-202J0D01*
G01X463590D01*
G02X463388Y1609168I0J202D01*
G01Y1609788D01*
G03X463338Y1609920I-200J0D01*
G02Y1612836I1661J1458D01*
G03X463388Y1612968I-150J132D01*
G01Y1614906D01*
G03X463338Y1615038I-200J0D01*
G02Y1617954I1661J1458D01*
G03X463388Y1618086I-150J132D01*
G01Y1618706D01*
G02X463590Y1618908I202J0D01*
G37*
G36*
G01X498236D02*
X501056D01*
G02X501258Y1618706I0J-202D01*
G01Y1618086D01*
G03X501308Y1617954I200J0D01*
G02Y1615038I-1661J-1458D01*
G03X501258Y1614906I150J-132D01*
G01Y1612968D01*
G03X501308Y1612836I200J0D01*
G02Y1609920I-1661J-1458D01*
G03X501258Y1609788I150J-132D01*
G01Y1609168D01*
G02X501056Y1608966I-202J0D01*
G01X498236D01*
G02X498034Y1609168I0J202D01*
G01Y1609788D01*
G03X497984Y1609920I-200J0D01*
G02Y1612836I1661J1458D01*
G03X498034Y1612968I-150J132D01*
G01Y1614906D01*
G03X497984Y1615038I-200J0D01*
G02Y1617954I1661J1458D01*
G03X498034Y1618086I-150J132D01*
G01Y1618706D01*
G02X498236Y1618908I202J0D01*
G37*
G36*
G01X1485558D02*
X1488378D01*
G02X1488580Y1618706I0J-202D01*
G01Y1618086D01*
G03X1488630Y1617954I200J0D01*
G02Y1615038I-1661J-1458D01*
G03X1488580Y1614906I150J-132D01*
G01Y1612968D01*
G03X1488630Y1612836I200J0D01*
G02Y1609920I-1661J-1458D01*
G03X1488580Y1609788I150J-132D01*
G01Y1609168D01*
G02X1488378Y1608966I-202J0D01*
G01X1485558D01*
G02X1485356Y1609168I0J202D01*
G01Y1609788D01*
G03X1485306Y1609920I-200J0D01*
G02Y1612836I1661J1458D01*
G03X1485356Y1612968I-150J132D01*
G01Y1614906D01*
G03X1485306Y1615038I-200J0D01*
G02Y1617954I1661J1458D01*
G03X1485356Y1618086I-150J132D01*
G01Y1618706D01*
G02X1485558Y1618908I202J0D01*
G37*
G36*
G01X1520204D02*
X1523024D01*
G02X1523226Y1618706I0J-202D01*
G01Y1618086D01*
G03X1523276Y1617954I200J0D01*
G02Y1615038I-1661J-1458D01*
G03X1523226Y1614906I150J-132D01*
G01Y1612968D01*
G03X1523276Y1612836I200J0D01*
G02Y1609920I-1661J-1458D01*
G03X1523226Y1609788I150J-132D01*
G01Y1609168D01*
G02X1523024Y1608966I-202J0D01*
G01X1520204D01*
G02X1520002Y1609168I0J202D01*
G01Y1609788D01*
G03X1519952Y1609920I-200J0D01*
G02Y1612836I1661J1458D01*
G03X1520002Y1612968I-150J132D01*
G01Y1614906D01*
G03X1519952Y1615038I-200J0D01*
G02Y1617954I1661J1458D01*
G03X1520002Y1618086I-150J132D01*
G01Y1618706D01*
G02X1520204Y1618908I202J0D01*
G37*
G36*
G01X480912Y1608966D02*
G02X480710Y1609168I0J202D01*
G01Y1609790D01*
G03X480660Y1609922I-200J0D01*
G02Y1612834I1664J1456D01*
G03X480710Y1612966I-150J132D01*
G01Y1614908D01*
G03X480660Y1615040I-200J0D01*
G02Y1617952I1664J1456D01*
G03X480710Y1618084I-150J132D01*
G01Y1618706D01*
G02X480913Y1618908I203J-1D01*
G01X483734D01*
G02X483936Y1618706I0J-202D01*
G01Y1618084D01*
G03X483986Y1617952I200J0D01*
G02Y1615040I-1664J-1456D01*
G03X483936Y1614908I150J-132D01*
G01Y1612966D01*
G03X483986Y1612834I200J0D01*
G02Y1609922I-1664J-1456D01*
G03X483936Y1609790I150J-132D01*
G01Y1609168D01*
G02X483733Y1608966I-203J1D01*
G01X480912D01*
G37*
G36*
G01X1502880D02*
G02X1502678Y1609168I0J202D01*
G01Y1609790D01*
G03X1502628Y1609922I-200J0D01*
G02Y1612834I1664J1456D01*
G03X1502678Y1612966I-150J132D01*
G01Y1614908D01*
G03X1502628Y1615040I-200J0D01*
G02Y1617952I1664J1456D01*
G03X1502678Y1618084I-150J132D01*
G01Y1618706D01*
G02X1502881Y1618908I203J-1D01*
G01X1505702D01*
G02X1505904Y1618706I0J-202D01*
G01Y1618084D01*
G03X1505954Y1617952I200J0D01*
G02Y1615040I-1664J-1456D01*
G03X1505904Y1614908I150J-132D01*
G01Y1612966D01*
G03X1505954Y1612834I200J0D01*
G02Y1609922I-1664J-1456D01*
G03X1505904Y1609790I150J-132D01*
G01Y1609168D01*
G02X1505701Y1608966I-203J1D01*
G01X1502880D01*
G37*
G36*
G01X1537526D02*
G02X1537324Y1609168I0J202D01*
G01Y1609790D01*
G03X1537274Y1609922I-200J0D01*
G02Y1612834I1664J1456D01*
G03X1537324Y1612966I-150J132D01*
G01Y1614908D01*
G03X1537274Y1615040I-200J0D01*
G02Y1617952I1664J1456D01*
G03X1537324Y1618084I-150J132D01*
G01Y1618706D01*
G02X1537527Y1618908I203J-1D01*
G01X1540348D01*
G02X1540550Y1618706I0J-202D01*
G01Y1618084D01*
G03X1540600Y1617952I200J0D01*
G02Y1615040I-1664J-1456D01*
G03X1540550Y1614908I150J-132D01*
G01Y1612966D01*
G03X1540600Y1612834I200J0D01*
G02Y1609922I-1664J-1456D01*
G03X1540550Y1609790I150J-132D01*
G01Y1609168D01*
G02X1540347Y1608966I-203J1D01*
G01X1537526D01*
G37*
G36*
G01X125795Y1466154D02*
X128615D01*
G02X128818Y1465951I0J-203D01*
G01Y1465329D01*
G03X128868Y1465197I200J0D01*
G02Y1462285I-1664J-1456D01*
G03X128818Y1462153I150J-132D01*
G01Y1460210D01*
G03X128868Y1460078I200J0D01*
G02Y1457166I-1664J-1456D01*
G03X128818Y1457034I150J-132D01*
G01Y1456413D01*
G02X128615Y1456210I-203J0D01*
G01X125795D01*
G02X125592Y1456413I0J203D01*
G01Y1457034D01*
G03X125542Y1457166I-200J0D01*
G02Y1460078I1664J1456D01*
G03X125592Y1460210I-150J132D01*
G01Y1462153D01*
G03X125542Y1462285I-200J0D01*
G02Y1465197I1664J1456D01*
G03X125592Y1465329I-150J132D01*
G01Y1465951D01*
G02X125795Y1466154I203J0D01*
G37*
G36*
G01X143118D02*
X145938D01*
G02X146140Y1465951I-1J-203D01*
G01Y1465331D01*
G03X146190Y1465199I200J0D01*
G02Y1462283I-1661J-1458D01*
G03X146140Y1462151I150J-132D01*
G01Y1460212D01*
G03X146190Y1460080I200J0D01*
G02Y1457164I-1661J-1458D01*
G03X146140Y1457032I150J-132D01*
G01Y1456413D01*
G02X145938Y1456210I-202J-1D01*
G01X143118D01*
G02X142916Y1456413I1J203D01*
G01Y1457032D01*
G03X142866Y1457164I-200J0D01*
G02Y1460080I1661J1458D01*
G03X142916Y1460212I-150J132D01*
G01Y1462151D01*
G03X142866Y1462283I-200J0D01*
G02Y1465199I1661J1458D01*
G03X142916Y1465331I-150J132D01*
G01Y1465951D01*
G02X143118Y1466154I202J1D01*
G37*
G36*
G01X160440D02*
X163260D01*
G02X163462Y1465951I-1J-203D01*
G01Y1465331D01*
G03X163512Y1465199I200J0D01*
G02Y1462283I-1661J-1458D01*
G03X163462Y1462151I150J-132D01*
G01Y1460212D01*
G03X163512Y1460080I200J0D01*
G02Y1457164I-1661J-1458D01*
G03X163462Y1457032I150J-132D01*
G01Y1456413D01*
G02X163260Y1456210I-202J-1D01*
G01X160440D01*
G02X160238Y1456413I1J203D01*
G01Y1457032D01*
G03X160188Y1457164I-200J0D01*
G02Y1460080I1661J1458D01*
G03X160238Y1460212I-150J132D01*
G01Y1462151D01*
G03X160188Y1462283I-200J0D01*
G02Y1465199I1661J1458D01*
G03X160238Y1465331I-150J132D01*
G01Y1465951D01*
G02X160440Y1466154I202J1D01*
G37*
G36*
G01X177763D02*
X180583D01*
G02X180786Y1465951I0J-203D01*
G01Y1465329D01*
G03X180836Y1465197I200J0D01*
G02Y1462285I-1664J-1456D01*
G03X180786Y1462153I150J-132D01*
G01Y1460210D01*
G03X180836Y1460078I200J0D01*
G02Y1457166I-1664J-1456D01*
G03X180786Y1457034I150J-132D01*
G01Y1456413D01*
G02X180583Y1456210I-203J0D01*
G01X177763D01*
G02X177560Y1456413I0J203D01*
G01Y1457034D01*
G03X177510Y1457166I-200J0D01*
G02Y1460078I1664J1456D01*
G03X177560Y1460210I-150J132D01*
G01Y1462153D01*
G03X177510Y1462285I-200J0D01*
G02Y1465197I1664J1456D01*
G03X177560Y1465329I-150J132D01*
G01Y1465951D01*
G02X177763Y1466154I203J0D01*
G37*
G36*
G01X281700D02*
X284520D01*
G02X284722Y1465951I-1J-203D01*
G01Y1465331D01*
G03X284772Y1465199I200J0D01*
G02Y1462283I-1661J-1458D01*
G03X284722Y1462151I150J-132D01*
G01Y1460212D01*
G03X284772Y1460080I200J0D01*
G02Y1457164I-1661J-1458D01*
G03X284722Y1457032I150J-132D01*
G01Y1456413D01*
G02X284520Y1456210I-202J-1D01*
G01X281700D01*
G02X281498Y1456413I1J203D01*
G01Y1457032D01*
G03X281448Y1457164I-200J0D01*
G02Y1460080I1661J1458D01*
G03X281498Y1460212I-150J132D01*
G01Y1462151D01*
G03X281448Y1462283I-200J0D01*
G02Y1465199I1661J1458D01*
G03X281498Y1465331I-150J132D01*
G01Y1465951D01*
G02X281700Y1466154I202J1D01*
G37*
G36*
G01X299023D02*
X301843D01*
G02X302046Y1465951I0J-203D01*
G01Y1465329D01*
G03X302096Y1465197I200J0D01*
G02Y1462285I-1664J-1456D01*
G03X302046Y1462153I150J-132D01*
G01Y1460210D01*
G03X302096Y1460078I200J0D01*
G02Y1457166I-1664J-1456D01*
G03X302046Y1457034I150J-132D01*
G01Y1456413D01*
G02X301843Y1456210I-203J0D01*
G01X299023D01*
G02X298820Y1456413I0J203D01*
G01Y1457034D01*
G03X298770Y1457166I-200J0D01*
G02Y1460078I1664J1456D01*
G03X298820Y1460210I-150J132D01*
G01Y1462153D01*
G03X298770Y1462285I-200J0D01*
G02Y1465197I1664J1456D01*
G03X298820Y1465329I-150J132D01*
G01Y1465951D01*
G02X299023Y1466154I203J0D01*
G37*
G36*
G01X454929D02*
X457749D01*
G02X457952Y1465951I0J-203D01*
G01Y1465329D01*
G03X458002Y1465197I200J0D01*
G02Y1462285I-1664J-1456D01*
G03X457952Y1462153I150J-132D01*
G01Y1460210D01*
G03X458002Y1460078I200J0D01*
G02Y1457166I-1664J-1456D01*
G03X457952Y1457034I150J-132D01*
G01Y1456413D01*
G02X457749Y1456210I-203J0D01*
G01X454929D01*
G02X454726Y1456413I0J203D01*
G01Y1457034D01*
G03X454676Y1457166I-200J0D01*
G02Y1460078I1664J1456D01*
G03X454726Y1460210I-150J132D01*
G01Y1462153D01*
G03X454676Y1462285I-200J0D01*
G02Y1465197I1664J1456D01*
G03X454726Y1465329I-150J132D01*
G01Y1465951D01*
G02X454929Y1466154I203J0D01*
G37*
G36*
G01X472252D02*
X475072D01*
G02X475274Y1465951I-1J-203D01*
G01Y1465331D01*
G03X475324Y1465199I200J0D01*
G02Y1462283I-1661J-1458D01*
G03X475274Y1462151I150J-132D01*
G01Y1460212D01*
G03X475324Y1460080I200J0D01*
G02Y1457164I-1661J-1458D01*
G03X475274Y1457032I150J-132D01*
G01Y1456413D01*
G02X475072Y1456210I-202J-1D01*
G01X472252D01*
G02X472050Y1456413I1J203D01*
G01Y1457032D01*
G03X472000Y1457164I-200J0D01*
G02Y1460080I1661J1458D01*
G03X472050Y1460212I-150J132D01*
G01Y1462151D01*
G03X472000Y1462283I-200J0D01*
G02Y1465199I1661J1458D01*
G03X472050Y1465331I-150J132D01*
G01Y1465951D01*
G02X472252Y1466154I202J1D01*
G37*
G36*
G01X489575D02*
X492395D01*
G02X492598Y1465951I0J-203D01*
G01Y1465329D01*
G03X492648Y1465197I200J0D01*
G02Y1462285I-1664J-1456D01*
G03X492598Y1462153I150J-132D01*
G01Y1460210D01*
G03X492648Y1460078I200J0D01*
G02Y1457166I-1664J-1456D01*
G03X492598Y1457034I150J-132D01*
G01Y1456413D01*
G02X492395Y1456210I-203J0D01*
G01X489575D01*
G02X489372Y1456413I0J203D01*
G01Y1457034D01*
G03X489322Y1457166I-200J0D01*
G02Y1460078I1664J1456D01*
G03X489372Y1460210I-150J132D01*
G01Y1462153D01*
G03X489322Y1462285I-200J0D01*
G02Y1465197I1664J1456D01*
G03X489372Y1465329I-150J132D01*
G01Y1465951D01*
G02X489575Y1466154I203J0D01*
G37*
G36*
G01X506897D02*
X509717D01*
G02X509920Y1465951I0J-203D01*
G01Y1465329D01*
G03X509970Y1465197I200J0D01*
G02Y1462285I-1664J-1456D01*
G03X509920Y1462153I150J-132D01*
G01Y1460210D01*
G03X509970Y1460078I200J0D01*
G02Y1457166I-1664J-1456D01*
G03X509920Y1457034I150J-132D01*
G01Y1456413D01*
G02X509717Y1456210I-203J0D01*
G01X506897D01*
G02X506694Y1456413I0J203D01*
G01Y1457034D01*
G03X506644Y1457166I-200J0D01*
G02Y1460078I1664J1456D01*
G03X506694Y1460210I-150J132D01*
G01Y1462153D01*
G03X506644Y1462285I-200J0D01*
G02Y1465197I1664J1456D01*
G03X506694Y1465329I-150J132D01*
G01Y1465951D01*
G02X506897Y1466154I203J0D01*
G37*
G36*
G01X645480D02*
X648300D01*
G02X648502Y1465951I-1J-203D01*
G01Y1465331D01*
G03X648552Y1465199I200J0D01*
G02Y1462283I-1661J-1458D01*
G03X648502Y1462151I150J-132D01*
G01Y1460212D01*
G03X648552Y1460080I200J0D01*
G02Y1457164I-1661J-1458D01*
G03X648502Y1457032I150J-132D01*
G01Y1456413D01*
G02X648300Y1456210I-202J-1D01*
G01X645480D01*
G02X645278Y1456413I1J203D01*
G01Y1457032D01*
G03X645228Y1457164I-200J0D01*
G02Y1460080I1661J1458D01*
G03X645278Y1460212I-150J132D01*
G01Y1462151D01*
G03X645228Y1462283I-200J0D01*
G02Y1465199I1661J1458D01*
G03X645278Y1465331I-150J132D01*
G01Y1465951D01*
G02X645480Y1466154I202J1D01*
G37*
G36*
G01X662803D02*
X665623D01*
G02X665826Y1465951I0J-203D01*
G01Y1465329D01*
G03X665876Y1465197I200J0D01*
G02Y1462285I-1664J-1456D01*
G03X665826Y1462153I150J-132D01*
G01Y1460210D01*
G03X665876Y1460078I200J0D01*
G02Y1457166I-1664J-1456D01*
G03X665826Y1457034I150J-132D01*
G01Y1456413D01*
G02X665623Y1456210I-203J0D01*
G01X662803D01*
G02X662600Y1456413I0J203D01*
G01Y1457034D01*
G03X662550Y1457166I-200J0D01*
G02Y1460078I1664J1456D01*
G03X662600Y1460210I-150J132D01*
G01Y1462153D01*
G03X662550Y1462285I-200J0D01*
G02Y1465197I1664J1456D01*
G03X662600Y1465329I-150J132D01*
G01Y1465951D01*
G02X662803Y1466154I203J0D01*
G37*
G36*
G01X680125D02*
X682945D01*
G02X683148Y1465951I0J-203D01*
G01Y1465329D01*
G03X683198Y1465197I200J0D01*
G02Y1462285I-1664J-1456D01*
G03X683148Y1462153I150J-132D01*
G01Y1460210D01*
G03X683198Y1460078I200J0D01*
G02Y1457166I-1664J-1456D01*
G03X683148Y1457034I150J-132D01*
G01Y1456413D01*
G02X682945Y1456210I-203J0D01*
G01X680125D01*
G02X679922Y1456413I0J203D01*
G01Y1457034D01*
G03X679872Y1457166I-200J0D01*
G02Y1460078I1664J1456D01*
G03X679922Y1460210I-150J132D01*
G01Y1462153D01*
G03X679872Y1462285I-200J0D01*
G02Y1465197I1664J1456D01*
G03X679922Y1465329I-150J132D01*
G01Y1465951D01*
G02X680125Y1466154I203J0D01*
G37*
G36*
G01X1165086D02*
X1167906D01*
G02X1168108Y1465951I-1J-203D01*
G01Y1465331D01*
G03X1168158Y1465199I200J0D01*
G02Y1462283I-1661J-1458D01*
G03X1168108Y1462151I150J-132D01*
G01Y1460212D01*
G03X1168158Y1460080I200J0D01*
G02Y1457164I-1661J-1458D01*
G03X1168108Y1457032I150J-132D01*
G01Y1456413D01*
G02X1167906Y1456210I-202J-1D01*
G01X1165086D01*
G02X1164884Y1456413I1J203D01*
G01Y1457032D01*
G03X1164834Y1457164I-200J0D01*
G02Y1460080I1661J1458D01*
G03X1164884Y1460212I-150J132D01*
G01Y1462151D01*
G03X1164834Y1462283I-200J0D01*
G02Y1465199I1661J1458D01*
G03X1164884Y1465331I-150J132D01*
G01Y1465951D01*
G02X1165086Y1466154I202J1D01*
G37*
G36*
G01X1182408D02*
X1185228D01*
G02X1185430Y1465951I-1J-203D01*
G01Y1465331D01*
G03X1185480Y1465199I200J0D01*
G02Y1462283I-1661J-1458D01*
G03X1185430Y1462151I150J-132D01*
G01Y1460212D01*
G03X1185480Y1460080I200J0D01*
G02Y1457164I-1661J-1458D01*
G03X1185430Y1457032I150J-132D01*
G01Y1456413D01*
G02X1185228Y1456210I-202J-1D01*
G01X1182408D01*
G02X1182206Y1456413I1J203D01*
G01Y1457032D01*
G03X1182156Y1457164I-200J0D01*
G02Y1460080I1661J1458D01*
G03X1182206Y1460212I-150J132D01*
G01Y1462151D01*
G03X1182156Y1462283I-200J0D01*
G02Y1465199I1661J1458D01*
G03X1182206Y1465331I-150J132D01*
G01Y1465951D01*
G02X1182408Y1466154I202J1D01*
G37*
G36*
G01X1303669D02*
X1306489D01*
G02X1306692Y1465951I0J-203D01*
G01Y1465329D01*
G03X1306742Y1465197I200J0D01*
G02Y1462285I-1664J-1456D01*
G03X1306692Y1462153I150J-132D01*
G01Y1460210D01*
G03X1306742Y1460078I200J0D01*
G02Y1457166I-1664J-1456D01*
G03X1306692Y1457034I150J-132D01*
G01Y1456413D01*
G02X1306489Y1456210I-203J0D01*
G01X1303669D01*
G02X1303466Y1456413I0J203D01*
G01Y1457034D01*
G03X1303416Y1457166I-200J0D01*
G02Y1460078I1664J1456D01*
G03X1303466Y1460210I-150J132D01*
G01Y1462153D01*
G03X1303416Y1462285I-200J0D01*
G02Y1465197I1664J1456D01*
G03X1303466Y1465329I-150J132D01*
G01Y1465951D01*
G02X1303669Y1466154I203J0D01*
G37*
G36*
G01X1320992D02*
X1323812D01*
G02X1324014Y1465951I-1J-203D01*
G01Y1465331D01*
G03X1324064Y1465199I200J0D01*
G02Y1462283I-1661J-1458D01*
G03X1324014Y1462151I150J-132D01*
G01Y1460212D01*
G03X1324064Y1460080I200J0D01*
G02Y1457164I-1661J-1458D01*
G03X1324014Y1457032I150J-132D01*
G01Y1456413D01*
G02X1323812Y1456210I-202J-1D01*
G01X1320992D01*
G02X1320790Y1456413I1J203D01*
G01Y1457032D01*
G03X1320740Y1457164I-200J0D01*
G02Y1460080I1661J1458D01*
G03X1320790Y1460212I-150J132D01*
G01Y1462151D01*
G03X1320740Y1462283I-200J0D01*
G02Y1465199I1661J1458D01*
G03X1320790Y1465331I-150J132D01*
G01Y1465951D01*
G02X1320992Y1466154I202J1D01*
G37*
G36*
G01X1338315D02*
X1341135D01*
G02X1341338Y1465951I0J-203D01*
G01Y1465329D01*
G03X1341388Y1465197I200J0D01*
G02Y1462285I-1664J-1456D01*
G03X1341338Y1462153I150J-132D01*
G01Y1460210D01*
G03X1341388Y1460078I200J0D01*
G02Y1457166I-1664J-1456D01*
G03X1341338Y1457034I150J-132D01*
G01Y1456413D01*
G02X1341135Y1456210I-203J0D01*
G01X1338315D01*
G02X1338112Y1456413I0J203D01*
G01Y1457034D01*
G03X1338062Y1457166I-200J0D01*
G02Y1460078I1664J1456D01*
G03X1338112Y1460210I-150J132D01*
G01Y1462153D01*
G03X1338062Y1462285I-200J0D01*
G02Y1465197I1664J1456D01*
G03X1338112Y1465329I-150J132D01*
G01Y1465951D01*
G02X1338315Y1466154I203J0D01*
G37*
G36*
G01X1355637D02*
X1358457D01*
G02X1358660Y1465951I0J-203D01*
G01Y1465329D01*
G03X1358710Y1465197I200J0D01*
G02Y1462285I-1664J-1456D01*
G03X1358660Y1462153I150J-132D01*
G01Y1460210D01*
G03X1358710Y1460078I200J0D01*
G02Y1457166I-1664J-1456D01*
G03X1358660Y1457034I150J-132D01*
G01Y1456413D01*
G02X1358457Y1456210I-203J0D01*
G01X1355637D01*
G02X1355434Y1456413I0J203D01*
G01Y1457034D01*
G03X1355384Y1457166I-200J0D01*
G02Y1460078I1664J1456D01*
G03X1355434Y1460210I-150J132D01*
G01Y1462153D01*
G03X1355384Y1462285I-200J0D01*
G02Y1465197I1664J1456D01*
G03X1355434Y1465329I-150J132D01*
G01Y1465951D01*
G02X1355637Y1466154I203J0D01*
G37*
G36*
G01X1476897D02*
X1479717D01*
G02X1479920Y1465951I0J-203D01*
G01Y1465329D01*
G03X1479970Y1465197I200J0D01*
G02Y1462285I-1664J-1456D01*
G03X1479920Y1462153I150J-132D01*
G01Y1460210D01*
G03X1479970Y1460078I200J0D01*
G02Y1457166I-1664J-1456D01*
G03X1479920Y1457034I150J-132D01*
G01Y1456413D01*
G02X1479717Y1456210I-203J0D01*
G01X1476897D01*
G02X1476694Y1456413I0J203D01*
G01Y1457034D01*
G03X1476644Y1457166I-200J0D01*
G02Y1460078I1664J1456D01*
G03X1476694Y1460210I-150J132D01*
G01Y1462153D01*
G03X1476644Y1462285I-200J0D01*
G02Y1465197I1664J1456D01*
G03X1476694Y1465329I-150J132D01*
G01Y1465951D01*
G02X1476897Y1466154I203J0D01*
G37*
G36*
G01X1494220D02*
X1497040D01*
G02X1497242Y1465951I-1J-203D01*
G01Y1465331D01*
G03X1497292Y1465199I200J0D01*
G02Y1462283I-1661J-1458D01*
G03X1497242Y1462151I150J-132D01*
G01Y1460212D01*
G03X1497292Y1460080I200J0D01*
G02Y1457164I-1661J-1458D01*
G03X1497242Y1457032I150J-132D01*
G01Y1456413D01*
G02X1497040Y1456210I-202J-1D01*
G01X1494220D01*
G02X1494018Y1456413I1J203D01*
G01Y1457032D01*
G03X1493968Y1457164I-200J0D01*
G02Y1460080I1661J1458D01*
G03X1494018Y1460212I-150J132D01*
G01Y1462151D01*
G03X1493968Y1462283I-200J0D01*
G02Y1465199I1661J1458D01*
G03X1494018Y1465331I-150J132D01*
G01Y1465951D01*
G02X1494220Y1466154I202J1D01*
G37*
G36*
G01X1511543D02*
X1514363D01*
G02X1514566Y1465951I0J-203D01*
G01Y1465329D01*
G03X1514616Y1465197I200J0D01*
G02Y1462285I-1664J-1456D01*
G03X1514566Y1462153I150J-132D01*
G01Y1460210D01*
G03X1514616Y1460078I200J0D01*
G02Y1457166I-1664J-1456D01*
G03X1514566Y1457034I150J-132D01*
G01Y1456413D01*
G02X1514363Y1456210I-203J0D01*
G01X1511543D01*
G02X1511340Y1456413I0J203D01*
G01Y1457034D01*
G03X1511290Y1457166I-200J0D01*
G02Y1460078I1664J1456D01*
G03X1511340Y1460210I-150J132D01*
G01Y1462153D01*
G03X1511290Y1462285I-200J0D01*
G02Y1465197I1664J1456D01*
G03X1511340Y1465329I-150J132D01*
G01Y1465951D01*
G02X1511543Y1466154I203J0D01*
G37*
G36*
G01X1528865D02*
X1531685D01*
G02X1531888Y1465951I0J-203D01*
G01Y1465329D01*
G03X1531938Y1465197I200J0D01*
G02Y1462285I-1664J-1456D01*
G03X1531888Y1462153I150J-132D01*
G01Y1460210D01*
G03X1531938Y1460078I200J0D01*
G02Y1457166I-1664J-1456D01*
G03X1531888Y1457034I150J-132D01*
G01Y1456413D01*
G02X1531685Y1456210I-203J0D01*
G01X1528865D01*
G02X1528662Y1456413I0J203D01*
G01Y1457034D01*
G03X1528612Y1457166I-200J0D01*
G02Y1460078I1664J1456D01*
G03X1528662Y1460210I-150J132D01*
G01Y1462153D01*
G03X1528612Y1462285I-200J0D01*
G02Y1465197I1664J1456D01*
G03X1528662Y1465329I-150J132D01*
G01Y1465951D01*
G02X1528865Y1466154I203J0D01*
G37*
G36*
G01X1684771D02*
X1687591D01*
G02X1687794Y1465951I0J-203D01*
G01Y1465329D01*
G03X1687844Y1465197I200J0D01*
G02Y1462285I-1664J-1456D01*
G03X1687794Y1462153I150J-132D01*
G01Y1460210D01*
G03X1687844Y1460078I200J0D01*
G02Y1457166I-1664J-1456D01*
G03X1687794Y1457034I150J-132D01*
G01Y1456413D01*
G02X1687591Y1456210I-203J0D01*
G01X1684771D01*
G02X1684568Y1456413I0J203D01*
G01Y1457034D01*
G03X1684518Y1457166I-200J0D01*
G02Y1460078I1664J1456D01*
G03X1684568Y1460210I-150J132D01*
G01Y1462153D01*
G03X1684518Y1462285I-200J0D01*
G02Y1465197I1664J1456D01*
G03X1684568Y1465329I-150J132D01*
G01Y1465951D01*
G02X1684771Y1466154I203J0D01*
G37*
G36*
G01X1702093D02*
X1704913D01*
G02X1705116Y1465951I0J-203D01*
G01Y1465329D01*
G03X1705166Y1465197I200J0D01*
G02Y1462285I-1664J-1456D01*
G03X1705116Y1462153I150J-132D01*
G01Y1460210D01*
G03X1705166Y1460078I200J0D01*
G02Y1457166I-1664J-1456D01*
G03X1705116Y1457034I150J-132D01*
G01Y1456413D01*
G02X1704913Y1456210I-203J0D01*
G01X1702093D01*
G02X1701890Y1456413I0J203D01*
G01Y1457034D01*
G03X1701840Y1457166I-200J0D01*
G02Y1460078I1664J1456D01*
G03X1701890Y1460210I-150J132D01*
G01Y1462153D01*
G03X1701840Y1462285I-200J0D01*
G02Y1465197I1664J1456D01*
G03X1701890Y1465329I-150J132D01*
G01Y1465951D01*
G02X1702093Y1466154I203J0D01*
G37*
G36*
G01X134456Y1470484D02*
X137276D01*
G02X137478Y1470281I-1J-203D01*
G01Y1469661D01*
G03X137528Y1469529I200J0D01*
G02Y1466613I-1661J-1458D01*
G03X137478Y1466481I150J-132D01*
G01Y1464543D01*
G03X137528Y1464411I200J0D01*
G02Y1461495I-1661J-1458D01*
G03X137478Y1461363I150J-132D01*
G01Y1460743D01*
G02X137276Y1460540I-202J-1D01*
G01X134456D01*
G02X134254Y1460743I1J203D01*
G01Y1461363D01*
G03X134204Y1461495I-200J0D01*
G02Y1464411I1661J1458D01*
G03X134254Y1464543I-150J132D01*
G01Y1466481D01*
G03X134204Y1466613I-200J0D01*
G02Y1469529I1661J1458D01*
G03X134254Y1469661I-150J132D01*
G01Y1470281D01*
G02X134456Y1470484I202J1D01*
G37*
G36*
G01X151779D02*
X154599D01*
G02X154802Y1470281I0J-203D01*
G01Y1469659D01*
G03X154852Y1469527I200J0D01*
G02Y1466615I-1664J-1456D01*
G03X154802Y1466483I150J-132D01*
G01Y1464541D01*
G03X154852Y1464409I200J0D01*
G02Y1461497I-1664J-1456D01*
G03X154802Y1461365I150J-132D01*
G01Y1460743D01*
G02X154599Y1460540I-203J0D01*
G01X151779D01*
G02X151576Y1460743I0J203D01*
G01Y1461365D01*
G03X151526Y1461497I-200J0D01*
G02Y1464409I1664J1456D01*
G03X151576Y1464541I-150J132D01*
G01Y1466483D01*
G03X151526Y1466615I-200J0D01*
G02Y1469527I1664J1456D01*
G03X151576Y1469659I-150J132D01*
G01Y1470281D01*
G02X151779Y1470484I203J0D01*
G37*
G36*
G01X169102D02*
X171922D01*
G02X172124Y1470281I-1J-203D01*
G01Y1469661D01*
G03X172174Y1469529I200J0D01*
G02Y1466613I-1661J-1458D01*
G03X172124Y1466481I150J-132D01*
G01Y1464543D01*
G03X172174Y1464411I200J0D01*
G02Y1461495I-1661J-1458D01*
G03X172124Y1461363I150J-132D01*
G01Y1460743D01*
G02X171922Y1460540I-202J-1D01*
G01X169102D01*
G02X168900Y1460743I1J203D01*
G01Y1461363D01*
G03X168850Y1461495I-200J0D01*
G02Y1464411I1661J1458D01*
G03X168900Y1464543I-150J132D01*
G01Y1466481D01*
G03X168850Y1466613I-200J0D01*
G02Y1469529I1661J1458D01*
G03X168900Y1469661I-150J132D01*
G01Y1470281D01*
G02X169102Y1470484I202J1D01*
G37*
G36*
G01X186425D02*
X189245D01*
G02X189448Y1470281I0J-203D01*
G01Y1469659D01*
G03X189498Y1469527I200J0D01*
G02Y1466615I-1664J-1456D01*
G03X189448Y1466483I150J-132D01*
G01Y1464541D01*
G03X189498Y1464409I200J0D01*
G02Y1461497I-1664J-1456D01*
G03X189448Y1461365I150J-132D01*
G01Y1460743D01*
G02X189245Y1460540I-203J0D01*
G01X186425D01*
G02X186222Y1460743I0J203D01*
G01Y1461365D01*
G03X186172Y1461497I-200J0D01*
G02Y1464409I1664J1456D01*
G03X186222Y1464541I-150J132D01*
G01Y1466483D01*
G03X186172Y1466615I-200J0D01*
G02Y1469527I1664J1456D01*
G03X186222Y1469659I-150J132D01*
G01Y1470281D01*
G02X186425Y1470484I203J0D01*
G37*
G36*
G01X290361D02*
X293181D01*
G02X293384Y1470281I0J-203D01*
G01Y1469659D01*
G03X293434Y1469527I200J0D01*
G02Y1466615I-1664J-1456D01*
G03X293384Y1466483I150J-132D01*
G01Y1464541D01*
G03X293434Y1464409I200J0D01*
G02Y1461497I-1664J-1456D01*
G03X293384Y1461365I150J-132D01*
G01Y1460743D01*
G02X293181Y1460540I-203J0D01*
G01X290361D01*
G02X290158Y1460743I0J203D01*
G01Y1461365D01*
G03X290108Y1461497I-200J0D01*
G02Y1464409I1664J1456D01*
G03X290158Y1464541I-150J132D01*
G01Y1466483D01*
G03X290108Y1466615I-200J0D01*
G02Y1469527I1664J1456D01*
G03X290158Y1469659I-150J132D01*
G01Y1470281D01*
G02X290361Y1470484I203J0D01*
G37*
G36*
G01X463590D02*
X466410D01*
G02X466612Y1470281I-1J-203D01*
G01Y1469661D01*
G03X466662Y1469529I200J0D01*
G02Y1466613I-1661J-1458D01*
G03X466612Y1466481I150J-132D01*
G01Y1464543D01*
G03X466662Y1464411I200J0D01*
G02Y1461495I-1661J-1458D01*
G03X466612Y1461363I150J-132D01*
G01Y1460743D01*
G02X466410Y1460540I-202J-1D01*
G01X463590D01*
G02X463388Y1460743I1J203D01*
G01Y1461363D01*
G03X463338Y1461495I-200J0D01*
G02Y1464411I1661J1458D01*
G03X463388Y1464543I-150J132D01*
G01Y1466481D01*
G03X463338Y1466613I-200J0D01*
G02Y1469529I1661J1458D01*
G03X463388Y1469661I-150J132D01*
G01Y1470281D01*
G02X463590Y1470484I202J1D01*
G37*
G36*
G01X480913D02*
X483733D01*
G02X483936Y1470281I0J-203D01*
G01Y1469659D01*
G03X483986Y1469527I200J0D01*
G02Y1466615I-1664J-1456D01*
G03X483936Y1466483I150J-132D01*
G01Y1464541D01*
G03X483986Y1464409I200J0D01*
G02Y1461497I-1664J-1456D01*
G03X483936Y1461365I150J-132D01*
G01Y1460743D01*
G02X483733Y1460540I-203J0D01*
G01X480913D01*
G02X480710Y1460743I0J203D01*
G01Y1461365D01*
G03X480660Y1461497I-200J0D01*
G02Y1464409I1664J1456D01*
G03X480710Y1464541I-150J132D01*
G01Y1466483D01*
G03X480660Y1466615I-200J0D01*
G02Y1469527I1664J1456D01*
G03X480710Y1469659I-150J132D01*
G01Y1470281D01*
G02X480913Y1470484I203J0D01*
G37*
G36*
G01X498236D02*
X501056D01*
G02X501258Y1470281I-1J-203D01*
G01Y1469661D01*
G03X501308Y1469529I200J0D01*
G02Y1466613I-1661J-1458D01*
G03X501258Y1466481I150J-132D01*
G01Y1464543D01*
G03X501308Y1464411I200J0D01*
G02Y1461495I-1661J-1458D01*
G03X501258Y1461363I150J-132D01*
G01Y1460743D01*
G02X501056Y1460540I-202J-1D01*
G01X498236D01*
G02X498034Y1460743I1J203D01*
G01Y1461363D01*
G03X497984Y1461495I-200J0D01*
G02Y1464411I1661J1458D01*
G03X498034Y1464543I-150J132D01*
G01Y1466481D01*
G03X497984Y1466613I-200J0D01*
G02Y1469529I1661J1458D01*
G03X498034Y1469661I-150J132D01*
G01Y1470281D01*
G02X498236Y1470484I202J1D01*
G37*
G36*
G01X515559D02*
X518379D01*
G02X518582Y1470281I0J-203D01*
G01Y1469659D01*
G03X518632Y1469527I200J0D01*
G02Y1466615I-1664J-1456D01*
G03X518582Y1466483I150J-132D01*
G01Y1464541D01*
G03X518632Y1464409I200J0D01*
G02Y1461497I-1664J-1456D01*
G03X518582Y1461365I150J-132D01*
G01Y1460743D01*
G02X518379Y1460540I-203J0D01*
G01X515559D01*
G02X515356Y1460743I0J203D01*
G01Y1461365D01*
G03X515306Y1461497I-200J0D01*
G02Y1464409I1664J1456D01*
G03X515356Y1464541I-150J132D01*
G01Y1466483D01*
G03X515306Y1466615I-200J0D01*
G02Y1469527I1664J1456D01*
G03X515356Y1469659I-150J132D01*
G01Y1470281D01*
G02X515559Y1470484I203J0D01*
G37*
G36*
G01X654141D02*
X656961D01*
G02X657164Y1470281I0J-203D01*
G01Y1469659D01*
G03X657214Y1469527I200J0D01*
G02Y1466615I-1664J-1456D01*
G03X657164Y1466483I150J-132D01*
G01Y1464541D01*
G03X657214Y1464409I200J0D01*
G02Y1461497I-1664J-1456D01*
G03X657164Y1461365I150J-132D01*
G01Y1460743D01*
G02X656961Y1460540I-203J0D01*
G01X654141D01*
G02X653938Y1460743I0J203D01*
G01Y1461365D01*
G03X653888Y1461497I-200J0D01*
G02Y1464409I1664J1456D01*
G03X653938Y1464541I-150J132D01*
G01Y1466483D01*
G03X653888Y1466615I-200J0D01*
G02Y1469527I1664J1456D01*
G03X653938Y1469659I-150J132D01*
G01Y1470281D01*
G02X654141Y1470484I203J0D01*
G37*
G36*
G01X671464D02*
X674284D01*
G02X674486Y1470281I-1J-203D01*
G01Y1469661D01*
G03X674536Y1469529I200J0D01*
G02Y1466613I-1661J-1458D01*
G03X674486Y1466481I150J-132D01*
G01Y1464543D01*
G03X674536Y1464411I200J0D01*
G02Y1461495I-1661J-1458D01*
G03X674486Y1461363I150J-132D01*
G01Y1460743D01*
G02X674284Y1460540I-202J-1D01*
G01X671464D01*
G02X671262Y1460743I1J203D01*
G01Y1461363D01*
G03X671212Y1461495I-200J0D01*
G02Y1464411I1661J1458D01*
G03X671262Y1464543I-150J132D01*
G01Y1466481D01*
G03X671212Y1466613I-200J0D01*
G02Y1469529I1661J1458D01*
G03X671262Y1469661I-150J132D01*
G01Y1470281D01*
G02X671464Y1470484I202J1D01*
G37*
G36*
G01X688787D02*
X691607D01*
G02X691810Y1470281I0J-203D01*
G01Y1469659D01*
G03X691860Y1469527I200J0D01*
G02Y1466615I-1664J-1456D01*
G03X691810Y1466483I150J-132D01*
G01Y1464541D01*
G03X691860Y1464409I200J0D01*
G02Y1461497I-1664J-1456D01*
G03X691810Y1461365I150J-132D01*
G01Y1460743D01*
G02X691607Y1460540I-203J0D01*
G01X688787D01*
G02X688584Y1460743I0J203D01*
G01Y1461365D01*
G03X688534Y1461497I-200J0D01*
G02Y1464409I1664J1456D01*
G03X688584Y1464541I-150J132D01*
G01Y1466483D01*
G03X688534Y1466615I-200J0D01*
G02Y1469527I1664J1456D01*
G03X688584Y1469659I-150J132D01*
G01Y1470281D01*
G02X688787Y1470484I203J0D01*
G37*
G36*
G01X1173747D02*
X1176567D01*
G02X1176770Y1470281I0J-203D01*
G01Y1469659D01*
G03X1176820Y1469527I200J0D01*
G02Y1466615I-1664J-1456D01*
G03X1176770Y1466483I150J-132D01*
G01Y1464541D01*
G03X1176820Y1464409I200J0D01*
G02Y1461497I-1664J-1456D01*
G03X1176770Y1461365I150J-132D01*
G01Y1460743D01*
G02X1176567Y1460540I-203J0D01*
G01X1173747D01*
G02X1173544Y1460743I0J203D01*
G01Y1461365D01*
G03X1173494Y1461497I-200J0D01*
G02Y1464409I1664J1456D01*
G03X1173544Y1464541I-150J132D01*
G01Y1466483D01*
G03X1173494Y1466615I-200J0D01*
G02Y1469527I1664J1456D01*
G03X1173544Y1469659I-150J132D01*
G01Y1470281D01*
G02X1173747Y1470484I203J0D01*
G37*
G36*
G01X1191070D02*
X1193890D01*
G02X1194092Y1470281I-1J-203D01*
G01Y1469661D01*
G03X1194142Y1469529I200J0D01*
G02Y1466613I-1661J-1458D01*
G03X1194092Y1466481I150J-132D01*
G01Y1464543D01*
G03X1194142Y1464411I200J0D01*
G02Y1461495I-1661J-1458D01*
G03X1194092Y1461363I150J-132D01*
G01Y1460743D01*
G02X1193890Y1460540I-202J-1D01*
G01X1191070D01*
G02X1190868Y1460743I1J203D01*
G01Y1461363D01*
G03X1190818Y1461495I-200J0D01*
G02Y1464411I1661J1458D01*
G03X1190868Y1464543I-150J132D01*
G01Y1466481D01*
G03X1190818Y1466613I-200J0D01*
G02Y1469529I1661J1458D01*
G03X1190868Y1469661I-150J132D01*
G01Y1470281D01*
G02X1191070Y1470484I202J1D01*
G37*
G36*
G01X1312330D02*
X1315150D01*
G02X1315352Y1470281I-1J-203D01*
G01Y1469661D01*
G03X1315402Y1469529I200J0D01*
G02Y1466613I-1661J-1458D01*
G03X1315352Y1466481I150J-132D01*
G01Y1464543D01*
G03X1315402Y1464411I200J0D01*
G02Y1461495I-1661J-1458D01*
G03X1315352Y1461363I150J-132D01*
G01Y1460743D01*
G02X1315150Y1460540I-202J-1D01*
G01X1312330D01*
G02X1312128Y1460743I1J203D01*
G01Y1461363D01*
G03X1312078Y1461495I-200J0D01*
G02Y1464411I1661J1458D01*
G03X1312128Y1464543I-150J132D01*
G01Y1466481D01*
G03X1312078Y1466613I-200J0D01*
G02Y1469529I1661J1458D01*
G03X1312128Y1469661I-150J132D01*
G01Y1470281D01*
G02X1312330Y1470484I202J1D01*
G37*
G36*
G01X1329653D02*
X1332473D01*
G02X1332676Y1470281I0J-203D01*
G01Y1469659D01*
G03X1332726Y1469527I200J0D01*
G02Y1466615I-1664J-1456D01*
G03X1332676Y1466483I150J-132D01*
G01Y1464541D01*
G03X1332726Y1464409I200J0D01*
G02Y1461497I-1664J-1456D01*
G03X1332676Y1461365I150J-132D01*
G01Y1460743D01*
G02X1332473Y1460540I-203J0D01*
G01X1329653D01*
G02X1329450Y1460743I0J203D01*
G01Y1461365D01*
G03X1329400Y1461497I-200J0D01*
G02Y1464409I1664J1456D01*
G03X1329450Y1464541I-150J132D01*
G01Y1466483D01*
G03X1329400Y1466615I-200J0D01*
G02Y1469527I1664J1456D01*
G03X1329450Y1469659I-150J132D01*
G01Y1470281D01*
G02X1329653Y1470484I203J0D01*
G37*
G36*
G01X1346976D02*
X1349796D01*
G02X1349998Y1470281I-1J-203D01*
G01Y1469661D01*
G03X1350048Y1469529I200J0D01*
G02Y1466613I-1661J-1458D01*
G03X1349998Y1466481I150J-132D01*
G01Y1464543D01*
G03X1350048Y1464411I200J0D01*
G02Y1461495I-1661J-1458D01*
G03X1349998Y1461363I150J-132D01*
G01Y1460743D01*
G02X1349796Y1460540I-202J-1D01*
G01X1346976D01*
G02X1346774Y1460743I1J203D01*
G01Y1461363D01*
G03X1346724Y1461495I-200J0D01*
G02Y1464411I1661J1458D01*
G03X1346774Y1464543I-150J132D01*
G01Y1466481D01*
G03X1346724Y1466613I-200J0D01*
G02Y1469529I1661J1458D01*
G03X1346774Y1469661I-150J132D01*
G01Y1470281D01*
G02X1346976Y1470484I202J1D01*
G37*
G36*
G01X1364299D02*
X1367119D01*
G02X1367322Y1470281I0J-203D01*
G01Y1469659D01*
G03X1367372Y1469527I200J0D01*
G02Y1466615I-1664J-1456D01*
G03X1367322Y1466483I150J-132D01*
G01Y1464541D01*
G03X1367372Y1464409I200J0D01*
G02Y1461497I-1664J-1456D01*
G03X1367322Y1461365I150J-132D01*
G01Y1460743D01*
G02X1367119Y1460540I-203J0D01*
G01X1364299D01*
G02X1364096Y1460743I0J203D01*
G01Y1461365D01*
G03X1364046Y1461497I-200J0D01*
G02Y1464409I1664J1456D01*
G03X1364096Y1464541I-150J132D01*
G01Y1466483D01*
G03X1364046Y1466615I-200J0D01*
G02Y1469527I1664J1456D01*
G03X1364096Y1469659I-150J132D01*
G01Y1470281D01*
G02X1364299Y1470484I203J0D01*
G37*
G36*
G01X1485558D02*
X1488378D01*
G02X1488580Y1470281I-1J-203D01*
G01Y1469661D01*
G03X1488630Y1469529I200J0D01*
G02Y1466613I-1661J-1458D01*
G03X1488580Y1466481I150J-132D01*
G01Y1464543D01*
G03X1488630Y1464411I200J0D01*
G02Y1461495I-1661J-1458D01*
G03X1488580Y1461363I150J-132D01*
G01Y1460743D01*
G02X1488378Y1460540I-202J-1D01*
G01X1485558D01*
G02X1485356Y1460743I1J203D01*
G01Y1461363D01*
G03X1485306Y1461495I-200J0D01*
G02Y1464411I1661J1458D01*
G03X1485356Y1464543I-150J132D01*
G01Y1466481D01*
G03X1485306Y1466613I-200J0D01*
G02Y1469529I1661J1458D01*
G03X1485356Y1469661I-150J132D01*
G01Y1470281D01*
G02X1485558Y1470484I202J1D01*
G37*
G36*
G01X1502881D02*
X1505701D01*
G02X1505904Y1470281I0J-203D01*
G01Y1469659D01*
G03X1505954Y1469527I200J0D01*
G02Y1466615I-1664J-1456D01*
G03X1505904Y1466483I150J-132D01*
G01Y1464541D01*
G03X1505954Y1464409I200J0D01*
G02Y1461497I-1664J-1456D01*
G03X1505904Y1461365I150J-132D01*
G01Y1460743D01*
G02X1505701Y1460540I-203J0D01*
G01X1502881D01*
G02X1502678Y1460743I0J203D01*
G01Y1461365D01*
G03X1502628Y1461497I-200J0D01*
G02Y1464409I1664J1456D01*
G03X1502678Y1464541I-150J132D01*
G01Y1466483D01*
G03X1502628Y1466615I-200J0D01*
G02Y1469527I1664J1456D01*
G03X1502678Y1469659I-150J132D01*
G01Y1470281D01*
G02X1502881Y1470484I203J0D01*
G37*
G36*
G01X1520204D02*
X1523024D01*
G02X1523226Y1470281I-1J-203D01*
G01Y1469661D01*
G03X1523276Y1469529I200J0D01*
G02Y1466613I-1661J-1458D01*
G03X1523226Y1466481I150J-132D01*
G01Y1464543D01*
G03X1523276Y1464411I200J0D01*
G02Y1461495I-1661J-1458D01*
G03X1523226Y1461363I150J-132D01*
G01Y1460743D01*
G02X1523024Y1460540I-202J-1D01*
G01X1520204D01*
G02X1520002Y1460743I1J203D01*
G01Y1461363D01*
G03X1519952Y1461495I-200J0D01*
G02Y1464411I1661J1458D01*
G03X1520002Y1464543I-150J132D01*
G01Y1466481D01*
G03X1519952Y1466613I-200J0D01*
G02Y1469529I1661J1458D01*
G03X1520002Y1469661I-150J132D01*
G01Y1470281D01*
G02X1520204Y1470484I202J1D01*
G37*
G36*
G01X1537527D02*
X1540347D01*
G02X1540550Y1470281I0J-203D01*
G01Y1469659D01*
G03X1540600Y1469527I200J0D01*
G02Y1466615I-1664J-1456D01*
G03X1540550Y1466483I150J-132D01*
G01Y1464541D01*
G03X1540600Y1464409I200J0D01*
G02Y1461497I-1664J-1456D01*
G03X1540550Y1461365I150J-132D01*
G01Y1460743D01*
G02X1540347Y1460540I-203J0D01*
G01X1537527D01*
G02X1537324Y1460743I0J203D01*
G01Y1461365D01*
G03X1537274Y1461497I-200J0D01*
G02Y1464409I1664J1456D01*
G03X1537324Y1464541I-150J132D01*
G01Y1466483D01*
G03X1537274Y1466615I-200J0D01*
G02Y1469527I1664J1456D01*
G03X1537324Y1469659I-150J132D01*
G01Y1470281D01*
G02X1537527Y1470484I203J0D01*
G37*
G36*
G01X1693432D02*
X1696252D01*
G02X1696454Y1470281I-1J-203D01*
G01Y1469661D01*
G03X1696504Y1469529I200J0D01*
G02Y1466613I-1661J-1458D01*
G03X1696454Y1466481I150J-132D01*
G01Y1464543D01*
G03X1696504Y1464411I200J0D01*
G02Y1461495I-1661J-1458D01*
G03X1696454Y1461363I150J-132D01*
G01Y1460743D01*
G02X1696252Y1460540I-202J-1D01*
G01X1693432D01*
G02X1693230Y1460743I1J203D01*
G01Y1461363D01*
G03X1693180Y1461495I-200J0D01*
G02Y1464411I1661J1458D01*
G03X1693230Y1464543I-150J132D01*
G01Y1466481D01*
G03X1693180Y1466613I-200J0D01*
G02Y1469529I1661J1458D01*
G03X1693230Y1469661I-150J132D01*
G01Y1470281D01*
G02X1693432Y1470484I202J1D01*
G37*
G36*
G01X1710755D02*
X1713575D01*
G02X1713778Y1470281I0J-203D01*
G01Y1469659D01*
G03X1713828Y1469527I200J0D01*
G02Y1466615I-1664J-1456D01*
G03X1713778Y1466483I150J-132D01*
G01Y1464541D01*
G03X1713828Y1464409I200J0D01*
G02Y1461497I-1664J-1456D01*
G03X1713778Y1461365I150J-132D01*
G01Y1460743D01*
G02X1713575Y1460540I-203J0D01*
G01X1710755D01*
G02X1710552Y1460743I0J203D01*
G01Y1461365D01*
G03X1710502Y1461497I-200J0D01*
G02Y1464409I1664J1456D01*
G03X1710552Y1464541I-150J132D01*
G01Y1466483D01*
G03X1710502Y1466615I-200J0D01*
G02Y1469527I1664J1456D01*
G03X1710552Y1469659I-150J132D01*
G01Y1470281D01*
G02X1710755Y1470484I203J0D01*
G37*
G36*
G01X125795Y1481508D02*
X128615D01*
G02X128818Y1481305I0J-203D01*
G01Y1480683D01*
G03X128868Y1480551I200J0D01*
G02Y1477639I-1664J-1456D01*
G03X128818Y1477507I150J-132D01*
G01Y1475565D01*
G03X128868Y1475433I200J0D01*
G02Y1472521I-1664J-1456D01*
G03X128818Y1472389I150J-132D01*
G01Y1471767D01*
G02X128615Y1471564I-203J0D01*
G01X125795D01*
G02X125592Y1471767I0J203D01*
G01Y1472389D01*
G03X125542Y1472521I-200J0D01*
G02Y1475433I1664J1456D01*
G03X125592Y1475565I-150J132D01*
G01Y1477507D01*
G03X125542Y1477639I-200J0D01*
G02Y1480551I1664J1456D01*
G03X125592Y1480683I-150J132D01*
G01Y1481305D01*
G02X125795Y1481508I203J0D01*
G37*
G36*
G01X143118D02*
X145938D01*
G02X146140Y1481305I-1J-203D01*
G01Y1480685D01*
G03X146190Y1480553I200J0D01*
G02Y1477637I-1661J-1458D01*
G03X146140Y1477505I150J-132D01*
G01Y1475567D01*
G03X146190Y1475435I200J0D01*
G02Y1472519I-1661J-1458D01*
G03X146140Y1472387I150J-132D01*
G01Y1471767D01*
G02X145938Y1471564I-202J-1D01*
G01X143118D01*
G02X142916Y1471767I1J203D01*
G01Y1472387D01*
G03X142866Y1472519I-200J0D01*
G02Y1475435I1661J1458D01*
G03X142916Y1475567I-150J132D01*
G01Y1477505D01*
G03X142866Y1477637I-200J0D01*
G02Y1480553I1661J1458D01*
G03X142916Y1480685I-150J132D01*
G01Y1481305D01*
G02X143118Y1481508I202J1D01*
G37*
G36*
G01X160440D02*
X163260D01*
G02X163462Y1481305I-1J-203D01*
G01Y1480685D01*
G03X163512Y1480553I200J0D01*
G02Y1477637I-1661J-1458D01*
G03X163462Y1477505I150J-132D01*
G01Y1475567D01*
G03X163512Y1475435I200J0D01*
G02Y1472519I-1661J-1458D01*
G03X163462Y1472387I150J-132D01*
G01Y1471767D01*
G02X163260Y1471564I-202J-1D01*
G01X160440D01*
G02X160238Y1471767I1J203D01*
G01Y1472387D01*
G03X160188Y1472519I-200J0D01*
G02Y1475435I1661J1458D01*
G03X160238Y1475567I-150J132D01*
G01Y1477505D01*
G03X160188Y1477637I-200J0D01*
G02Y1480553I1661J1458D01*
G03X160238Y1480685I-150J132D01*
G01Y1481305D01*
G02X160440Y1481508I202J1D01*
G37*
G36*
G01X177763D02*
X180583D01*
G02X180786Y1481305I0J-203D01*
G01Y1480683D01*
G03X180836Y1480551I200J0D01*
G02Y1477639I-1664J-1456D01*
G03X180786Y1477507I150J-132D01*
G01Y1475565D01*
G03X180836Y1475433I200J0D01*
G02Y1472521I-1664J-1456D01*
G03X180786Y1472389I150J-132D01*
G01Y1471767D01*
G02X180583Y1471564I-203J0D01*
G01X177763D01*
G02X177560Y1471767I0J203D01*
G01Y1472389D01*
G03X177510Y1472521I-200J0D01*
G02Y1475433I1664J1456D01*
G03X177560Y1475565I-150J132D01*
G01Y1477507D01*
G03X177510Y1477639I-200J0D01*
G02Y1480551I1664J1456D01*
G03X177560Y1480683I-150J132D01*
G01Y1481305D01*
G02X177763Y1481508I203J0D01*
G37*
G36*
G01X281700D02*
X284520D01*
G02X284722Y1481305I-1J-203D01*
G01Y1480685D01*
G03X284772Y1480553I200J0D01*
G02Y1477637I-1661J-1458D01*
G03X284722Y1477505I150J-132D01*
G01Y1475567D01*
G03X284772Y1475435I200J0D01*
G02Y1472519I-1661J-1458D01*
G03X284722Y1472387I150J-132D01*
G01Y1471767D01*
G02X284520Y1471564I-202J-1D01*
G01X281700D01*
G02X281498Y1471767I1J203D01*
G01Y1472387D01*
G03X281448Y1472519I-200J0D01*
G02Y1475435I1661J1458D01*
G03X281498Y1475567I-150J132D01*
G01Y1477505D01*
G03X281448Y1477637I-200J0D01*
G02Y1480553I1661J1458D01*
G03X281498Y1480685I-150J132D01*
G01Y1481305D01*
G02X281700Y1481508I202J1D01*
G37*
G36*
G01X299023D02*
X301843D01*
G02X302046Y1481305I0J-203D01*
G01Y1480683D01*
G03X302096Y1480551I200J0D01*
G02Y1477639I-1664J-1456D01*
G03X302046Y1477507I150J-132D01*
G01Y1475565D01*
G03X302096Y1475433I200J0D01*
G02Y1472521I-1664J-1456D01*
G03X302046Y1472389I150J-132D01*
G01Y1471767D01*
G02X301843Y1471564I-203J0D01*
G01X299023D01*
G02X298820Y1471767I0J203D01*
G01Y1472389D01*
G03X298770Y1472521I-200J0D01*
G02Y1475433I1664J1456D01*
G03X298820Y1475565I-150J132D01*
G01Y1477507D01*
G03X298770Y1477639I-200J0D01*
G02Y1480551I1664J1456D01*
G03X298820Y1480683I-150J132D01*
G01Y1481305D01*
G02X299023Y1481508I203J0D01*
G37*
G36*
G01X454929D02*
X457749D01*
G02X457952Y1481305I0J-203D01*
G01Y1480683D01*
G03X458002Y1480551I200J0D01*
G02Y1477639I-1664J-1456D01*
G03X457952Y1477507I150J-132D01*
G01Y1475565D01*
G03X458002Y1475433I200J0D01*
G02Y1472521I-1664J-1456D01*
G03X457952Y1472389I150J-132D01*
G01Y1471767D01*
G02X457749Y1471564I-203J0D01*
G01X454929D01*
G02X454726Y1471767I0J203D01*
G01Y1472389D01*
G03X454676Y1472521I-200J0D01*
G02Y1475433I1664J1456D01*
G03X454726Y1475565I-150J132D01*
G01Y1477507D01*
G03X454676Y1477639I-200J0D01*
G02Y1480551I1664J1456D01*
G03X454726Y1480683I-150J132D01*
G01Y1481305D01*
G02X454929Y1481508I203J0D01*
G37*
G36*
G01X472252D02*
X475072D01*
G02X475274Y1481305I-1J-203D01*
G01Y1480685D01*
G03X475324Y1480553I200J0D01*
G02Y1477637I-1661J-1458D01*
G03X475274Y1477505I150J-132D01*
G01Y1475567D01*
G03X475324Y1475435I200J0D01*
G02Y1472519I-1661J-1458D01*
G03X475274Y1472387I150J-132D01*
G01Y1471767D01*
G02X475072Y1471564I-202J-1D01*
G01X472252D01*
G02X472050Y1471767I1J203D01*
G01Y1472387D01*
G03X472000Y1472519I-200J0D01*
G02Y1475435I1661J1458D01*
G03X472050Y1475567I-150J132D01*
G01Y1477505D01*
G03X472000Y1477637I-200J0D01*
G02Y1480553I1661J1458D01*
G03X472050Y1480685I-150J132D01*
G01Y1481305D01*
G02X472252Y1481508I202J1D01*
G37*
G36*
G01X489575D02*
X492395D01*
G02X492598Y1481305I0J-203D01*
G01Y1480683D01*
G03X492648Y1480551I200J0D01*
G02Y1477639I-1664J-1456D01*
G03X492598Y1477507I150J-132D01*
G01Y1475565D01*
G03X492648Y1475433I200J0D01*
G02Y1472521I-1664J-1456D01*
G03X492598Y1472389I150J-132D01*
G01Y1471767D01*
G02X492395Y1471564I-203J0D01*
G01X489575D01*
G02X489372Y1471767I0J203D01*
G01Y1472389D01*
G03X489322Y1472521I-200J0D01*
G02Y1475433I1664J1456D01*
G03X489372Y1475565I-150J132D01*
G01Y1477507D01*
G03X489322Y1477639I-200J0D01*
G02Y1480551I1664J1456D01*
G03X489372Y1480683I-150J132D01*
G01Y1481305D01*
G02X489575Y1481508I203J0D01*
G37*
G36*
G01X506897D02*
X509717D01*
G02X509920Y1481305I0J-203D01*
G01Y1480683D01*
G03X509970Y1480551I200J0D01*
G02Y1477639I-1664J-1456D01*
G03X509920Y1477507I150J-132D01*
G01Y1475565D01*
G03X509970Y1475433I200J0D01*
G02Y1472521I-1664J-1456D01*
G03X509920Y1472389I150J-132D01*
G01Y1471767D01*
G02X509717Y1471564I-203J0D01*
G01X506897D01*
G02X506694Y1471767I0J203D01*
G01Y1472389D01*
G03X506644Y1472521I-200J0D01*
G02Y1475433I1664J1456D01*
G03X506694Y1475565I-150J132D01*
G01Y1477507D01*
G03X506644Y1477639I-200J0D01*
G02Y1480551I1664J1456D01*
G03X506694Y1480683I-150J132D01*
G01Y1481305D01*
G02X506897Y1481508I203J0D01*
G37*
G36*
G01X645480D02*
X648300D01*
G02X648502Y1481305I-1J-203D01*
G01Y1480685D01*
G03X648552Y1480553I200J0D01*
G02Y1477637I-1661J-1458D01*
G03X648502Y1477505I150J-132D01*
G01Y1475567D01*
G03X648552Y1475435I200J0D01*
G02Y1472519I-1661J-1458D01*
G03X648502Y1472387I150J-132D01*
G01Y1471767D01*
G02X648300Y1471564I-202J-1D01*
G01X645480D01*
G02X645278Y1471767I1J203D01*
G01Y1472387D01*
G03X645228Y1472519I-200J0D01*
G02Y1475435I1661J1458D01*
G03X645278Y1475567I-150J132D01*
G01Y1477505D01*
G03X645228Y1477637I-200J0D01*
G02Y1480553I1661J1458D01*
G03X645278Y1480685I-150J132D01*
G01Y1481305D01*
G02X645480Y1481508I202J1D01*
G37*
G36*
G01X662803D02*
X665623D01*
G02X665826Y1481305I0J-203D01*
G01Y1480683D01*
G03X665876Y1480551I200J0D01*
G02Y1477639I-1664J-1456D01*
G03X665826Y1477507I150J-132D01*
G01Y1475565D01*
G03X665876Y1475433I200J0D01*
G02Y1472521I-1664J-1456D01*
G03X665826Y1472389I150J-132D01*
G01Y1471767D01*
G02X665623Y1471564I-203J0D01*
G01X662803D01*
G02X662600Y1471767I0J203D01*
G01Y1472389D01*
G03X662550Y1472521I-200J0D01*
G02Y1475433I1664J1456D01*
G03X662600Y1475565I-150J132D01*
G01Y1477507D01*
G03X662550Y1477639I-200J0D01*
G02Y1480551I1664J1456D01*
G03X662600Y1480683I-150J132D01*
G01Y1481305D01*
G02X662803Y1481508I203J0D01*
G37*
G36*
G01X680125D02*
X682945D01*
G02X683148Y1481305I0J-203D01*
G01Y1480683D01*
G03X683198Y1480551I200J0D01*
G02Y1477639I-1664J-1456D01*
G03X683148Y1477507I150J-132D01*
G01Y1475565D01*
G03X683198Y1475433I200J0D01*
G02Y1472521I-1664J-1456D01*
G03X683148Y1472389I150J-132D01*
G01Y1471767D01*
G02X682945Y1471564I-203J0D01*
G01X680125D01*
G02X679922Y1471767I0J203D01*
G01Y1472389D01*
G03X679872Y1472521I-200J0D01*
G02Y1475433I1664J1456D01*
G03X679922Y1475565I-150J132D01*
G01Y1477507D01*
G03X679872Y1477639I-200J0D01*
G02Y1480551I1664J1456D01*
G03X679922Y1480683I-150J132D01*
G01Y1481305D01*
G02X680125Y1481508I203J0D01*
G37*
G36*
G01X1165086D02*
X1167906D01*
G02X1168108Y1481305I-1J-203D01*
G01Y1480685D01*
G03X1168158Y1480553I200J0D01*
G02Y1477637I-1661J-1458D01*
G03X1168108Y1477505I150J-132D01*
G01Y1475567D01*
G03X1168158Y1475435I200J0D01*
G02Y1472519I-1661J-1458D01*
G03X1168108Y1472387I150J-132D01*
G01Y1471767D01*
G02X1167906Y1471564I-202J-1D01*
G01X1165086D01*
G02X1164884Y1471767I1J203D01*
G01Y1472387D01*
G03X1164834Y1472519I-200J0D01*
G02Y1475435I1661J1458D01*
G03X1164884Y1475567I-150J132D01*
G01Y1477505D01*
G03X1164834Y1477637I-200J0D01*
G02Y1480553I1661J1458D01*
G03X1164884Y1480685I-150J132D01*
G01Y1481305D01*
G02X1165086Y1481508I202J1D01*
G37*
G36*
G01X1182408D02*
X1185228D01*
G02X1185430Y1481305I-1J-203D01*
G01Y1480685D01*
G03X1185480Y1480553I200J0D01*
G02Y1477637I-1661J-1458D01*
G03X1185430Y1477505I150J-132D01*
G01Y1475567D01*
G03X1185480Y1475435I200J0D01*
G02Y1472519I-1661J-1458D01*
G03X1185430Y1472387I150J-132D01*
G01Y1471767D01*
G02X1185228Y1471564I-202J-1D01*
G01X1182408D01*
G02X1182206Y1471767I1J203D01*
G01Y1472387D01*
G03X1182156Y1472519I-200J0D01*
G02Y1475435I1661J1458D01*
G03X1182206Y1475567I-150J132D01*
G01Y1477505D01*
G03X1182156Y1477637I-200J0D01*
G02Y1480553I1661J1458D01*
G03X1182206Y1480685I-150J132D01*
G01Y1481305D01*
G02X1182408Y1481508I202J1D01*
G37*
G36*
G01X1303669D02*
X1306489D01*
G02X1306692Y1481305I0J-203D01*
G01Y1480683D01*
G03X1306742Y1480551I200J0D01*
G02Y1477639I-1664J-1456D01*
G03X1306692Y1477507I150J-132D01*
G01Y1475565D01*
G03X1306742Y1475433I200J0D01*
G02Y1472521I-1664J-1456D01*
G03X1306692Y1472389I150J-132D01*
G01Y1471767D01*
G02X1306489Y1471564I-203J0D01*
G01X1303669D01*
G02X1303466Y1471767I0J203D01*
G01Y1472389D01*
G03X1303416Y1472521I-200J0D01*
G02Y1475433I1664J1456D01*
G03X1303466Y1475565I-150J132D01*
G01Y1477507D01*
G03X1303416Y1477639I-200J0D01*
G02Y1480551I1664J1456D01*
G03X1303466Y1480683I-150J132D01*
G01Y1481305D01*
G02X1303669Y1481508I203J0D01*
G37*
G36*
G01X1320992D02*
X1323812D01*
G02X1324014Y1481305I-1J-203D01*
G01Y1480685D01*
G03X1324064Y1480553I200J0D01*
G02Y1477637I-1661J-1458D01*
G03X1324014Y1477505I150J-132D01*
G01Y1475567D01*
G03X1324064Y1475435I200J0D01*
G02Y1472519I-1661J-1458D01*
G03X1324014Y1472387I150J-132D01*
G01Y1471767D01*
G02X1323812Y1471564I-202J-1D01*
G01X1320992D01*
G02X1320790Y1471767I1J203D01*
G01Y1472387D01*
G03X1320740Y1472519I-200J0D01*
G02Y1475435I1661J1458D01*
G03X1320790Y1475567I-150J132D01*
G01Y1477505D01*
G03X1320740Y1477637I-200J0D01*
G02Y1480553I1661J1458D01*
G03X1320790Y1480685I-150J132D01*
G01Y1481305D01*
G02X1320992Y1481508I202J1D01*
G37*
G36*
G01X1338315D02*
X1341135D01*
G02X1341338Y1481305I0J-203D01*
G01Y1480683D01*
G03X1341388Y1480551I200J0D01*
G02Y1477639I-1664J-1456D01*
G03X1341338Y1477507I150J-132D01*
G01Y1475565D01*
G03X1341388Y1475433I200J0D01*
G02Y1472521I-1664J-1456D01*
G03X1341338Y1472389I150J-132D01*
G01Y1471767D01*
G02X1341135Y1471564I-203J0D01*
G01X1338315D01*
G02X1338112Y1471767I0J203D01*
G01Y1472389D01*
G03X1338062Y1472521I-200J0D01*
G02Y1475433I1664J1456D01*
G03X1338112Y1475565I-150J132D01*
G01Y1477507D01*
G03X1338062Y1477639I-200J0D01*
G02Y1480551I1664J1456D01*
G03X1338112Y1480683I-150J132D01*
G01Y1481305D01*
G02X1338315Y1481508I203J0D01*
G37*
G36*
G01X1355637D02*
X1358457D01*
G02X1358660Y1481305I0J-203D01*
G01Y1480683D01*
G03X1358710Y1480551I200J0D01*
G02Y1477639I-1664J-1456D01*
G03X1358660Y1477507I150J-132D01*
G01Y1475565D01*
G03X1358710Y1475433I200J0D01*
G02Y1472521I-1664J-1456D01*
G03X1358660Y1472389I150J-132D01*
G01Y1471767D01*
G02X1358457Y1471564I-203J0D01*
G01X1355637D01*
G02X1355434Y1471767I0J203D01*
G01Y1472389D01*
G03X1355384Y1472521I-200J0D01*
G02Y1475433I1664J1456D01*
G03X1355434Y1475565I-150J132D01*
G01Y1477507D01*
G03X1355384Y1477639I-200J0D01*
G02Y1480551I1664J1456D01*
G03X1355434Y1480683I-150J132D01*
G01Y1481305D01*
G02X1355637Y1481508I203J0D01*
G37*
G36*
G01X1476897D02*
X1479717D01*
G02X1479920Y1481305I0J-203D01*
G01Y1480683D01*
G03X1479970Y1480551I200J0D01*
G02Y1477639I-1664J-1456D01*
G03X1479920Y1477507I150J-132D01*
G01Y1475565D01*
G03X1479970Y1475433I200J0D01*
G02Y1472521I-1664J-1456D01*
G03X1479920Y1472389I150J-132D01*
G01Y1471767D01*
G02X1479717Y1471564I-203J0D01*
G01X1476897D01*
G02X1476694Y1471767I0J203D01*
G01Y1472389D01*
G03X1476644Y1472521I-200J0D01*
G02Y1475433I1664J1456D01*
G03X1476694Y1475565I-150J132D01*
G01Y1477507D01*
G03X1476644Y1477639I-200J0D01*
G02Y1480551I1664J1456D01*
G03X1476694Y1480683I-150J132D01*
G01Y1481305D01*
G02X1476897Y1481508I203J0D01*
G37*
G36*
G01X1494220D02*
X1497040D01*
G02X1497242Y1481305I-1J-203D01*
G01Y1480685D01*
G03X1497292Y1480553I200J0D01*
G02Y1477637I-1661J-1458D01*
G03X1497242Y1477505I150J-132D01*
G01Y1475567D01*
G03X1497292Y1475435I200J0D01*
G02Y1472519I-1661J-1458D01*
G03X1497242Y1472387I150J-132D01*
G01Y1471767D01*
G02X1497040Y1471564I-202J-1D01*
G01X1494220D01*
G02X1494018Y1471767I1J203D01*
G01Y1472387D01*
G03X1493968Y1472519I-200J0D01*
G02Y1475435I1661J1458D01*
G03X1494018Y1475567I-150J132D01*
G01Y1477505D01*
G03X1493968Y1477637I-200J0D01*
G02Y1480553I1661J1458D01*
G03X1494018Y1480685I-150J132D01*
G01Y1481305D01*
G02X1494220Y1481508I202J1D01*
G37*
G36*
G01X1511543D02*
X1514363D01*
G02X1514566Y1481305I0J-203D01*
G01Y1480683D01*
G03X1514616Y1480551I200J0D01*
G02Y1477639I-1664J-1456D01*
G03X1514566Y1477507I150J-132D01*
G01Y1475565D01*
G03X1514616Y1475433I200J0D01*
G02Y1472521I-1664J-1456D01*
G03X1514566Y1472389I150J-132D01*
G01Y1471767D01*
G02X1514363Y1471564I-203J0D01*
G01X1511543D01*
G02X1511340Y1471767I0J203D01*
G01Y1472389D01*
G03X1511290Y1472521I-200J0D01*
G02Y1475433I1664J1456D01*
G03X1511340Y1475565I-150J132D01*
G01Y1477507D01*
G03X1511290Y1477639I-200J0D01*
G02Y1480551I1664J1456D01*
G03X1511340Y1480683I-150J132D01*
G01Y1481305D01*
G02X1511543Y1481508I203J0D01*
G37*
G36*
G01X1528865D02*
X1531685D01*
G02X1531888Y1481305I0J-203D01*
G01Y1480683D01*
G03X1531938Y1480551I200J0D01*
G02Y1477639I-1664J-1456D01*
G03X1531888Y1477507I150J-132D01*
G01Y1475565D01*
G03X1531938Y1475433I200J0D01*
G02Y1472521I-1664J-1456D01*
G03X1531888Y1472389I150J-132D01*
G01Y1471767D01*
G02X1531685Y1471564I-203J0D01*
G01X1528865D01*
G02X1528662Y1471767I0J203D01*
G01Y1472389D01*
G03X1528612Y1472521I-200J0D01*
G02Y1475433I1664J1456D01*
G03X1528662Y1475565I-150J132D01*
G01Y1477507D01*
G03X1528612Y1477639I-200J0D01*
G02Y1480551I1664J1456D01*
G03X1528662Y1480683I-150J132D01*
G01Y1481305D01*
G02X1528865Y1481508I203J0D01*
G37*
G36*
G01X1684771D02*
X1687591D01*
G02X1687794Y1481305I0J-203D01*
G01Y1480683D01*
G03X1687844Y1480551I200J0D01*
G02Y1477639I-1664J-1456D01*
G03X1687794Y1477507I150J-132D01*
G01Y1475565D01*
G03X1687844Y1475433I200J0D01*
G02Y1472521I-1664J-1456D01*
G03X1687794Y1472389I150J-132D01*
G01Y1471767D01*
G02X1687591Y1471564I-203J0D01*
G01X1684771D01*
G02X1684568Y1471767I0J203D01*
G01Y1472389D01*
G03X1684518Y1472521I-200J0D01*
G02Y1475433I1664J1456D01*
G03X1684568Y1475565I-150J132D01*
G01Y1477507D01*
G03X1684518Y1477639I-200J0D01*
G02Y1480551I1664J1456D01*
G03X1684568Y1480683I-150J132D01*
G01Y1481305D01*
G02X1684771Y1481508I203J0D01*
G37*
G36*
G01X1702093D02*
X1704913D01*
G02X1705116Y1481305I0J-203D01*
G01Y1480683D01*
G03X1705166Y1480551I200J0D01*
G02Y1477639I-1664J-1456D01*
G03X1705116Y1477507I150J-132D01*
G01Y1475565D01*
G03X1705166Y1475433I200J0D01*
G02Y1472521I-1664J-1456D01*
G03X1705116Y1472389I150J-132D01*
G01Y1471767D01*
G02X1704913Y1471564I-203J0D01*
G01X1702093D01*
G02X1701890Y1471767I0J203D01*
G01Y1472389D01*
G03X1701840Y1472521I-200J0D01*
G02Y1475433I1664J1456D01*
G03X1701890Y1475565I-150J132D01*
G01Y1477507D01*
G03X1701840Y1477639I-200J0D01*
G02Y1480551I1664J1456D01*
G03X1701890Y1480683I-150J132D01*
G01Y1481305D01*
G02X1702093Y1481508I203J0D01*
G37*
G36*
G01X134456Y1485838D02*
X137276D01*
G02X137478Y1485635I-1J-203D01*
G01Y1485016D01*
G03X137528Y1484884I200J0D01*
G02Y1481968I-1661J-1458D01*
G03X137478Y1481836I150J-132D01*
G01Y1479898D01*
G03X137528Y1479766I200J0D01*
G02Y1476850I-1661J-1458D01*
G03X137478Y1476718I150J-132D01*
G01Y1476097D01*
G02X137276Y1475894I-202J-1D01*
G01X134456D01*
G02X134254Y1476097I1J203D01*
G01Y1476718D01*
G03X134204Y1476850I-200J0D01*
G02Y1479766I1661J1458D01*
G03X134254Y1479898I-150J132D01*
G01Y1481836D01*
G03X134204Y1481968I-200J0D01*
G02Y1484884I1661J1458D01*
G03X134254Y1485016I-150J132D01*
G01Y1485635D01*
G02X134456Y1485838I202J1D01*
G37*
G36*
G01X151779D02*
X154599D01*
G02X154802Y1485635I0J-203D01*
G01Y1485014D01*
G03X154852Y1484882I200J0D01*
G02Y1481970I-1664J-1456D01*
G03X154802Y1481838I150J-132D01*
G01Y1479896D01*
G03X154852Y1479764I200J0D01*
G02Y1476852I-1664J-1456D01*
G03X154802Y1476720I150J-132D01*
G01Y1476097D01*
G02X154599Y1475894I-203J0D01*
G01X151779D01*
G02X151576Y1476097I0J203D01*
G01Y1476720D01*
G03X151526Y1476852I-200J0D01*
G02Y1479764I1664J1456D01*
G03X151576Y1479896I-150J132D01*
G01Y1481838D01*
G03X151526Y1481970I-200J0D01*
G02Y1484882I1664J1456D01*
G03X151576Y1485014I-150J132D01*
G01Y1485635D01*
G02X151779Y1485838I203J0D01*
G37*
G36*
G01X169102D02*
X171922D01*
G02X172124Y1485635I-1J-203D01*
G01Y1485016D01*
G03X172174Y1484884I200J0D01*
G02Y1481968I-1661J-1458D01*
G03X172124Y1481836I150J-132D01*
G01Y1479898D01*
G03X172174Y1479766I200J0D01*
G02Y1476850I-1661J-1458D01*
G03X172124Y1476718I150J-132D01*
G01Y1476097D01*
G02X171922Y1475894I-202J-1D01*
G01X169102D01*
G02X168900Y1476097I1J203D01*
G01Y1476718D01*
G03X168850Y1476850I-200J0D01*
G02Y1479766I1661J1458D01*
G03X168900Y1479898I-150J132D01*
G01Y1481836D01*
G03X168850Y1481968I-200J0D01*
G02Y1484884I1661J1458D01*
G03X168900Y1485016I-150J132D01*
G01Y1485635D01*
G02X169102Y1485838I202J1D01*
G37*
G36*
G01X290361D02*
X293181D01*
G02X293384Y1485635I0J-203D01*
G01Y1485014D01*
G03X293434Y1484882I200J0D01*
G02Y1481970I-1664J-1456D01*
G03X293384Y1481838I150J-132D01*
G01Y1479896D01*
G03X293434Y1479764I200J0D01*
G02Y1476852I-1664J-1456D01*
G03X293384Y1476720I150J-132D01*
G01Y1476097D01*
G02X293181Y1475894I-203J0D01*
G01X290361D01*
G02X290158Y1476097I0J203D01*
G01Y1476720D01*
G03X290108Y1476852I-200J0D01*
G02Y1479764I1664J1456D01*
G03X290158Y1479896I-150J132D01*
G01Y1481838D01*
G03X290108Y1481970I-200J0D01*
G02Y1484882I1664J1456D01*
G03X290158Y1485014I-150J132D01*
G01Y1485635D01*
G02X290361Y1485838I203J0D01*
G37*
G36*
G01X463590D02*
X466410D01*
G02X466612Y1485635I-1J-203D01*
G01Y1485016D01*
G03X466662Y1484884I200J0D01*
G02Y1481968I-1661J-1458D01*
G03X466612Y1481836I150J-132D01*
G01Y1479898D01*
G03X466662Y1479766I200J0D01*
G02Y1476850I-1661J-1458D01*
G03X466612Y1476718I150J-132D01*
G01Y1476097D01*
G02X466410Y1475894I-202J-1D01*
G01X463590D01*
G02X463388Y1476097I1J203D01*
G01Y1476718D01*
G03X463338Y1476850I-200J0D01*
G02Y1479766I1661J1458D01*
G03X463388Y1479898I-150J132D01*
G01Y1481836D01*
G03X463338Y1481968I-200J0D01*
G02Y1484884I1661J1458D01*
G03X463388Y1485016I-150J132D01*
G01Y1485635D01*
G02X463590Y1485838I202J1D01*
G37*
G36*
G01X480913D02*
X483733D01*
G02X483936Y1485635I0J-203D01*
G01Y1485014D01*
G03X483986Y1484882I200J0D01*
G02Y1481970I-1664J-1456D01*
G03X483936Y1481838I150J-132D01*
G01Y1479896D01*
G03X483986Y1479764I200J0D01*
G02Y1476852I-1664J-1456D01*
G03X483936Y1476720I150J-132D01*
G01Y1476097D01*
G02X483733Y1475894I-203J0D01*
G01X480913D01*
G02X480710Y1476097I0J203D01*
G01Y1476720D01*
G03X480660Y1476852I-200J0D01*
G02Y1479764I1664J1456D01*
G03X480710Y1479896I-150J132D01*
G01Y1481838D01*
G03X480660Y1481970I-200J0D01*
G02Y1484882I1664J1456D01*
G03X480710Y1485014I-150J132D01*
G01Y1485635D01*
G02X480913Y1485838I203J0D01*
G37*
G36*
G01X498236D02*
X501056D01*
G02X501258Y1485635I-1J-203D01*
G01Y1485016D01*
G03X501308Y1484884I200J0D01*
G02Y1481968I-1661J-1458D01*
G03X501258Y1481836I150J-132D01*
G01Y1479898D01*
G03X501308Y1479766I200J0D01*
G02Y1476850I-1661J-1458D01*
G03X501258Y1476718I150J-132D01*
G01Y1476097D01*
G02X501056Y1475894I-202J-1D01*
G01X498236D01*
G02X498034Y1476097I1J203D01*
G01Y1476718D01*
G03X497984Y1476850I-200J0D01*
G02Y1479766I1661J1458D01*
G03X498034Y1479898I-150J132D01*
G01Y1481836D01*
G03X497984Y1481968I-200J0D01*
G02Y1484884I1661J1458D01*
G03X498034Y1485016I-150J132D01*
G01Y1485635D01*
G02X498236Y1485838I202J1D01*
G37*
G36*
G01X515559D02*
X518379D01*
G02X518582Y1485635I0J-203D01*
G01Y1485014D01*
G03X518632Y1484882I200J0D01*
G02Y1481970I-1664J-1456D01*
G03X518582Y1481838I150J-132D01*
G01Y1479896D01*
G03X518632Y1479764I200J0D01*
G02Y1476852I-1664J-1456D01*
G03X518582Y1476720I150J-132D01*
G01Y1476097D01*
G02X518379Y1475894I-203J0D01*
G01X515559D01*
G02X515356Y1476097I0J203D01*
G01Y1476720D01*
G03X515306Y1476852I-200J0D01*
G02Y1479764I1664J1456D01*
G03X515356Y1479896I-150J132D01*
G01Y1481838D01*
G03X515306Y1481970I-200J0D01*
G02Y1484882I1664J1456D01*
G03X515356Y1485014I-150J132D01*
G01Y1485635D01*
G02X515559Y1485838I203J0D01*
G37*
G36*
G01X654141D02*
X656961D01*
G02X657164Y1485635I0J-203D01*
G01Y1485014D01*
G03X657214Y1484882I200J0D01*
G02Y1481970I-1664J-1456D01*
G03X657164Y1481838I150J-132D01*
G01Y1479896D01*
G03X657214Y1479764I200J0D01*
G02Y1476852I-1664J-1456D01*
G03X657164Y1476720I150J-132D01*
G01Y1476097D01*
G02X656961Y1475894I-203J0D01*
G01X654141D01*
G02X653938Y1476097I0J203D01*
G01Y1476720D01*
G03X653888Y1476852I-200J0D01*
G02Y1479764I1664J1456D01*
G03X653938Y1479896I-150J132D01*
G01Y1481838D01*
G03X653888Y1481970I-200J0D01*
G02Y1484882I1664J1456D01*
G03X653938Y1485014I-150J132D01*
G01Y1485635D01*
G02X654141Y1485838I203J0D01*
G37*
G36*
G01X671464D02*
X674284D01*
G02X674486Y1485635I-1J-203D01*
G01Y1485016D01*
G03X674536Y1484884I200J0D01*
G02Y1481968I-1661J-1458D01*
G03X674486Y1481836I150J-132D01*
G01Y1479898D01*
G03X674536Y1479766I200J0D01*
G02Y1476850I-1661J-1458D01*
G03X674486Y1476718I150J-132D01*
G01Y1476097D01*
G02X674284Y1475894I-202J-1D01*
G01X671464D01*
G02X671262Y1476097I1J203D01*
G01Y1476718D01*
G03X671212Y1476850I-200J0D01*
G02Y1479766I1661J1458D01*
G03X671262Y1479898I-150J132D01*
G01Y1481836D01*
G03X671212Y1481968I-200J0D01*
G02Y1484884I1661J1458D01*
G03X671262Y1485016I-150J132D01*
G01Y1485635D01*
G02X671464Y1485838I202J1D01*
G37*
G36*
G01X688787D02*
X691607D01*
G02X691810Y1485635I0J-203D01*
G01Y1485014D01*
G03X691860Y1484882I200J0D01*
G02Y1481970I-1664J-1456D01*
G03X691810Y1481838I150J-132D01*
G01Y1479896D01*
G03X691860Y1479764I200J0D01*
G02Y1476852I-1664J-1456D01*
G03X691810Y1476720I150J-132D01*
G01Y1476097D01*
G02X691607Y1475894I-203J0D01*
G01X688787D01*
G02X688584Y1476097I0J203D01*
G01Y1476720D01*
G03X688534Y1476852I-200J0D01*
G02Y1479764I1664J1456D01*
G03X688584Y1479896I-150J132D01*
G01Y1481838D01*
G03X688534Y1481970I-200J0D01*
G02Y1484882I1664J1456D01*
G03X688584Y1485014I-150J132D01*
G01Y1485635D01*
G02X688787Y1485838I203J0D01*
G37*
G36*
G01X1173747D02*
X1176567D01*
G02X1176770Y1485635I0J-203D01*
G01Y1485014D01*
G03X1176820Y1484882I200J0D01*
G02Y1481970I-1664J-1456D01*
G03X1176770Y1481838I150J-132D01*
G01Y1479896D01*
G03X1176820Y1479764I200J0D01*
G02Y1476852I-1664J-1456D01*
G03X1176770Y1476720I150J-132D01*
G01Y1476097D01*
G02X1176567Y1475894I-203J0D01*
G01X1173747D01*
G02X1173544Y1476097I0J203D01*
G01Y1476720D01*
G03X1173494Y1476852I-200J0D01*
G02Y1479764I1664J1456D01*
G03X1173544Y1479896I-150J132D01*
G01Y1481838D01*
G03X1173494Y1481970I-200J0D01*
G02Y1484882I1664J1456D01*
G03X1173544Y1485014I-150J132D01*
G01Y1485635D01*
G02X1173747Y1485838I203J0D01*
G37*
G36*
G01X1191070D02*
X1193890D01*
G02X1194092Y1485635I-1J-203D01*
G01Y1485016D01*
G03X1194142Y1484884I200J0D01*
G02Y1481968I-1661J-1458D01*
G03X1194092Y1481836I150J-132D01*
G01Y1479898D01*
G03X1194142Y1479766I200J0D01*
G02Y1476850I-1661J-1458D01*
G03X1194092Y1476718I150J-132D01*
G01Y1476097D01*
G02X1193890Y1475894I-202J-1D01*
G01X1191070D01*
G02X1190868Y1476097I1J203D01*
G01Y1476718D01*
G03X1190818Y1476850I-200J0D01*
G02Y1479766I1661J1458D01*
G03X1190868Y1479898I-150J132D01*
G01Y1481836D01*
G03X1190818Y1481968I-200J0D01*
G02Y1484884I1661J1458D01*
G03X1190868Y1485016I-150J132D01*
G01Y1485635D01*
G02X1191070Y1485838I202J1D01*
G37*
G36*
G01X1312330D02*
X1315150D01*
G02X1315352Y1485635I-1J-203D01*
G01Y1485016D01*
G03X1315402Y1484884I200J0D01*
G02Y1481968I-1661J-1458D01*
G03X1315352Y1481836I150J-132D01*
G01Y1479898D01*
G03X1315402Y1479766I200J0D01*
G02Y1476850I-1661J-1458D01*
G03X1315352Y1476718I150J-132D01*
G01Y1476097D01*
G02X1315150Y1475894I-202J-1D01*
G01X1312330D01*
G02X1312128Y1476097I1J203D01*
G01Y1476718D01*
G03X1312078Y1476850I-200J0D01*
G02Y1479766I1661J1458D01*
G03X1312128Y1479898I-150J132D01*
G01Y1481836D01*
G03X1312078Y1481968I-200J0D01*
G02Y1484884I1661J1458D01*
G03X1312128Y1485016I-150J132D01*
G01Y1485635D01*
G02X1312330Y1485838I202J1D01*
G37*
G36*
G01X1329653D02*
X1332473D01*
G02X1332676Y1485635I0J-203D01*
G01Y1485014D01*
G03X1332726Y1484882I200J0D01*
G02Y1481970I-1664J-1456D01*
G03X1332676Y1481838I150J-132D01*
G01Y1479896D01*
G03X1332726Y1479764I200J0D01*
G02Y1476852I-1664J-1456D01*
G03X1332676Y1476720I150J-132D01*
G01Y1476097D01*
G02X1332473Y1475894I-203J0D01*
G01X1329653D01*
G02X1329450Y1476097I0J203D01*
G01Y1476720D01*
G03X1329400Y1476852I-200J0D01*
G02Y1479764I1664J1456D01*
G03X1329450Y1479896I-150J132D01*
G01Y1481838D01*
G03X1329400Y1481970I-200J0D01*
G02Y1484882I1664J1456D01*
G03X1329450Y1485014I-150J132D01*
G01Y1485635D01*
G02X1329653Y1485838I203J0D01*
G37*
G36*
G01X1346976D02*
X1349796D01*
G02X1349998Y1485635I-1J-203D01*
G01Y1485016D01*
G03X1350048Y1484884I200J0D01*
G02Y1481968I-1661J-1458D01*
G03X1349998Y1481836I150J-132D01*
G01Y1479898D01*
G03X1350048Y1479766I200J0D01*
G02Y1476850I-1661J-1458D01*
G03X1349998Y1476718I150J-132D01*
G01Y1476097D01*
G02X1349796Y1475894I-202J-1D01*
G01X1346976D01*
G02X1346774Y1476097I1J203D01*
G01Y1476718D01*
G03X1346724Y1476850I-200J0D01*
G02Y1479766I1661J1458D01*
G03X1346774Y1479898I-150J132D01*
G01Y1481836D01*
G03X1346724Y1481968I-200J0D01*
G02Y1484884I1661J1458D01*
G03X1346774Y1485016I-150J132D01*
G01Y1485635D01*
G02X1346976Y1485838I202J1D01*
G37*
G36*
G01X1364299D02*
X1367119D01*
G02X1367322Y1485635I0J-203D01*
G01Y1485014D01*
G03X1367372Y1484882I200J0D01*
G02Y1481970I-1664J-1456D01*
G03X1367322Y1481838I150J-132D01*
G01Y1479896D01*
G03X1367372Y1479764I200J0D01*
G02Y1476852I-1664J-1456D01*
G03X1367322Y1476720I150J-132D01*
G01Y1476097D01*
G02X1367119Y1475894I-203J0D01*
G01X1364299D01*
G02X1364096Y1476097I0J203D01*
G01Y1476720D01*
G03X1364046Y1476852I-200J0D01*
G02Y1479764I1664J1456D01*
G03X1364096Y1479896I-150J132D01*
G01Y1481838D01*
G03X1364046Y1481970I-200J0D01*
G02Y1484882I1664J1456D01*
G03X1364096Y1485014I-150J132D01*
G01Y1485635D01*
G02X1364299Y1485838I203J0D01*
G37*
G36*
G01X1485558D02*
X1488378D01*
G02X1488580Y1485635I-1J-203D01*
G01Y1485016D01*
G03X1488630Y1484884I200J0D01*
G02Y1481968I-1661J-1458D01*
G03X1488580Y1481836I150J-132D01*
G01Y1479898D01*
G03X1488630Y1479766I200J0D01*
G02Y1476850I-1661J-1458D01*
G03X1488580Y1476718I150J-132D01*
G01Y1476097D01*
G02X1488378Y1475894I-202J-1D01*
G01X1485558D01*
G02X1485356Y1476097I1J203D01*
G01Y1476718D01*
G03X1485306Y1476850I-200J0D01*
G02Y1479766I1661J1458D01*
G03X1485356Y1479898I-150J132D01*
G01Y1481836D01*
G03X1485306Y1481968I-200J0D01*
G02Y1484884I1661J1458D01*
G03X1485356Y1485016I-150J132D01*
G01Y1485635D01*
G02X1485558Y1485838I202J1D01*
G37*
G36*
G01X1502881D02*
X1505701D01*
G02X1505904Y1485635I0J-203D01*
G01Y1485014D01*
G03X1505954Y1484882I200J0D01*
G02Y1481970I-1664J-1456D01*
G03X1505904Y1481838I150J-132D01*
G01Y1479896D01*
G03X1505954Y1479764I200J0D01*
G02Y1476852I-1664J-1456D01*
G03X1505904Y1476720I150J-132D01*
G01Y1476097D01*
G02X1505701Y1475894I-203J0D01*
G01X1502881D01*
G02X1502678Y1476097I0J203D01*
G01Y1476720D01*
G03X1502628Y1476852I-200J0D01*
G02Y1479764I1664J1456D01*
G03X1502678Y1479896I-150J132D01*
G01Y1481838D01*
G03X1502628Y1481970I-200J0D01*
G02Y1484882I1664J1456D01*
G03X1502678Y1485014I-150J132D01*
G01Y1485635D01*
G02X1502881Y1485838I203J0D01*
G37*
G36*
G01X1520204D02*
X1523024D01*
G02X1523226Y1485635I-1J-203D01*
G01Y1485016D01*
G03X1523276Y1484884I200J0D01*
G02Y1481968I-1661J-1458D01*
G03X1523226Y1481836I150J-132D01*
G01Y1479898D01*
G03X1523276Y1479766I200J0D01*
G02Y1476850I-1661J-1458D01*
G03X1523226Y1476718I150J-132D01*
G01Y1476097D01*
G02X1523024Y1475894I-202J-1D01*
G01X1520204D01*
G02X1520002Y1476097I1J203D01*
G01Y1476718D01*
G03X1519952Y1476850I-200J0D01*
G02Y1479766I1661J1458D01*
G03X1520002Y1479898I-150J132D01*
G01Y1481836D01*
G03X1519952Y1481968I-200J0D01*
G02Y1484884I1661J1458D01*
G03X1520002Y1485016I-150J132D01*
G01Y1485635D01*
G02X1520204Y1485838I202J1D01*
G37*
G36*
G01X1537527D02*
X1540347D01*
G02X1540550Y1485635I0J-203D01*
G01Y1485014D01*
G03X1540600Y1484882I200J0D01*
G02Y1481970I-1664J-1456D01*
G03X1540550Y1481838I150J-132D01*
G01Y1479896D01*
G03X1540600Y1479764I200J0D01*
G02Y1476852I-1664J-1456D01*
G03X1540550Y1476720I150J-132D01*
G01Y1476097D01*
G02X1540347Y1475894I-203J0D01*
G01X1537527D01*
G02X1537324Y1476097I0J203D01*
G01Y1476720D01*
G03X1537274Y1476852I-200J0D01*
G02Y1479764I1664J1456D01*
G03X1537324Y1479896I-150J132D01*
G01Y1481838D01*
G03X1537274Y1481970I-200J0D01*
G02Y1484882I1664J1456D01*
G03X1537324Y1485014I-150J132D01*
G01Y1485635D01*
G02X1537527Y1485838I203J0D01*
G37*
G36*
G01X1693432D02*
X1696252D01*
G02X1696454Y1485635I-1J-203D01*
G01Y1485016D01*
G03X1696504Y1484884I200J0D01*
G02Y1481968I-1661J-1458D01*
G03X1696454Y1481836I150J-132D01*
G01Y1479898D01*
G03X1696504Y1479766I200J0D01*
G02Y1476850I-1661J-1458D01*
G03X1696454Y1476718I150J-132D01*
G01Y1476097D01*
G02X1696252Y1475894I-202J-1D01*
G01X1693432D01*
G02X1693230Y1476097I1J203D01*
G01Y1476718D01*
G03X1693180Y1476850I-200J0D01*
G02Y1479766I1661J1458D01*
G03X1693230Y1479898I-150J132D01*
G01Y1481836D01*
G03X1693180Y1481968I-200J0D01*
G02Y1484884I1661J1458D01*
G03X1693230Y1485016I-150J132D01*
G01Y1485635D01*
G02X1693432Y1485838I202J1D01*
G37*
G36*
G01X1710755D02*
X1713575D01*
G02X1713778Y1485635I0J-203D01*
G01Y1485014D01*
G03X1713828Y1484882I200J0D01*
G02Y1481970I-1664J-1456D01*
G03X1713778Y1481838I150J-132D01*
G01Y1479896D01*
G03X1713828Y1479764I200J0D01*
G02Y1476852I-1664J-1456D01*
G03X1713778Y1476720I150J-132D01*
G01Y1476097D01*
G02X1713575Y1475894I-203J0D01*
G01X1710755D01*
G02X1710552Y1476097I0J203D01*
G01Y1476720D01*
G03X1710502Y1476852I-200J0D01*
G02Y1479764I1664J1456D01*
G03X1710552Y1479896I-150J132D01*
G01Y1481838D01*
G03X1710502Y1481970I-200J0D01*
G02Y1484882I1664J1456D01*
G03X1710552Y1485014I-150J132D01*
G01Y1485635D01*
G02X1710755Y1485838I203J0D01*
G37*
G36*
G01X186425D02*
X189245D01*
G02X189448Y1485636I1J-202D01*
G01Y1485014D01*
G03X189498Y1484882I200J0D01*
G02Y1481970I-1664J-1456D01*
G03X189448Y1481838I150J-132D01*
G01Y1479896D01*
G03X189498Y1479764I200J0D01*
G02Y1476852I-1664J-1456D01*
G03X189448Y1476720I150J-132D01*
G01Y1476098D01*
G02X189245Y1475896I-203J1D01*
G01X186425D01*
G02X186222Y1476098I-1J202D01*
G01Y1476720D01*
G03X186172Y1476852I-200J0D01*
G02Y1479764I1664J1456D01*
G03X186222Y1479896I-150J132D01*
G01Y1481838D01*
G03X186172Y1481970I-200J0D01*
G02Y1484882I1664J1456D01*
G03X186222Y1485014I-150J132D01*
G01Y1485636D01*
G02X186425Y1485838I203J-1D01*
G37*
G36*
G01X125795Y1496862D02*
X128615D01*
G02X128818Y1496659I0J-203D01*
G01Y1496037D01*
G03X128868Y1495905I200J0D01*
G02Y1492993I-1664J-1456D01*
G03X128818Y1492861I150J-132D01*
G01Y1490919D01*
G03X128868Y1490787I200J0D01*
G02Y1487875I-1664J-1456D01*
G03X128818Y1487743I150J-132D01*
G01Y1487121D01*
G02X128615Y1486918I-203J0D01*
G01X125795D01*
G02X125592Y1487121I0J203D01*
G01Y1487743D01*
G03X125542Y1487875I-200J0D01*
G02Y1490787I1664J1456D01*
G03X125592Y1490919I-150J132D01*
G01Y1492861D01*
G03X125542Y1492993I-200J0D01*
G02Y1495905I1664J1456D01*
G03X125592Y1496037I-150J132D01*
G01Y1496659D01*
G02X125795Y1496862I203J0D01*
G37*
G36*
G01X143118D02*
X145938D01*
G02X146140Y1496659I-1J-203D01*
G01Y1496039D01*
G03X146190Y1495907I200J0D01*
G02Y1492991I-1661J-1458D01*
G03X146140Y1492859I150J-132D01*
G01Y1490921D01*
G03X146190Y1490789I200J0D01*
G02Y1487873I-1661J-1458D01*
G03X146140Y1487741I150J-132D01*
G01Y1487121D01*
G02X145938Y1486918I-202J-1D01*
G01X143118D01*
G02X142916Y1487121I1J203D01*
G01Y1487741D01*
G03X142866Y1487873I-200J0D01*
G02Y1490789I1661J1458D01*
G03X142916Y1490921I-150J132D01*
G01Y1492859D01*
G03X142866Y1492991I-200J0D01*
G02Y1495907I1661J1458D01*
G03X142916Y1496039I-150J132D01*
G01Y1496659D01*
G02X143118Y1496862I202J1D01*
G37*
G36*
G01X160440D02*
X163260D01*
G02X163462Y1496659I-1J-203D01*
G01Y1496039D01*
G03X163512Y1495907I200J0D01*
G02Y1492991I-1661J-1458D01*
G03X163462Y1492859I150J-132D01*
G01Y1490921D01*
G03X163512Y1490789I200J0D01*
G02Y1487873I-1661J-1458D01*
G03X163462Y1487741I150J-132D01*
G01Y1487121D01*
G02X163260Y1486918I-202J-1D01*
G01X160440D01*
G02X160238Y1487121I1J203D01*
G01Y1487741D01*
G03X160188Y1487873I-200J0D01*
G02Y1490789I1661J1458D01*
G03X160238Y1490921I-150J132D01*
G01Y1492859D01*
G03X160188Y1492991I-200J0D01*
G02Y1495907I1661J1458D01*
G03X160238Y1496039I-150J132D01*
G01Y1496659D01*
G02X160440Y1496862I202J1D01*
G37*
G36*
G01X281700D02*
X284520D01*
G02X284722Y1496659I-1J-203D01*
G01Y1496039D01*
G03X284772Y1495907I200J0D01*
G02Y1492991I-1661J-1458D01*
G03X284722Y1492859I150J-132D01*
G01Y1490921D01*
G03X284772Y1490789I200J0D01*
G02Y1487873I-1661J-1458D01*
G03X284722Y1487741I150J-132D01*
G01Y1487121D01*
G02X284520Y1486918I-202J-1D01*
G01X281700D01*
G02X281498Y1487121I1J203D01*
G01Y1487741D01*
G03X281448Y1487873I-200J0D01*
G02Y1490789I1661J1458D01*
G03X281498Y1490921I-150J132D01*
G01Y1492859D01*
G03X281448Y1492991I-200J0D01*
G02Y1495907I1661J1458D01*
G03X281498Y1496039I-150J132D01*
G01Y1496659D01*
G02X281700Y1496862I202J1D01*
G37*
G36*
G01X299023D02*
X301843D01*
G02X302046Y1496659I0J-203D01*
G01Y1496037D01*
G03X302096Y1495905I200J0D01*
G02Y1492993I-1664J-1456D01*
G03X302046Y1492861I150J-132D01*
G01Y1490919D01*
G03X302096Y1490787I200J0D01*
G02Y1487875I-1664J-1456D01*
G03X302046Y1487743I150J-132D01*
G01Y1487121D01*
G02X301843Y1486918I-203J0D01*
G01X299023D01*
G02X298820Y1487121I0J203D01*
G01Y1487743D01*
G03X298770Y1487875I-200J0D01*
G02Y1490787I1664J1456D01*
G03X298820Y1490919I-150J132D01*
G01Y1492861D01*
G03X298770Y1492993I-200J0D01*
G02Y1495905I1664J1456D01*
G03X298820Y1496037I-150J132D01*
G01Y1496659D01*
G02X299023Y1496862I203J0D01*
G37*
G36*
G01X454929D02*
X457749D01*
G02X457952Y1496659I0J-203D01*
G01Y1496037D01*
G03X458002Y1495905I200J0D01*
G02Y1492993I-1664J-1456D01*
G03X457952Y1492861I150J-132D01*
G01Y1490919D01*
G03X458002Y1490787I200J0D01*
G02Y1487875I-1664J-1456D01*
G03X457952Y1487743I150J-132D01*
G01Y1487121D01*
G02X457749Y1486918I-203J0D01*
G01X454929D01*
G02X454726Y1487121I0J203D01*
G01Y1487743D01*
G03X454676Y1487875I-200J0D01*
G02Y1490787I1664J1456D01*
G03X454726Y1490919I-150J132D01*
G01Y1492861D01*
G03X454676Y1492993I-200J0D01*
G02Y1495905I1664J1456D01*
G03X454726Y1496037I-150J132D01*
G01Y1496659D01*
G02X454929Y1496862I203J0D01*
G37*
G36*
G01X472252D02*
X475072D01*
G02X475274Y1496659I-1J-203D01*
G01Y1496039D01*
G03X475324Y1495907I200J0D01*
G02Y1492991I-1661J-1458D01*
G03X475274Y1492859I150J-132D01*
G01Y1490921D01*
G03X475324Y1490789I200J0D01*
G02Y1487873I-1661J-1458D01*
G03X475274Y1487741I150J-132D01*
G01Y1487121D01*
G02X475072Y1486918I-202J-1D01*
G01X472252D01*
G02X472050Y1487121I1J203D01*
G01Y1487741D01*
G03X472000Y1487873I-200J0D01*
G02Y1490789I1661J1458D01*
G03X472050Y1490921I-150J132D01*
G01Y1492859D01*
G03X472000Y1492991I-200J0D01*
G02Y1495907I1661J1458D01*
G03X472050Y1496039I-150J132D01*
G01Y1496659D01*
G02X472252Y1496862I202J1D01*
G37*
G36*
G01X489575D02*
X492395D01*
G02X492598Y1496659I0J-203D01*
G01Y1496037D01*
G03X492648Y1495905I200J0D01*
G02Y1492993I-1664J-1456D01*
G03X492598Y1492861I150J-132D01*
G01Y1490919D01*
G03X492648Y1490787I200J0D01*
G02Y1487875I-1664J-1456D01*
G03X492598Y1487743I150J-132D01*
G01Y1487121D01*
G02X492395Y1486918I-203J0D01*
G01X489575D01*
G02X489372Y1487121I0J203D01*
G01Y1487743D01*
G03X489322Y1487875I-200J0D01*
G02Y1490787I1664J1456D01*
G03X489372Y1490919I-150J132D01*
G01Y1492861D01*
G03X489322Y1492993I-200J0D01*
G02Y1495905I1664J1456D01*
G03X489372Y1496037I-150J132D01*
G01Y1496659D01*
G02X489575Y1496862I203J0D01*
G37*
G36*
G01X506897D02*
X509717D01*
G02X509920Y1496659I0J-203D01*
G01Y1496037D01*
G03X509970Y1495905I200J0D01*
G02Y1492993I-1664J-1456D01*
G03X509920Y1492861I150J-132D01*
G01Y1490919D01*
G03X509970Y1490787I200J0D01*
G02Y1487875I-1664J-1456D01*
G03X509920Y1487743I150J-132D01*
G01Y1487121D01*
G02X509717Y1486918I-203J0D01*
G01X506897D01*
G02X506694Y1487121I0J203D01*
G01Y1487743D01*
G03X506644Y1487875I-200J0D01*
G02Y1490787I1664J1456D01*
G03X506694Y1490919I-150J132D01*
G01Y1492861D01*
G03X506644Y1492993I-200J0D01*
G02Y1495905I1664J1456D01*
G03X506694Y1496037I-150J132D01*
G01Y1496659D01*
G02X506897Y1496862I203J0D01*
G37*
G36*
G01X645480D02*
X648300D01*
G02X648502Y1496659I-1J-203D01*
G01Y1496039D01*
G03X648552Y1495907I200J0D01*
G02Y1492991I-1661J-1458D01*
G03X648502Y1492859I150J-132D01*
G01Y1490921D01*
G03X648552Y1490789I200J0D01*
G02Y1487873I-1661J-1458D01*
G03X648502Y1487741I150J-132D01*
G01Y1487121D01*
G02X648300Y1486918I-202J-1D01*
G01X645480D01*
G02X645278Y1487121I1J203D01*
G01Y1487741D01*
G03X645228Y1487873I-200J0D01*
G02Y1490789I1661J1458D01*
G03X645278Y1490921I-150J132D01*
G01Y1492859D01*
G03X645228Y1492991I-200J0D01*
G02Y1495907I1661J1458D01*
G03X645278Y1496039I-150J132D01*
G01Y1496659D01*
G02X645480Y1496862I202J1D01*
G37*
G36*
G01X662803D02*
X665623D01*
G02X665826Y1496659I0J-203D01*
G01Y1496037D01*
G03X665876Y1495905I200J0D01*
G02Y1492993I-1664J-1456D01*
G03X665826Y1492861I150J-132D01*
G01Y1490919D01*
G03X665876Y1490787I200J0D01*
G02Y1487875I-1664J-1456D01*
G03X665826Y1487743I150J-132D01*
G01Y1487121D01*
G02X665623Y1486918I-203J0D01*
G01X662803D01*
G02X662600Y1487121I0J203D01*
G01Y1487743D01*
G03X662550Y1487875I-200J0D01*
G02Y1490787I1664J1456D01*
G03X662600Y1490919I-150J132D01*
G01Y1492861D01*
G03X662550Y1492993I-200J0D01*
G02Y1495905I1664J1456D01*
G03X662600Y1496037I-150J132D01*
G01Y1496659D01*
G02X662803Y1496862I203J0D01*
G37*
G36*
G01X680125D02*
X682945D01*
G02X683148Y1496659I0J-203D01*
G01Y1496037D01*
G03X683198Y1495905I200J0D01*
G02Y1492993I-1664J-1456D01*
G03X683148Y1492861I150J-132D01*
G01Y1490919D01*
G03X683198Y1490787I200J0D01*
G02Y1487875I-1664J-1456D01*
G03X683148Y1487743I150J-132D01*
G01Y1487121D01*
G02X682945Y1486918I-203J0D01*
G01X680125D01*
G02X679922Y1487121I0J203D01*
G01Y1487743D01*
G03X679872Y1487875I-200J0D01*
G02Y1490787I1664J1456D01*
G03X679922Y1490919I-150J132D01*
G01Y1492861D01*
G03X679872Y1492993I-200J0D01*
G02Y1495905I1664J1456D01*
G03X679922Y1496037I-150J132D01*
G01Y1496659D01*
G02X680125Y1496862I203J0D01*
G37*
G36*
G01X1165086D02*
X1167906D01*
G02X1168108Y1496659I-1J-203D01*
G01Y1496039D01*
G03X1168158Y1495907I200J0D01*
G02Y1492991I-1661J-1458D01*
G03X1168108Y1492859I150J-132D01*
G01Y1490921D01*
G03X1168158Y1490789I200J0D01*
G02Y1487873I-1661J-1458D01*
G03X1168108Y1487741I150J-132D01*
G01Y1487121D01*
G02X1167906Y1486918I-202J-1D01*
G01X1165086D01*
G02X1164884Y1487121I1J203D01*
G01Y1487741D01*
G03X1164834Y1487873I-200J0D01*
G02Y1490789I1661J1458D01*
G03X1164884Y1490921I-150J132D01*
G01Y1492859D01*
G03X1164834Y1492991I-200J0D01*
G02Y1495907I1661J1458D01*
G03X1164884Y1496039I-150J132D01*
G01Y1496659D01*
G02X1165086Y1496862I202J1D01*
G37*
G36*
G01X1182408D02*
X1185228D01*
G02X1185430Y1496659I-1J-203D01*
G01Y1496039D01*
G03X1185480Y1495907I200J0D01*
G02Y1492991I-1661J-1458D01*
G03X1185430Y1492859I150J-132D01*
G01Y1490921D01*
G03X1185480Y1490789I200J0D01*
G02Y1487873I-1661J-1458D01*
G03X1185430Y1487741I150J-132D01*
G01Y1487121D01*
G02X1185228Y1486918I-202J-1D01*
G01X1182408D01*
G02X1182206Y1487121I1J203D01*
G01Y1487741D01*
G03X1182156Y1487873I-200J0D01*
G02Y1490789I1661J1458D01*
G03X1182206Y1490921I-150J132D01*
G01Y1492859D01*
G03X1182156Y1492991I-200J0D01*
G02Y1495907I1661J1458D01*
G03X1182206Y1496039I-150J132D01*
G01Y1496659D01*
G02X1182408Y1496862I202J1D01*
G37*
G36*
G01X1303669D02*
X1306489D01*
G02X1306692Y1496659I0J-203D01*
G01Y1496037D01*
G03X1306742Y1495905I200J0D01*
G02Y1492993I-1664J-1456D01*
G03X1306692Y1492861I150J-132D01*
G01Y1490919D01*
G03X1306742Y1490787I200J0D01*
G02Y1487875I-1664J-1456D01*
G03X1306692Y1487743I150J-132D01*
G01Y1487121D01*
G02X1306489Y1486918I-203J0D01*
G01X1303669D01*
G02X1303466Y1487121I0J203D01*
G01Y1487743D01*
G03X1303416Y1487875I-200J0D01*
G02Y1490787I1664J1456D01*
G03X1303466Y1490919I-150J132D01*
G01Y1492861D01*
G03X1303416Y1492993I-200J0D01*
G02Y1495905I1664J1456D01*
G03X1303466Y1496037I-150J132D01*
G01Y1496659D01*
G02X1303669Y1496862I203J0D01*
G37*
G36*
G01X1320992D02*
X1323812D01*
G02X1324014Y1496659I-1J-203D01*
G01Y1496039D01*
G03X1324064Y1495907I200J0D01*
G02Y1492991I-1661J-1458D01*
G03X1324014Y1492859I150J-132D01*
G01Y1490921D01*
G03X1324064Y1490789I200J0D01*
G02Y1487873I-1661J-1458D01*
G03X1324014Y1487741I150J-132D01*
G01Y1487121D01*
G02X1323812Y1486918I-202J-1D01*
G01X1320992D01*
G02X1320790Y1487121I1J203D01*
G01Y1487741D01*
G03X1320740Y1487873I-200J0D01*
G02Y1490789I1661J1458D01*
G03X1320790Y1490921I-150J132D01*
G01Y1492859D01*
G03X1320740Y1492991I-200J0D01*
G02Y1495907I1661J1458D01*
G03X1320790Y1496039I-150J132D01*
G01Y1496659D01*
G02X1320992Y1496862I202J1D01*
G37*
G36*
G01X1338315D02*
X1341135D01*
G02X1341338Y1496659I0J-203D01*
G01Y1496037D01*
G03X1341388Y1495905I200J0D01*
G02Y1492993I-1664J-1456D01*
G03X1341338Y1492861I150J-132D01*
G01Y1490919D01*
G03X1341388Y1490787I200J0D01*
G02Y1487875I-1664J-1456D01*
G03X1341338Y1487743I150J-132D01*
G01Y1487121D01*
G02X1341135Y1486918I-203J0D01*
G01X1338315D01*
G02X1338112Y1487121I0J203D01*
G01Y1487743D01*
G03X1338062Y1487875I-200J0D01*
G02Y1490787I1664J1456D01*
G03X1338112Y1490919I-150J132D01*
G01Y1492861D01*
G03X1338062Y1492993I-200J0D01*
G02Y1495905I1664J1456D01*
G03X1338112Y1496037I-150J132D01*
G01Y1496659D01*
G02X1338315Y1496862I203J0D01*
G37*
G36*
G01X1355637D02*
X1358457D01*
G02X1358660Y1496659I0J-203D01*
G01Y1496037D01*
G03X1358710Y1495905I200J0D01*
G02Y1492993I-1664J-1456D01*
G03X1358660Y1492861I150J-132D01*
G01Y1490919D01*
G03X1358710Y1490787I200J0D01*
G02Y1487875I-1664J-1456D01*
G03X1358660Y1487743I150J-132D01*
G01Y1487121D01*
G02X1358457Y1486918I-203J0D01*
G01X1355637D01*
G02X1355434Y1487121I0J203D01*
G01Y1487743D01*
G03X1355384Y1487875I-200J0D01*
G02Y1490787I1664J1456D01*
G03X1355434Y1490919I-150J132D01*
G01Y1492861D01*
G03X1355384Y1492993I-200J0D01*
G02Y1495905I1664J1456D01*
G03X1355434Y1496037I-150J132D01*
G01Y1496659D01*
G02X1355637Y1496862I203J0D01*
G37*
G36*
G01X1476897D02*
X1479717D01*
G02X1479920Y1496659I0J-203D01*
G01Y1496037D01*
G03X1479970Y1495905I200J0D01*
G02Y1492993I-1664J-1456D01*
G03X1479920Y1492861I150J-132D01*
G01Y1490919D01*
G03X1479970Y1490787I200J0D01*
G02Y1487875I-1664J-1456D01*
G03X1479920Y1487743I150J-132D01*
G01Y1487121D01*
G02X1479717Y1486918I-203J0D01*
G01X1476897D01*
G02X1476694Y1487121I0J203D01*
G01Y1487743D01*
G03X1476644Y1487875I-200J0D01*
G02Y1490787I1664J1456D01*
G03X1476694Y1490919I-150J132D01*
G01Y1492861D01*
G03X1476644Y1492993I-200J0D01*
G02Y1495905I1664J1456D01*
G03X1476694Y1496037I-150J132D01*
G01Y1496659D01*
G02X1476897Y1496862I203J0D01*
G37*
G36*
G01X1494220D02*
X1497040D01*
G02X1497242Y1496659I-1J-203D01*
G01Y1496039D01*
G03X1497292Y1495907I200J0D01*
G02Y1492991I-1661J-1458D01*
G03X1497242Y1492859I150J-132D01*
G01Y1490921D01*
G03X1497292Y1490789I200J0D01*
G02Y1487873I-1661J-1458D01*
G03X1497242Y1487741I150J-132D01*
G01Y1487121D01*
G02X1497040Y1486918I-202J-1D01*
G01X1494220D01*
G02X1494018Y1487121I1J203D01*
G01Y1487741D01*
G03X1493968Y1487873I-200J0D01*
G02Y1490789I1661J1458D01*
G03X1494018Y1490921I-150J132D01*
G01Y1492859D01*
G03X1493968Y1492991I-200J0D01*
G02Y1495907I1661J1458D01*
G03X1494018Y1496039I-150J132D01*
G01Y1496659D01*
G02X1494220Y1496862I202J1D01*
G37*
G36*
G01X1511543D02*
X1514363D01*
G02X1514566Y1496659I0J-203D01*
G01Y1496037D01*
G03X1514616Y1495905I200J0D01*
G02Y1492993I-1664J-1456D01*
G03X1514566Y1492861I150J-132D01*
G01Y1490919D01*
G03X1514616Y1490787I200J0D01*
G02Y1487875I-1664J-1456D01*
G03X1514566Y1487743I150J-132D01*
G01Y1487121D01*
G02X1514363Y1486918I-203J0D01*
G01X1511543D01*
G02X1511340Y1487121I0J203D01*
G01Y1487743D01*
G03X1511290Y1487875I-200J0D01*
G02Y1490787I1664J1456D01*
G03X1511340Y1490919I-150J132D01*
G01Y1492861D01*
G03X1511290Y1492993I-200J0D01*
G02Y1495905I1664J1456D01*
G03X1511340Y1496037I-150J132D01*
G01Y1496659D01*
G02X1511543Y1496862I203J0D01*
G37*
G36*
G01X1528865D02*
X1531685D01*
G02X1531888Y1496659I0J-203D01*
G01Y1496037D01*
G03X1531938Y1495905I200J0D01*
G02Y1492993I-1664J-1456D01*
G03X1531888Y1492861I150J-132D01*
G01Y1490919D01*
G03X1531938Y1490787I200J0D01*
G02Y1487875I-1664J-1456D01*
G03X1531888Y1487743I150J-132D01*
G01Y1487121D01*
G02X1531685Y1486918I-203J0D01*
G01X1528865D01*
G02X1528662Y1487121I0J203D01*
G01Y1487743D01*
G03X1528612Y1487875I-200J0D01*
G02Y1490787I1664J1456D01*
G03X1528662Y1490919I-150J132D01*
G01Y1492861D01*
G03X1528612Y1492993I-200J0D01*
G02Y1495905I1664J1456D01*
G03X1528662Y1496037I-150J132D01*
G01Y1496659D01*
G02X1528865Y1496862I203J0D01*
G37*
G36*
G01X1684771D02*
X1687591D01*
G02X1687794Y1496659I0J-203D01*
G01Y1496037D01*
G03X1687844Y1495905I200J0D01*
G02Y1492993I-1664J-1456D01*
G03X1687794Y1492861I150J-132D01*
G01Y1490919D01*
G03X1687844Y1490787I200J0D01*
G02Y1487875I-1664J-1456D01*
G03X1687794Y1487743I150J-132D01*
G01Y1487121D01*
G02X1687591Y1486918I-203J0D01*
G01X1684771D01*
G02X1684568Y1487121I0J203D01*
G01Y1487743D01*
G03X1684518Y1487875I-200J0D01*
G02Y1490787I1664J1456D01*
G03X1684568Y1490919I-150J132D01*
G01Y1492861D01*
G03X1684518Y1492993I-200J0D01*
G02Y1495905I1664J1456D01*
G03X1684568Y1496037I-150J132D01*
G01Y1496659D01*
G02X1684771Y1496862I203J0D01*
G37*
G36*
G01X1702093D02*
X1704913D01*
G02X1705116Y1496659I0J-203D01*
G01Y1496037D01*
G03X1705166Y1495905I200J0D01*
G02Y1492993I-1664J-1456D01*
G03X1705116Y1492861I150J-132D01*
G01Y1490919D01*
G03X1705166Y1490787I200J0D01*
G02Y1487875I-1664J-1456D01*
G03X1705116Y1487743I150J-132D01*
G01Y1487121D01*
G02X1704913Y1486918I-203J0D01*
G01X1702093D01*
G02X1701890Y1487121I0J203D01*
G01Y1487743D01*
G03X1701840Y1487875I-200J0D01*
G02Y1490787I1664J1456D01*
G03X1701890Y1490919I-150J132D01*
G01Y1492861D01*
G03X1701840Y1492993I-200J0D01*
G02Y1495905I1664J1456D01*
G03X1701890Y1496037I-150J132D01*
G01Y1496659D01*
G02X1702093Y1496862I203J0D01*
G37*
G36*
G01X134456Y1501192D02*
X137276D01*
G02X137478Y1500989I-1J-203D01*
G01Y1500370D01*
G03X137528Y1500238I200J0D01*
G02Y1497322I-1661J-1458D01*
G03X137478Y1497190I150J-132D01*
G01Y1495252D01*
G03X137528Y1495120I200J0D01*
G02Y1492204I-1661J-1458D01*
G03X137478Y1492072I150J-132D01*
G01Y1491451D01*
G02X137276Y1491248I-202J-1D01*
G01X134456D01*
G02X134254Y1491451I1J203D01*
G01Y1492072D01*
G03X134204Y1492204I-200J0D01*
G02Y1495120I1661J1458D01*
G03X134254Y1495252I-150J132D01*
G01Y1497190D01*
G03X134204Y1497322I-200J0D01*
G02Y1500238I1661J1458D01*
G03X134254Y1500370I-150J132D01*
G01Y1500989D01*
G02X134456Y1501192I202J1D01*
G37*
G36*
G01X151779D02*
X154599D01*
G02X154802Y1500989I0J-203D01*
G01Y1500368D01*
G03X154852Y1500236I200J0D01*
G02Y1497324I-1664J-1456D01*
G03X154802Y1497192I150J-132D01*
G01Y1495250D01*
G03X154852Y1495118I200J0D01*
G02Y1492206I-1664J-1456D01*
G03X154802Y1492074I150J-132D01*
G01Y1491451D01*
G02X154599Y1491248I-203J0D01*
G01X151779D01*
G02X151576Y1491451I0J203D01*
G01Y1492074D01*
G03X151526Y1492206I-200J0D01*
G02Y1495118I1664J1456D01*
G03X151576Y1495250I-150J132D01*
G01Y1497192D01*
G03X151526Y1497324I-200J0D01*
G02Y1500236I1664J1456D01*
G03X151576Y1500368I-150J132D01*
G01Y1500989D01*
G02X151779Y1501192I203J0D01*
G37*
G36*
G01X169102D02*
X171922D01*
G02X172124Y1500989I-1J-203D01*
G01Y1500370D01*
G03X172174Y1500238I200J0D01*
G02Y1497322I-1661J-1458D01*
G03X172124Y1497190I150J-132D01*
G01Y1495252D01*
G03X172174Y1495120I200J0D01*
G02Y1492204I-1661J-1458D01*
G03X172124Y1492072I150J-132D01*
G01Y1491451D01*
G02X171922Y1491248I-202J-1D01*
G01X169102D01*
G02X168900Y1491451I1J203D01*
G01Y1492072D01*
G03X168850Y1492204I-200J0D01*
G02Y1495120I1661J1458D01*
G03X168900Y1495252I-150J132D01*
G01Y1497190D01*
G03X168850Y1497322I-200J0D01*
G02Y1500238I1661J1458D01*
G03X168900Y1500370I-150J132D01*
G01Y1500989D01*
G02X169102Y1501192I202J1D01*
G37*
G36*
G01X290361D02*
X293181D01*
G02X293384Y1500989I0J-203D01*
G01Y1500368D01*
G03X293434Y1500236I200J0D01*
G02Y1497324I-1664J-1456D01*
G03X293384Y1497192I150J-132D01*
G01Y1495250D01*
G03X293434Y1495118I200J0D01*
G02Y1492206I-1664J-1456D01*
G03X293384Y1492074I150J-132D01*
G01Y1491451D01*
G02X293181Y1491248I-203J0D01*
G01X290361D01*
G02X290158Y1491451I0J203D01*
G01Y1492074D01*
G03X290108Y1492206I-200J0D01*
G02Y1495118I1664J1456D01*
G03X290158Y1495250I-150J132D01*
G01Y1497192D01*
G03X290108Y1497324I-200J0D01*
G02Y1500236I1664J1456D01*
G03X290158Y1500368I-150J132D01*
G01Y1500989D01*
G02X290361Y1501192I203J0D01*
G37*
G36*
G01X463590D02*
X466410D01*
G02X466612Y1500989I-1J-203D01*
G01Y1500370D01*
G03X466662Y1500238I200J0D01*
G02Y1497322I-1661J-1458D01*
G03X466612Y1497190I150J-132D01*
G01Y1495252D01*
G03X466662Y1495120I200J0D01*
G02Y1492204I-1661J-1458D01*
G03X466612Y1492072I150J-132D01*
G01Y1491451D01*
G02X466410Y1491248I-202J-1D01*
G01X463590D01*
G02X463388Y1491451I1J203D01*
G01Y1492072D01*
G03X463338Y1492204I-200J0D01*
G02Y1495120I1661J1458D01*
G03X463388Y1495252I-150J132D01*
G01Y1497190D01*
G03X463338Y1497322I-200J0D01*
G02Y1500238I1661J1458D01*
G03X463388Y1500370I-150J132D01*
G01Y1500989D01*
G02X463590Y1501192I202J1D01*
G37*
G36*
G01X480913D02*
X483733D01*
G02X483936Y1500989I0J-203D01*
G01Y1500368D01*
G03X483986Y1500236I200J0D01*
G02Y1497324I-1664J-1456D01*
G03X483936Y1497192I150J-132D01*
G01Y1495250D01*
G03X483986Y1495118I200J0D01*
G02Y1492206I-1664J-1456D01*
G03X483936Y1492074I150J-132D01*
G01Y1491451D01*
G02X483733Y1491248I-203J0D01*
G01X480913D01*
G02X480710Y1491451I0J203D01*
G01Y1492074D01*
G03X480660Y1492206I-200J0D01*
G02Y1495118I1664J1456D01*
G03X480710Y1495250I-150J132D01*
G01Y1497192D01*
G03X480660Y1497324I-200J0D01*
G02Y1500236I1664J1456D01*
G03X480710Y1500368I-150J132D01*
G01Y1500989D01*
G02X480913Y1501192I203J0D01*
G37*
G36*
G01X498236D02*
X501056D01*
G02X501258Y1500989I-1J-203D01*
G01Y1500370D01*
G03X501308Y1500238I200J0D01*
G02Y1497322I-1661J-1458D01*
G03X501258Y1497190I150J-132D01*
G01Y1495252D01*
G03X501308Y1495120I200J0D01*
G02Y1492204I-1661J-1458D01*
G03X501258Y1492072I150J-132D01*
G01Y1491451D01*
G02X501056Y1491248I-202J-1D01*
G01X498236D01*
G02X498034Y1491451I1J203D01*
G01Y1492072D01*
G03X497984Y1492204I-200J0D01*
G02Y1495120I1661J1458D01*
G03X498034Y1495252I-150J132D01*
G01Y1497190D01*
G03X497984Y1497322I-200J0D01*
G02Y1500238I1661J1458D01*
G03X498034Y1500370I-150J132D01*
G01Y1500989D01*
G02X498236Y1501192I202J1D01*
G37*
G36*
G01X515559D02*
X518379D01*
G02X518582Y1500989I0J-203D01*
G01Y1500368D01*
G03X518632Y1500236I200J0D01*
G02Y1497324I-1664J-1456D01*
G03X518582Y1497192I150J-132D01*
G01Y1495250D01*
G03X518632Y1495118I200J0D01*
G02Y1492206I-1664J-1456D01*
G03X518582Y1492074I150J-132D01*
G01Y1491451D01*
G02X518379Y1491248I-203J0D01*
G01X515559D01*
G02X515356Y1491451I0J203D01*
G01Y1492074D01*
G03X515306Y1492206I-200J0D01*
G02Y1495118I1664J1456D01*
G03X515356Y1495250I-150J132D01*
G01Y1497192D01*
G03X515306Y1497324I-200J0D01*
G02Y1500236I1664J1456D01*
G03X515356Y1500368I-150J132D01*
G01Y1500989D01*
G02X515559Y1501192I203J0D01*
G37*
G36*
G01X654141D02*
X656961D01*
G02X657164Y1500989I0J-203D01*
G01Y1500368D01*
G03X657214Y1500236I200J0D01*
G02Y1497324I-1664J-1456D01*
G03X657164Y1497192I150J-132D01*
G01Y1495250D01*
G03X657214Y1495118I200J0D01*
G02Y1492206I-1664J-1456D01*
G03X657164Y1492074I150J-132D01*
G01Y1491451D01*
G02X656961Y1491248I-203J0D01*
G01X654141D01*
G02X653938Y1491451I0J203D01*
G01Y1492074D01*
G03X653888Y1492206I-200J0D01*
G02Y1495118I1664J1456D01*
G03X653938Y1495250I-150J132D01*
G01Y1497192D01*
G03X653888Y1497324I-200J0D01*
G02Y1500236I1664J1456D01*
G03X653938Y1500368I-150J132D01*
G01Y1500989D01*
G02X654141Y1501192I203J0D01*
G37*
G36*
G01X671464D02*
X674284D01*
G02X674486Y1500989I-1J-203D01*
G01Y1500370D01*
G03X674536Y1500238I200J0D01*
G02Y1497322I-1661J-1458D01*
G03X674486Y1497190I150J-132D01*
G01Y1495252D01*
G03X674536Y1495120I200J0D01*
G02Y1492204I-1661J-1458D01*
G03X674486Y1492072I150J-132D01*
G01Y1491451D01*
G02X674284Y1491248I-202J-1D01*
G01X671464D01*
G02X671262Y1491451I1J203D01*
G01Y1492072D01*
G03X671212Y1492204I-200J0D01*
G02Y1495120I1661J1458D01*
G03X671262Y1495252I-150J132D01*
G01Y1497190D01*
G03X671212Y1497322I-200J0D01*
G02Y1500238I1661J1458D01*
G03X671262Y1500370I-150J132D01*
G01Y1500989D01*
G02X671464Y1501192I202J1D01*
G37*
G36*
G01X688787D02*
X691607D01*
G02X691810Y1500989I0J-203D01*
G01Y1500368D01*
G03X691860Y1500236I200J0D01*
G02Y1497324I-1664J-1456D01*
G03X691810Y1497192I150J-132D01*
G01Y1495250D01*
G03X691860Y1495118I200J0D01*
G02Y1492206I-1664J-1456D01*
G03X691810Y1492074I150J-132D01*
G01Y1491451D01*
G02X691607Y1491248I-203J0D01*
G01X688787D01*
G02X688584Y1491451I0J203D01*
G01Y1492074D01*
G03X688534Y1492206I-200J0D01*
G02Y1495118I1664J1456D01*
G03X688584Y1495250I-150J132D01*
G01Y1497192D01*
G03X688534Y1497324I-200J0D01*
G02Y1500236I1664J1456D01*
G03X688584Y1500368I-150J132D01*
G01Y1500989D01*
G02X688787Y1501192I203J0D01*
G37*
G36*
G01X1173747D02*
X1176567D01*
G02X1176770Y1500989I0J-203D01*
G01Y1500368D01*
G03X1176820Y1500236I200J0D01*
G02Y1497324I-1664J-1456D01*
G03X1176770Y1497192I150J-132D01*
G01Y1495250D01*
G03X1176820Y1495118I200J0D01*
G02Y1492206I-1664J-1456D01*
G03X1176770Y1492074I150J-132D01*
G01Y1491451D01*
G02X1176567Y1491248I-203J0D01*
G01X1173747D01*
G02X1173544Y1491451I0J203D01*
G01Y1492074D01*
G03X1173494Y1492206I-200J0D01*
G02Y1495118I1664J1456D01*
G03X1173544Y1495250I-150J132D01*
G01Y1497192D01*
G03X1173494Y1497324I-200J0D01*
G02Y1500236I1664J1456D01*
G03X1173544Y1500368I-150J132D01*
G01Y1500989D01*
G02X1173747Y1501192I203J0D01*
G37*
G36*
G01X1191070D02*
X1193890D01*
G02X1194092Y1500989I-1J-203D01*
G01Y1500370D01*
G03X1194142Y1500238I200J0D01*
G02Y1497322I-1661J-1458D01*
G03X1194092Y1497190I150J-132D01*
G01Y1495252D01*
G03X1194142Y1495120I200J0D01*
G02Y1492204I-1661J-1458D01*
G03X1194092Y1492072I150J-132D01*
G01Y1491451D01*
G02X1193890Y1491248I-202J-1D01*
G01X1191070D01*
G02X1190868Y1491451I1J203D01*
G01Y1492072D01*
G03X1190818Y1492204I-200J0D01*
G02Y1495120I1661J1458D01*
G03X1190868Y1495252I-150J132D01*
G01Y1497190D01*
G03X1190818Y1497322I-200J0D01*
G02Y1500238I1661J1458D01*
G03X1190868Y1500370I-150J132D01*
G01Y1500989D01*
G02X1191070Y1501192I202J1D01*
G37*
G36*
G01X1312330D02*
X1315150D01*
G02X1315352Y1500989I-1J-203D01*
G01Y1500370D01*
G03X1315402Y1500238I200J0D01*
G02Y1497322I-1661J-1458D01*
G03X1315352Y1497190I150J-132D01*
G01Y1495252D01*
G03X1315402Y1495120I200J0D01*
G02Y1492204I-1661J-1458D01*
G03X1315352Y1492072I150J-132D01*
G01Y1491451D01*
G02X1315150Y1491248I-202J-1D01*
G01X1312330D01*
G02X1312128Y1491451I1J203D01*
G01Y1492072D01*
G03X1312078Y1492204I-200J0D01*
G02Y1495120I1661J1458D01*
G03X1312128Y1495252I-150J132D01*
G01Y1497190D01*
G03X1312078Y1497322I-200J0D01*
G02Y1500238I1661J1458D01*
G03X1312128Y1500370I-150J132D01*
G01Y1500989D01*
G02X1312330Y1501192I202J1D01*
G37*
G36*
G01X1329653D02*
X1332473D01*
G02X1332676Y1500989I0J-203D01*
G01Y1500368D01*
G03X1332726Y1500236I200J0D01*
G02Y1497324I-1664J-1456D01*
G03X1332676Y1497192I150J-132D01*
G01Y1495250D01*
G03X1332726Y1495118I200J0D01*
G02Y1492206I-1664J-1456D01*
G03X1332676Y1492074I150J-132D01*
G01Y1491451D01*
G02X1332473Y1491248I-203J0D01*
G01X1329653D01*
G02X1329450Y1491451I0J203D01*
G01Y1492074D01*
G03X1329400Y1492206I-200J0D01*
G02Y1495118I1664J1456D01*
G03X1329450Y1495250I-150J132D01*
G01Y1497192D01*
G03X1329400Y1497324I-200J0D01*
G02Y1500236I1664J1456D01*
G03X1329450Y1500368I-150J132D01*
G01Y1500989D01*
G02X1329653Y1501192I203J0D01*
G37*
G36*
G01X1346976D02*
X1349796D01*
G02X1349998Y1500989I-1J-203D01*
G01Y1500370D01*
G03X1350048Y1500238I200J0D01*
G02Y1497322I-1661J-1458D01*
G03X1349998Y1497190I150J-132D01*
G01Y1495252D01*
G03X1350048Y1495120I200J0D01*
G02Y1492204I-1661J-1458D01*
G03X1349998Y1492072I150J-132D01*
G01Y1491451D01*
G02X1349796Y1491248I-202J-1D01*
G01X1346976D01*
G02X1346774Y1491451I1J203D01*
G01Y1492072D01*
G03X1346724Y1492204I-200J0D01*
G02Y1495120I1661J1458D01*
G03X1346774Y1495252I-150J132D01*
G01Y1497190D01*
G03X1346724Y1497322I-200J0D01*
G02Y1500238I1661J1458D01*
G03X1346774Y1500370I-150J132D01*
G01Y1500989D01*
G02X1346976Y1501192I202J1D01*
G37*
G36*
G01X1364299D02*
X1367119D01*
G02X1367322Y1500989I0J-203D01*
G01Y1500368D01*
G03X1367372Y1500236I200J0D01*
G02Y1497324I-1664J-1456D01*
G03X1367322Y1497192I150J-132D01*
G01Y1495250D01*
G03X1367372Y1495118I200J0D01*
G02Y1492206I-1664J-1456D01*
G03X1367322Y1492074I150J-132D01*
G01Y1491451D01*
G02X1367119Y1491248I-203J0D01*
G01X1364299D01*
G02X1364096Y1491451I0J203D01*
G01Y1492074D01*
G03X1364046Y1492206I-200J0D01*
G02Y1495118I1664J1456D01*
G03X1364096Y1495250I-150J132D01*
G01Y1497192D01*
G03X1364046Y1497324I-200J0D01*
G02Y1500236I1664J1456D01*
G03X1364096Y1500368I-150J132D01*
G01Y1500989D01*
G02X1364299Y1501192I203J0D01*
G37*
G36*
G01X1485558D02*
X1488378D01*
G02X1488580Y1500989I-1J-203D01*
G01Y1500370D01*
G03X1488630Y1500238I200J0D01*
G02Y1497322I-1661J-1458D01*
G03X1488580Y1497190I150J-132D01*
G01Y1495252D01*
G03X1488630Y1495120I200J0D01*
G02Y1492204I-1661J-1458D01*
G03X1488580Y1492072I150J-132D01*
G01Y1491451D01*
G02X1488378Y1491248I-202J-1D01*
G01X1485558D01*
G02X1485356Y1491451I1J203D01*
G01Y1492072D01*
G03X1485306Y1492204I-200J0D01*
G02Y1495120I1661J1458D01*
G03X1485356Y1495252I-150J132D01*
G01Y1497190D01*
G03X1485306Y1497322I-200J0D01*
G02Y1500238I1661J1458D01*
G03X1485356Y1500370I-150J132D01*
G01Y1500989D01*
G02X1485558Y1501192I202J1D01*
G37*
G36*
G01X1502881D02*
X1505701D01*
G02X1505904Y1500989I0J-203D01*
G01Y1500368D01*
G03X1505954Y1500236I200J0D01*
G02Y1497324I-1664J-1456D01*
G03X1505904Y1497192I150J-132D01*
G01Y1495250D01*
G03X1505954Y1495118I200J0D01*
G02Y1492206I-1664J-1456D01*
G03X1505904Y1492074I150J-132D01*
G01Y1491451D01*
G02X1505701Y1491248I-203J0D01*
G01X1502881D01*
G02X1502678Y1491451I0J203D01*
G01Y1492074D01*
G03X1502628Y1492206I-200J0D01*
G02Y1495118I1664J1456D01*
G03X1502678Y1495250I-150J132D01*
G01Y1497192D01*
G03X1502628Y1497324I-200J0D01*
G02Y1500236I1664J1456D01*
G03X1502678Y1500368I-150J132D01*
G01Y1500989D01*
G02X1502881Y1501192I203J0D01*
G37*
G36*
G01X1520204D02*
X1523024D01*
G02X1523226Y1500989I-1J-203D01*
G01Y1500370D01*
G03X1523276Y1500238I200J0D01*
G02Y1497322I-1661J-1458D01*
G03X1523226Y1497190I150J-132D01*
G01Y1495252D01*
G03X1523276Y1495120I200J0D01*
G02Y1492204I-1661J-1458D01*
G03X1523226Y1492072I150J-132D01*
G01Y1491451D01*
G02X1523024Y1491248I-202J-1D01*
G01X1520204D01*
G02X1520002Y1491451I1J203D01*
G01Y1492072D01*
G03X1519952Y1492204I-200J0D01*
G02Y1495120I1661J1458D01*
G03X1520002Y1495252I-150J132D01*
G01Y1497190D01*
G03X1519952Y1497322I-200J0D01*
G02Y1500238I1661J1458D01*
G03X1520002Y1500370I-150J132D01*
G01Y1500989D01*
G02X1520204Y1501192I202J1D01*
G37*
G36*
G01X1537527D02*
X1540347D01*
G02X1540550Y1500989I0J-203D01*
G01Y1500368D01*
G03X1540600Y1500236I200J0D01*
G02Y1497324I-1664J-1456D01*
G03X1540550Y1497192I150J-132D01*
G01Y1495250D01*
G03X1540600Y1495118I200J0D01*
G02Y1492206I-1664J-1456D01*
G03X1540550Y1492074I150J-132D01*
G01Y1491451D01*
G02X1540347Y1491248I-203J0D01*
G01X1537527D01*
G02X1537324Y1491451I0J203D01*
G01Y1492074D01*
G03X1537274Y1492206I-200J0D01*
G02Y1495118I1664J1456D01*
G03X1537324Y1495250I-150J132D01*
G01Y1497192D01*
G03X1537274Y1497324I-200J0D01*
G02Y1500236I1664J1456D01*
G03X1537324Y1500368I-150J132D01*
G01Y1500989D01*
G02X1537527Y1501192I203J0D01*
G37*
G36*
G01X1693432D02*
X1696252D01*
G02X1696454Y1500989I-1J-203D01*
G01Y1500370D01*
G03X1696504Y1500238I200J0D01*
G02Y1497322I-1661J-1458D01*
G03X1696454Y1497190I150J-132D01*
G01Y1495252D01*
G03X1696504Y1495120I200J0D01*
G02Y1492204I-1661J-1458D01*
G03X1696454Y1492072I150J-132D01*
G01Y1491451D01*
G02X1696252Y1491248I-202J-1D01*
G01X1693432D01*
G02X1693230Y1491451I1J203D01*
G01Y1492072D01*
G03X1693180Y1492204I-200J0D01*
G02Y1495120I1661J1458D01*
G03X1693230Y1495252I-150J132D01*
G01Y1497190D01*
G03X1693180Y1497322I-200J0D01*
G02Y1500238I1661J1458D01*
G03X1693230Y1500370I-150J132D01*
G01Y1500989D01*
G02X1693432Y1501192I202J1D01*
G37*
G36*
G01X1710755D02*
X1713575D01*
G02X1713778Y1500989I0J-203D01*
G01Y1500368D01*
G03X1713828Y1500236I200J0D01*
G02Y1497324I-1664J-1456D01*
G03X1713778Y1497192I150J-132D01*
G01Y1495250D01*
G03X1713828Y1495118I200J0D01*
G02Y1492206I-1664J-1456D01*
G03X1713778Y1492074I150J-132D01*
G01Y1491451D01*
G02X1713575Y1491248I-203J0D01*
G01X1710755D01*
G02X1710552Y1491451I0J203D01*
G01Y1492074D01*
G03X1710502Y1492206I-200J0D01*
G02Y1495118I1664J1456D01*
G03X1710552Y1495250I-150J132D01*
G01Y1497192D01*
G03X1710502Y1497324I-200J0D01*
G02Y1500236I1664J1456D01*
G03X1710552Y1500368I-150J132D01*
G01Y1500989D01*
G02X1710755Y1501192I203J0D01*
G37*
G36*
G01X143118Y1512216D02*
X145938D01*
G02X146140Y1512014I0J-202D01*
G01Y1511394D01*
G03X146190Y1511262I200J0D01*
G02Y1508346I-1661J-1458D01*
G03X146140Y1508214I150J-132D01*
G01Y1506275D01*
G03X146190Y1506143I200J0D01*
G02Y1503227I-1661J-1458D01*
G03X146140Y1503095I150J-132D01*
G01Y1502476D01*
G02X145938Y1502274I-202J0D01*
G01X143118D01*
G02X142916Y1502476I0J202D01*
G01Y1503095D01*
G03X142866Y1503227I-200J0D01*
G02Y1506143I1661J1458D01*
G03X142916Y1506275I-150J132D01*
G01Y1508214D01*
G03X142866Y1508346I-200J0D01*
G02Y1511262I1661J1458D01*
G03X142916Y1511394I-150J132D01*
G01Y1512014D01*
G02X143118Y1512216I202J0D01*
G37*
G36*
G01X160440D02*
X163260D01*
G02X163462Y1512014I0J-202D01*
G01Y1511394D01*
G03X163512Y1511262I200J0D01*
G02Y1508346I-1661J-1458D01*
G03X163462Y1508214I150J-132D01*
G01Y1506275D01*
G03X163512Y1506143I200J0D01*
G02Y1503227I-1661J-1458D01*
G03X163462Y1503095I150J-132D01*
G01Y1502476D01*
G02X163260Y1502274I-202J0D01*
G01X160440D01*
G02X160238Y1502476I0J202D01*
G01Y1503095D01*
G03X160188Y1503227I-200J0D01*
G02Y1506143I1661J1458D01*
G03X160238Y1506275I-150J132D01*
G01Y1508214D01*
G03X160188Y1508346I-200J0D01*
G02Y1511262I1661J1458D01*
G03X160238Y1511394I-150J132D01*
G01Y1512014D01*
G02X160440Y1512216I202J0D01*
G37*
G36*
G01X281700D02*
X284520D01*
G02X284722Y1512014I0J-202D01*
G01Y1511394D01*
G03X284772Y1511262I200J0D01*
G02Y1508346I-1661J-1458D01*
G03X284722Y1508214I150J-132D01*
G01Y1506275D01*
G03X284772Y1506143I200J0D01*
G02Y1503227I-1661J-1458D01*
G03X284722Y1503095I150J-132D01*
G01Y1502476D01*
G02X284520Y1502274I-202J0D01*
G01X281700D01*
G02X281498Y1502476I0J202D01*
G01Y1503095D01*
G03X281448Y1503227I-200J0D01*
G02Y1506143I1661J1458D01*
G03X281498Y1506275I-150J132D01*
G01Y1508214D01*
G03X281448Y1508346I-200J0D01*
G02Y1511262I1661J1458D01*
G03X281498Y1511394I-150J132D01*
G01Y1512014D01*
G02X281700Y1512216I202J0D01*
G37*
G36*
G01X472252D02*
X475072D01*
G02X475274Y1512014I0J-202D01*
G01Y1511394D01*
G03X475324Y1511262I200J0D01*
G02Y1508346I-1661J-1458D01*
G03X475274Y1508214I150J-132D01*
G01Y1506275D01*
G03X475324Y1506143I200J0D01*
G02Y1503227I-1661J-1458D01*
G03X475274Y1503095I150J-132D01*
G01Y1502476D01*
G02X475072Y1502274I-202J0D01*
G01X472252D01*
G02X472050Y1502476I0J202D01*
G01Y1503095D01*
G03X472000Y1503227I-200J0D01*
G02Y1506143I1661J1458D01*
G03X472050Y1506275I-150J132D01*
G01Y1508214D01*
G03X472000Y1508346I-200J0D01*
G02Y1511262I1661J1458D01*
G03X472050Y1511394I-150J132D01*
G01Y1512014D01*
G02X472252Y1512216I202J0D01*
G37*
G36*
G01X645480D02*
X648300D01*
G02X648502Y1512014I0J-202D01*
G01Y1511394D01*
G03X648552Y1511262I200J0D01*
G02Y1508346I-1661J-1458D01*
G03X648502Y1508214I150J-132D01*
G01Y1506275D01*
G03X648552Y1506143I200J0D01*
G02Y1503227I-1661J-1458D01*
G03X648502Y1503095I150J-132D01*
G01Y1502476D01*
G02X648300Y1502274I-202J0D01*
G01X645480D01*
G02X645278Y1502476I0J202D01*
G01Y1503095D01*
G03X645228Y1503227I-200J0D01*
G02Y1506143I1661J1458D01*
G03X645278Y1506275I-150J132D01*
G01Y1508214D01*
G03X645228Y1508346I-200J0D01*
G02Y1511262I1661J1458D01*
G03X645278Y1511394I-150J132D01*
G01Y1512014D01*
G02X645480Y1512216I202J0D01*
G37*
G36*
G01X1165086D02*
X1167906D01*
G02X1168108Y1512014I0J-202D01*
G01Y1511394D01*
G03X1168158Y1511262I200J0D01*
G02Y1508346I-1661J-1458D01*
G03X1168108Y1508214I150J-132D01*
G01Y1506275D01*
G03X1168158Y1506143I200J0D01*
G02Y1503227I-1661J-1458D01*
G03X1168108Y1503095I150J-132D01*
G01Y1502476D01*
G02X1167906Y1502274I-202J0D01*
G01X1165086D01*
G02X1164884Y1502476I0J202D01*
G01Y1503095D01*
G03X1164834Y1503227I-200J0D01*
G02Y1506143I1661J1458D01*
G03X1164884Y1506275I-150J132D01*
G01Y1508214D01*
G03X1164834Y1508346I-200J0D01*
G02Y1511262I1661J1458D01*
G03X1164884Y1511394I-150J132D01*
G01Y1512014D01*
G02X1165086Y1512216I202J0D01*
G37*
G36*
G01X1182408D02*
X1185228D01*
G02X1185430Y1512014I0J-202D01*
G01Y1511394D01*
G03X1185480Y1511262I200J0D01*
G02Y1508346I-1661J-1458D01*
G03X1185430Y1508214I150J-132D01*
G01Y1506275D01*
G03X1185480Y1506143I200J0D01*
G02Y1503227I-1661J-1458D01*
G03X1185430Y1503095I150J-132D01*
G01Y1502476D01*
G02X1185228Y1502274I-202J0D01*
G01X1182408D01*
G02X1182206Y1502476I0J202D01*
G01Y1503095D01*
G03X1182156Y1503227I-200J0D01*
G02Y1506143I1661J1458D01*
G03X1182206Y1506275I-150J132D01*
G01Y1508214D01*
G03X1182156Y1508346I-200J0D01*
G02Y1511262I1661J1458D01*
G03X1182206Y1511394I-150J132D01*
G01Y1512014D01*
G02X1182408Y1512216I202J0D01*
G37*
G36*
G01X1320992D02*
X1323812D01*
G02X1324014Y1512014I0J-202D01*
G01Y1511394D01*
G03X1324064Y1511262I200J0D01*
G02Y1508346I-1661J-1458D01*
G03X1324014Y1508214I150J-132D01*
G01Y1506275D01*
G03X1324064Y1506143I200J0D01*
G02Y1503227I-1661J-1458D01*
G03X1324014Y1503095I150J-132D01*
G01Y1502476D01*
G02X1323812Y1502274I-202J0D01*
G01X1320992D01*
G02X1320790Y1502476I0J202D01*
G01Y1503095D01*
G03X1320740Y1503227I-200J0D01*
G02Y1506143I1661J1458D01*
G03X1320790Y1506275I-150J132D01*
G01Y1508214D01*
G03X1320740Y1508346I-200J0D01*
G02Y1511262I1661J1458D01*
G03X1320790Y1511394I-150J132D01*
G01Y1512014D01*
G02X1320992Y1512216I202J0D01*
G37*
G36*
G01X1494220D02*
X1497040D01*
G02X1497242Y1512014I0J-202D01*
G01Y1511394D01*
G03X1497292Y1511262I200J0D01*
G02Y1508346I-1661J-1458D01*
G03X1497242Y1508214I150J-132D01*
G01Y1506275D01*
G03X1497292Y1506143I200J0D01*
G02Y1503227I-1661J-1458D01*
G03X1497242Y1503095I150J-132D01*
G01Y1502476D01*
G02X1497040Y1502274I-202J0D01*
G01X1494220D01*
G02X1494018Y1502476I0J202D01*
G01Y1503095D01*
G03X1493968Y1503227I-200J0D01*
G02Y1506143I1661J1458D01*
G03X1494018Y1506275I-150J132D01*
G01Y1508214D01*
G03X1493968Y1508346I-200J0D01*
G02Y1511262I1661J1458D01*
G03X1494018Y1511394I-150J132D01*
G01Y1512014D01*
G02X1494220Y1512216I202J0D01*
G37*
G36*
G01X125795D02*
X128615D01*
G02X128818Y1512014I1J-202D01*
G01Y1511392D01*
G03X128868Y1511260I200J0D01*
G02Y1508348I-1664J-1456D01*
G03X128818Y1508216I150J-132D01*
G01Y1506273D01*
G03X128868Y1506141I200J0D01*
G02Y1503229I-1664J-1456D01*
G03X128818Y1503097I150J-132D01*
G01Y1502476D01*
G02X128615Y1502274I-203J1D01*
G01X125795D01*
G02X125592Y1502476I-1J202D01*
G01Y1503097D01*
G03X125542Y1503229I-200J0D01*
G02Y1506141I1664J1456D01*
G03X125592Y1506273I-150J132D01*
G01Y1508216D01*
G03X125542Y1508348I-200J0D01*
G02Y1511260I1664J1456D01*
G03X125592Y1511392I-150J132D01*
G01Y1512014D01*
G02X125795Y1512216I203J-1D01*
G37*
G36*
G01X299023D02*
X301843D01*
G02X302046Y1512014I1J-202D01*
G01Y1511392D01*
G03X302096Y1511260I200J0D01*
G02Y1508348I-1664J-1456D01*
G03X302046Y1508216I150J-132D01*
G01Y1506273D01*
G03X302096Y1506141I200J0D01*
G02Y1503229I-1664J-1456D01*
G03X302046Y1503097I150J-132D01*
G01Y1502476D01*
G02X301843Y1502274I-203J1D01*
G01X299023D01*
G02X298820Y1502476I-1J202D01*
G01Y1503097D01*
G03X298770Y1503229I-200J0D01*
G02Y1506141I1664J1456D01*
G03X298820Y1506273I-150J132D01*
G01Y1508216D01*
G03X298770Y1508348I-200J0D01*
G02Y1511260I1664J1456D01*
G03X298820Y1511392I-150J132D01*
G01Y1512014D01*
G02X299023Y1512216I203J-1D01*
G37*
G36*
G01X454929D02*
X457749D01*
G02X457952Y1512014I1J-202D01*
G01Y1511392D01*
G03X458002Y1511260I200J0D01*
G02Y1508348I-1664J-1456D01*
G03X457952Y1508216I150J-132D01*
G01Y1506273D01*
G03X458002Y1506141I200J0D01*
G02Y1503229I-1664J-1456D01*
G03X457952Y1503097I150J-132D01*
G01Y1502476D01*
G02X457749Y1502274I-203J1D01*
G01X454929D01*
G02X454726Y1502476I-1J202D01*
G01Y1503097D01*
G03X454676Y1503229I-200J0D01*
G02Y1506141I1664J1456D01*
G03X454726Y1506273I-150J132D01*
G01Y1508216D01*
G03X454676Y1508348I-200J0D01*
G02Y1511260I1664J1456D01*
G03X454726Y1511392I-150J132D01*
G01Y1512014D01*
G02X454929Y1512216I203J-1D01*
G37*
G36*
G01X489575D02*
X492395D01*
G02X492598Y1512014I1J-202D01*
G01Y1511392D01*
G03X492648Y1511260I200J0D01*
G02Y1508348I-1664J-1456D01*
G03X492598Y1508216I150J-132D01*
G01Y1506273D01*
G03X492648Y1506141I200J0D01*
G02Y1503229I-1664J-1456D01*
G03X492598Y1503097I150J-132D01*
G01Y1502476D01*
G02X492395Y1502274I-203J1D01*
G01X489575D01*
G02X489372Y1502476I-1J202D01*
G01Y1503097D01*
G03X489322Y1503229I-200J0D01*
G02Y1506141I1664J1456D01*
G03X489372Y1506273I-150J132D01*
G01Y1508216D01*
G03X489322Y1508348I-200J0D01*
G02Y1511260I1664J1456D01*
G03X489372Y1511392I-150J132D01*
G01Y1512014D01*
G02X489575Y1512216I203J-1D01*
G37*
G36*
G01X506897D02*
X509717D01*
G02X509920Y1512014I1J-202D01*
G01Y1511392D01*
G03X509970Y1511260I200J0D01*
G02Y1508348I-1664J-1456D01*
G03X509920Y1508216I150J-132D01*
G01Y1506273D01*
G03X509970Y1506141I200J0D01*
G02Y1503229I-1664J-1456D01*
G03X509920Y1503097I150J-132D01*
G01Y1502476D01*
G02X509717Y1502274I-203J1D01*
G01X506897D01*
G02X506694Y1502476I-1J202D01*
G01Y1503097D01*
G03X506644Y1503229I-200J0D01*
G02Y1506141I1664J1456D01*
G03X506694Y1506273I-150J132D01*
G01Y1508216D01*
G03X506644Y1508348I-200J0D01*
G02Y1511260I1664J1456D01*
G03X506694Y1511392I-150J132D01*
G01Y1512014D01*
G02X506897Y1512216I203J-1D01*
G37*
G36*
G01X662803D02*
X665623D01*
G02X665826Y1512014I1J-202D01*
G01Y1511392D01*
G03X665876Y1511260I200J0D01*
G02Y1508348I-1664J-1456D01*
G03X665826Y1508216I150J-132D01*
G01Y1506273D01*
G03X665876Y1506141I200J0D01*
G02Y1503229I-1664J-1456D01*
G03X665826Y1503097I150J-132D01*
G01Y1502476D01*
G02X665623Y1502274I-203J1D01*
G01X662803D01*
G02X662600Y1502476I-1J202D01*
G01Y1503097D01*
G03X662550Y1503229I-200J0D01*
G02Y1506141I1664J1456D01*
G03X662600Y1506273I-150J132D01*
G01Y1508216D01*
G03X662550Y1508348I-200J0D01*
G02Y1511260I1664J1456D01*
G03X662600Y1511392I-150J132D01*
G01Y1512014D01*
G02X662803Y1512216I203J-1D01*
G37*
G36*
G01X680125D02*
X682945D01*
G02X683148Y1512014I1J-202D01*
G01Y1511392D01*
G03X683198Y1511260I200J0D01*
G02Y1508348I-1664J-1456D01*
G03X683148Y1508216I150J-132D01*
G01Y1506273D01*
G03X683198Y1506141I200J0D01*
G02Y1503229I-1664J-1456D01*
G03X683148Y1503097I150J-132D01*
G01Y1502476D01*
G02X682945Y1502274I-203J1D01*
G01X680125D01*
G02X679922Y1502476I-1J202D01*
G01Y1503097D01*
G03X679872Y1503229I-200J0D01*
G02Y1506141I1664J1456D01*
G03X679922Y1506273I-150J132D01*
G01Y1508216D01*
G03X679872Y1508348I-200J0D01*
G02Y1511260I1664J1456D01*
G03X679922Y1511392I-150J132D01*
G01Y1512014D01*
G02X680125Y1512216I203J-1D01*
G37*
G36*
G01X1303669D02*
X1306489D01*
G02X1306692Y1512014I1J-202D01*
G01Y1511392D01*
G03X1306742Y1511260I200J0D01*
G02Y1508348I-1664J-1456D01*
G03X1306692Y1508216I150J-132D01*
G01Y1506273D01*
G03X1306742Y1506141I200J0D01*
G02Y1503229I-1664J-1456D01*
G03X1306692Y1503097I150J-132D01*
G01Y1502476D01*
G02X1306489Y1502274I-203J1D01*
G01X1303669D01*
G02X1303466Y1502476I-1J202D01*
G01Y1503097D01*
G03X1303416Y1503229I-200J0D01*
G02Y1506141I1664J1456D01*
G03X1303466Y1506273I-150J132D01*
G01Y1508216D01*
G03X1303416Y1508348I-200J0D01*
G02Y1511260I1664J1456D01*
G03X1303466Y1511392I-150J132D01*
G01Y1512014D01*
G02X1303669Y1512216I203J-1D01*
G37*
G36*
G01X1338315D02*
X1341135D01*
G02X1341338Y1512014I1J-202D01*
G01Y1511392D01*
G03X1341388Y1511260I200J0D01*
G02Y1508348I-1664J-1456D01*
G03X1341338Y1508216I150J-132D01*
G01Y1506273D01*
G03X1341388Y1506141I200J0D01*
G02Y1503229I-1664J-1456D01*
G03X1341338Y1503097I150J-132D01*
G01Y1502476D01*
G02X1341135Y1502274I-203J1D01*
G01X1338315D01*
G02X1338112Y1502476I-1J202D01*
G01Y1503097D01*
G03X1338062Y1503229I-200J0D01*
G02Y1506141I1664J1456D01*
G03X1338112Y1506273I-150J132D01*
G01Y1508216D01*
G03X1338062Y1508348I-200J0D01*
G02Y1511260I1664J1456D01*
G03X1338112Y1511392I-150J132D01*
G01Y1512014D01*
G02X1338315Y1512216I203J-1D01*
G37*
G36*
G01X1355637D02*
X1358457D01*
G02X1358660Y1512014I1J-202D01*
G01Y1511392D01*
G03X1358710Y1511260I200J0D01*
G02Y1508348I-1664J-1456D01*
G03X1358660Y1508216I150J-132D01*
G01Y1506273D01*
G03X1358710Y1506141I200J0D01*
G02Y1503229I-1664J-1456D01*
G03X1358660Y1503097I150J-132D01*
G01Y1502476D01*
G02X1358457Y1502274I-203J1D01*
G01X1355637D01*
G02X1355434Y1502476I-1J202D01*
G01Y1503097D01*
G03X1355384Y1503229I-200J0D01*
G02Y1506141I1664J1456D01*
G03X1355434Y1506273I-150J132D01*
G01Y1508216D01*
G03X1355384Y1508348I-200J0D01*
G02Y1511260I1664J1456D01*
G03X1355434Y1511392I-150J132D01*
G01Y1512014D01*
G02X1355637Y1512216I203J-1D01*
G37*
G36*
G01X1476897D02*
X1479717D01*
G02X1479920Y1512014I1J-202D01*
G01Y1511392D01*
G03X1479970Y1511260I200J0D01*
G02Y1508348I-1664J-1456D01*
G03X1479920Y1508216I150J-132D01*
G01Y1506273D01*
G03X1479970Y1506141I200J0D01*
G02Y1503229I-1664J-1456D01*
G03X1479920Y1503097I150J-132D01*
G01Y1502476D01*
G02X1479717Y1502274I-203J1D01*
G01X1476897D01*
G02X1476694Y1502476I-1J202D01*
G01Y1503097D01*
G03X1476644Y1503229I-200J0D01*
G02Y1506141I1664J1456D01*
G03X1476694Y1506273I-150J132D01*
G01Y1508216D01*
G03X1476644Y1508348I-200J0D01*
G02Y1511260I1664J1456D01*
G03X1476694Y1511392I-150J132D01*
G01Y1512014D01*
G02X1476897Y1512216I203J-1D01*
G37*
G36*
G01X1511543D02*
X1514363D01*
G02X1514566Y1512014I1J-202D01*
G01Y1511392D01*
G03X1514616Y1511260I200J0D01*
G02Y1508348I-1664J-1456D01*
G03X1514566Y1508216I150J-132D01*
G01Y1506273D01*
G03X1514616Y1506141I200J0D01*
G02Y1503229I-1664J-1456D01*
G03X1514566Y1503097I150J-132D01*
G01Y1502476D01*
G02X1514363Y1502274I-203J1D01*
G01X1511543D01*
G02X1511340Y1502476I-1J202D01*
G01Y1503097D01*
G03X1511290Y1503229I-200J0D01*
G02Y1506141I1664J1456D01*
G03X1511340Y1506273I-150J132D01*
G01Y1508216D01*
G03X1511290Y1508348I-200J0D01*
G02Y1511260I1664J1456D01*
G03X1511340Y1511392I-150J132D01*
G01Y1512014D01*
G02X1511543Y1512216I203J-1D01*
G37*
G36*
G01X1528865D02*
X1531685D01*
G02X1531888Y1512014I1J-202D01*
G01Y1511392D01*
G03X1531938Y1511260I200J0D01*
G02Y1508348I-1664J-1456D01*
G03X1531888Y1508216I150J-132D01*
G01Y1506273D01*
G03X1531938Y1506141I200J0D01*
G02Y1503229I-1664J-1456D01*
G03X1531888Y1503097I150J-132D01*
G01Y1502476D01*
G02X1531685Y1502274I-203J1D01*
G01X1528865D01*
G02X1528662Y1502476I-1J202D01*
G01Y1503097D01*
G03X1528612Y1503229I-200J0D01*
G02Y1506141I1664J1456D01*
G03X1528662Y1506273I-150J132D01*
G01Y1508216D01*
G03X1528612Y1508348I-200J0D01*
G02Y1511260I1664J1456D01*
G03X1528662Y1511392I-150J132D01*
G01Y1512014D01*
G02X1528865Y1512216I203J-1D01*
G37*
G36*
G01X1684771D02*
X1687591D01*
G02X1687794Y1512014I1J-202D01*
G01Y1511392D01*
G03X1687844Y1511260I200J0D01*
G02Y1508348I-1664J-1456D01*
G03X1687794Y1508216I150J-132D01*
G01Y1506273D01*
G03X1687844Y1506141I200J0D01*
G02Y1503229I-1664J-1456D01*
G03X1687794Y1503097I150J-132D01*
G01Y1502476D01*
G02X1687591Y1502274I-203J1D01*
G01X1684771D01*
G02X1684568Y1502476I-1J202D01*
G01Y1503097D01*
G03X1684518Y1503229I-200J0D01*
G02Y1506141I1664J1456D01*
G03X1684568Y1506273I-150J132D01*
G01Y1508216D01*
G03X1684518Y1508348I-200J0D01*
G02Y1511260I1664J1456D01*
G03X1684568Y1511392I-150J132D01*
G01Y1512014D01*
G02X1684771Y1512216I203J-1D01*
G37*
G36*
G01X1702093D02*
X1704913D01*
G02X1705116Y1512014I1J-202D01*
G01Y1511392D01*
G03X1705166Y1511260I200J0D01*
G02Y1508348I-1664J-1456D01*
G03X1705116Y1508216I150J-132D01*
G01Y1506273D01*
G03X1705166Y1506141I200J0D01*
G02Y1503229I-1664J-1456D01*
G03X1705116Y1503097I150J-132D01*
G01Y1502476D01*
G02X1704913Y1502274I-203J1D01*
G01X1702093D01*
G02X1701890Y1502476I-1J202D01*
G01Y1503097D01*
G03X1701840Y1503229I-200J0D01*
G02Y1506141I1664J1456D01*
G03X1701890Y1506273I-150J132D01*
G01Y1508216D01*
G03X1701840Y1508348I-200J0D01*
G02Y1511260I1664J1456D01*
G03X1701890Y1511392I-150J132D01*
G01Y1512014D01*
G02X1702093Y1512216I203J-1D01*
G37*
G36*
G01X134456Y1516546D02*
X137276D01*
G02X137478Y1516344I0J-202D01*
G01Y1515724D01*
G03X137528Y1515592I200J0D01*
G02Y1512676I-1661J-1458D01*
G03X137478Y1512544I150J-132D01*
G01Y1510606D01*
G03X137528Y1510474I200J0D01*
G02Y1507558I-1661J-1458D01*
G03X137478Y1507426I150J-132D01*
G01Y1506806D01*
G02X137276Y1506604I-202J0D01*
G01X134456D01*
G02X134254Y1506806I0J202D01*
G01Y1507426D01*
G03X134204Y1507558I-200J0D01*
G02Y1510474I1661J1458D01*
G03X134254Y1510606I-150J132D01*
G01Y1512544D01*
G03X134204Y1512676I-200J0D01*
G02Y1515592I1661J1458D01*
G03X134254Y1515724I-150J132D01*
G01Y1516344D01*
G02X134456Y1516546I202J0D01*
G37*
G36*
G01X169102D02*
X171922D01*
G02X172124Y1516344I0J-202D01*
G01Y1515724D01*
G03X172174Y1515592I200J0D01*
G02Y1512676I-1661J-1458D01*
G03X172124Y1512544I150J-132D01*
G01Y1510606D01*
G03X172174Y1510474I200J0D01*
G02Y1507558I-1661J-1458D01*
G03X172124Y1507426I150J-132D01*
G01Y1506806D01*
G02X171922Y1506604I-202J0D01*
G01X169102D01*
G02X168900Y1506806I0J202D01*
G01Y1507426D01*
G03X168850Y1507558I-200J0D01*
G02Y1510474I1661J1458D01*
G03X168900Y1510606I-150J132D01*
G01Y1512544D01*
G03X168850Y1512676I-200J0D01*
G02Y1515592I1661J1458D01*
G03X168900Y1515724I-150J132D01*
G01Y1516344D01*
G02X169102Y1516546I202J0D01*
G37*
G36*
G01X463590D02*
X466410D01*
G02X466612Y1516344I0J-202D01*
G01Y1515724D01*
G03X466662Y1515592I200J0D01*
G02Y1512676I-1661J-1458D01*
G03X466612Y1512544I150J-132D01*
G01Y1510606D01*
G03X466662Y1510474I200J0D01*
G02Y1507558I-1661J-1458D01*
G03X466612Y1507426I150J-132D01*
G01Y1506806D01*
G02X466410Y1506604I-202J0D01*
G01X463590D01*
G02X463388Y1506806I0J202D01*
G01Y1507426D01*
G03X463338Y1507558I-200J0D01*
G02Y1510474I1661J1458D01*
G03X463388Y1510606I-150J132D01*
G01Y1512544D01*
G03X463338Y1512676I-200J0D01*
G02Y1515592I1661J1458D01*
G03X463388Y1515724I-150J132D01*
G01Y1516344D01*
G02X463590Y1516546I202J0D01*
G37*
G36*
G01X498236D02*
X501056D01*
G02X501258Y1516344I0J-202D01*
G01Y1515724D01*
G03X501308Y1515592I200J0D01*
G02Y1512676I-1661J-1458D01*
G03X501258Y1512544I150J-132D01*
G01Y1510606D01*
G03X501308Y1510474I200J0D01*
G02Y1507558I-1661J-1458D01*
G03X501258Y1507426I150J-132D01*
G01Y1506806D01*
G02X501056Y1506604I-202J0D01*
G01X498236D01*
G02X498034Y1506806I0J202D01*
G01Y1507426D01*
G03X497984Y1507558I-200J0D01*
G02Y1510474I1661J1458D01*
G03X498034Y1510606I-150J132D01*
G01Y1512544D01*
G03X497984Y1512676I-200J0D01*
G02Y1515592I1661J1458D01*
G03X498034Y1515724I-150J132D01*
G01Y1516344D01*
G02X498236Y1516546I202J0D01*
G37*
G36*
G01X671464D02*
X674284D01*
G02X674486Y1516344I0J-202D01*
G01Y1515724D01*
G03X674536Y1515592I200J0D01*
G02Y1512676I-1661J-1458D01*
G03X674486Y1512544I150J-132D01*
G01Y1510606D01*
G03X674536Y1510474I200J0D01*
G02Y1507558I-1661J-1458D01*
G03X674486Y1507426I150J-132D01*
G01Y1506806D01*
G02X674284Y1506604I-202J0D01*
G01X671464D01*
G02X671262Y1506806I0J202D01*
G01Y1507426D01*
G03X671212Y1507558I-200J0D01*
G02Y1510474I1661J1458D01*
G03X671262Y1510606I-150J132D01*
G01Y1512544D01*
G03X671212Y1512676I-200J0D01*
G02Y1515592I1661J1458D01*
G03X671262Y1515724I-150J132D01*
G01Y1516344D01*
G02X671464Y1516546I202J0D01*
G37*
G36*
G01X1191070D02*
X1193890D01*
G02X1194092Y1516344I0J-202D01*
G01Y1515724D01*
G03X1194142Y1515592I200J0D01*
G02Y1512676I-1661J-1458D01*
G03X1194092Y1512544I150J-132D01*
G01Y1510606D01*
G03X1194142Y1510474I200J0D01*
G02Y1507558I-1661J-1458D01*
G03X1194092Y1507426I150J-132D01*
G01Y1506806D01*
G02X1193890Y1506604I-202J0D01*
G01X1191070D01*
G02X1190868Y1506806I0J202D01*
G01Y1507426D01*
G03X1190818Y1507558I-200J0D01*
G02Y1510474I1661J1458D01*
G03X1190868Y1510606I-150J132D01*
G01Y1512544D01*
G03X1190818Y1512676I-200J0D01*
G02Y1515592I1661J1458D01*
G03X1190868Y1515724I-150J132D01*
G01Y1516344D01*
G02X1191070Y1516546I202J0D01*
G37*
G36*
G01X1312330D02*
X1315150D01*
G02X1315352Y1516344I0J-202D01*
G01Y1515724D01*
G03X1315402Y1515592I200J0D01*
G02Y1512676I-1661J-1458D01*
G03X1315352Y1512544I150J-132D01*
G01Y1510606D01*
G03X1315402Y1510474I200J0D01*
G02Y1507558I-1661J-1458D01*
G03X1315352Y1507426I150J-132D01*
G01Y1506806D01*
G02X1315150Y1506604I-202J0D01*
G01X1312330D01*
G02X1312128Y1506806I0J202D01*
G01Y1507426D01*
G03X1312078Y1507558I-200J0D01*
G02Y1510474I1661J1458D01*
G03X1312128Y1510606I-150J132D01*
G01Y1512544D01*
G03X1312078Y1512676I-200J0D01*
G02Y1515592I1661J1458D01*
G03X1312128Y1515724I-150J132D01*
G01Y1516344D01*
G02X1312330Y1516546I202J0D01*
G37*
G36*
G01X1346976D02*
X1349796D01*
G02X1349998Y1516344I0J-202D01*
G01Y1515724D01*
G03X1350048Y1515592I200J0D01*
G02Y1512676I-1661J-1458D01*
G03X1349998Y1512544I150J-132D01*
G01Y1510606D01*
G03X1350048Y1510474I200J0D01*
G02Y1507558I-1661J-1458D01*
G03X1349998Y1507426I150J-132D01*
G01Y1506806D01*
G02X1349796Y1506604I-202J0D01*
G01X1346976D01*
G02X1346774Y1506806I0J202D01*
G01Y1507426D01*
G03X1346724Y1507558I-200J0D01*
G02Y1510474I1661J1458D01*
G03X1346774Y1510606I-150J132D01*
G01Y1512544D01*
G03X1346724Y1512676I-200J0D01*
G02Y1515592I1661J1458D01*
G03X1346774Y1515724I-150J132D01*
G01Y1516344D01*
G02X1346976Y1516546I202J0D01*
G37*
G36*
G01X1485558D02*
X1488378D01*
G02X1488580Y1516344I0J-202D01*
G01Y1515724D01*
G03X1488630Y1515592I200J0D01*
G02Y1512676I-1661J-1458D01*
G03X1488580Y1512544I150J-132D01*
G01Y1510606D01*
G03X1488630Y1510474I200J0D01*
G02Y1507558I-1661J-1458D01*
G03X1488580Y1507426I150J-132D01*
G01Y1506806D01*
G02X1488378Y1506604I-202J0D01*
G01X1485558D01*
G02X1485356Y1506806I0J202D01*
G01Y1507426D01*
G03X1485306Y1507558I-200J0D01*
G02Y1510474I1661J1458D01*
G03X1485356Y1510606I-150J132D01*
G01Y1512544D01*
G03X1485306Y1512676I-200J0D01*
G02Y1515592I1661J1458D01*
G03X1485356Y1515724I-150J132D01*
G01Y1516344D01*
G02X1485558Y1516546I202J0D01*
G37*
G36*
G01X1520204D02*
X1523024D01*
G02X1523226Y1516344I0J-202D01*
G01Y1515724D01*
G03X1523276Y1515592I200J0D01*
G02Y1512676I-1661J-1458D01*
G03X1523226Y1512544I150J-132D01*
G01Y1510606D01*
G03X1523276Y1510474I200J0D01*
G02Y1507558I-1661J-1458D01*
G03X1523226Y1507426I150J-132D01*
G01Y1506806D01*
G02X1523024Y1506604I-202J0D01*
G01X1520204D01*
G02X1520002Y1506806I0J202D01*
G01Y1507426D01*
G03X1519952Y1507558I-200J0D01*
G02Y1510474I1661J1458D01*
G03X1520002Y1510606I-150J132D01*
G01Y1512544D01*
G03X1519952Y1512676I-200J0D01*
G02Y1515592I1661J1458D01*
G03X1520002Y1515724I-150J132D01*
G01Y1516344D01*
G02X1520204Y1516546I202J0D01*
G37*
G36*
G01X1693432D02*
X1696252D01*
G02X1696454Y1516344I0J-202D01*
G01Y1515724D01*
G03X1696504Y1515592I200J0D01*
G02Y1512676I-1661J-1458D01*
G03X1696454Y1512544I150J-132D01*
G01Y1510606D01*
G03X1696504Y1510474I200J0D01*
G02Y1507558I-1661J-1458D01*
G03X1696454Y1507426I150J-132D01*
G01Y1506806D01*
G02X1696252Y1506604I-202J0D01*
G01X1693432D01*
G02X1693230Y1506806I0J202D01*
G01Y1507426D01*
G03X1693180Y1507558I-200J0D01*
G02Y1510474I1661J1458D01*
G03X1693230Y1510606I-150J132D01*
G01Y1512544D01*
G03X1693180Y1512676I-200J0D01*
G02Y1515592I1661J1458D01*
G03X1693230Y1515724I-150J132D01*
G01Y1516344D01*
G02X1693432Y1516546I202J0D01*
G37*
G36*
G01X151779D02*
X154599D01*
G02X154802Y1516344I1J-202D01*
G01Y1515722D01*
G03X154852Y1515590I200J0D01*
G02Y1512678I-1664J-1456D01*
G03X154802Y1512546I150J-132D01*
G01Y1510604D01*
G03X154852Y1510472I200J0D01*
G02Y1507560I-1664J-1456D01*
G03X154802Y1507428I150J-132D01*
G01Y1506806D01*
G02X154599Y1506604I-203J1D01*
G01X151779D01*
G02X151576Y1506806I-1J202D01*
G01Y1507428D01*
G03X151526Y1507560I-200J0D01*
G02Y1510472I1664J1456D01*
G03X151576Y1510604I-150J132D01*
G01Y1512546D01*
G03X151526Y1512678I-200J0D01*
G02Y1515590I1664J1456D01*
G03X151576Y1515722I-150J132D01*
G01Y1516344D01*
G02X151779Y1516546I203J-1D01*
G37*
G36*
G01X290361D02*
X293181D01*
G02X293384Y1516344I1J-202D01*
G01Y1515722D01*
G03X293434Y1515590I200J0D01*
G02Y1512678I-1664J-1456D01*
G03X293384Y1512546I150J-132D01*
G01Y1510604D01*
G03X293434Y1510472I200J0D01*
G02Y1507560I-1664J-1456D01*
G03X293384Y1507428I150J-132D01*
G01Y1506806D01*
G02X293181Y1506604I-203J1D01*
G01X290361D01*
G02X290158Y1506806I-1J202D01*
G01Y1507428D01*
G03X290108Y1507560I-200J0D01*
G02Y1510472I1664J1456D01*
G03X290158Y1510604I-150J132D01*
G01Y1512546D01*
G03X290108Y1512678I-200J0D01*
G02Y1515590I1664J1456D01*
G03X290158Y1515722I-150J132D01*
G01Y1516344D01*
G02X290361Y1516546I203J-1D01*
G37*
G36*
G01X480913D02*
X483733D01*
G02X483936Y1516344I1J-202D01*
G01Y1515722D01*
G03X483986Y1515590I200J0D01*
G02Y1512678I-1664J-1456D01*
G03X483936Y1512546I150J-132D01*
G01Y1510604D01*
G03X483986Y1510472I200J0D01*
G02Y1507560I-1664J-1456D01*
G03X483936Y1507428I150J-132D01*
G01Y1506806D01*
G02X483733Y1506604I-203J1D01*
G01X480913D01*
G02X480710Y1506806I-1J202D01*
G01Y1507428D01*
G03X480660Y1507560I-200J0D01*
G02Y1510472I1664J1456D01*
G03X480710Y1510604I-150J132D01*
G01Y1512546D01*
G03X480660Y1512678I-200J0D01*
G02Y1515590I1664J1456D01*
G03X480710Y1515722I-150J132D01*
G01Y1516344D01*
G02X480913Y1516546I203J-1D01*
G37*
G36*
G01X515559D02*
X518379D01*
G02X518582Y1516344I1J-202D01*
G01Y1515722D01*
G03X518632Y1515590I200J0D01*
G02Y1512678I-1664J-1456D01*
G03X518582Y1512546I150J-132D01*
G01Y1510604D01*
G03X518632Y1510472I200J0D01*
G02Y1507560I-1664J-1456D01*
G03X518582Y1507428I150J-132D01*
G01Y1506806D01*
G02X518379Y1506604I-203J1D01*
G01X515559D01*
G02X515356Y1506806I-1J202D01*
G01Y1507428D01*
G03X515306Y1507560I-200J0D01*
G02Y1510472I1664J1456D01*
G03X515356Y1510604I-150J132D01*
G01Y1512546D01*
G03X515306Y1512678I-200J0D01*
G02Y1515590I1664J1456D01*
G03X515356Y1515722I-150J132D01*
G01Y1516344D01*
G02X515559Y1516546I203J-1D01*
G37*
G36*
G01X654141D02*
X656961D01*
G02X657164Y1516344I1J-202D01*
G01Y1515722D01*
G03X657214Y1515590I200J0D01*
G02Y1512678I-1664J-1456D01*
G03X657164Y1512546I150J-132D01*
G01Y1510604D01*
G03X657214Y1510472I200J0D01*
G02Y1507560I-1664J-1456D01*
G03X657164Y1507428I150J-132D01*
G01Y1506806D01*
G02X656961Y1506604I-203J1D01*
G01X654141D01*
G02X653938Y1506806I-1J202D01*
G01Y1507428D01*
G03X653888Y1507560I-200J0D01*
G02Y1510472I1664J1456D01*
G03X653938Y1510604I-150J132D01*
G01Y1512546D01*
G03X653888Y1512678I-200J0D01*
G02Y1515590I1664J1456D01*
G03X653938Y1515722I-150J132D01*
G01Y1516344D01*
G02X654141Y1516546I203J-1D01*
G37*
G36*
G01X688787D02*
X691607D01*
G02X691810Y1516344I1J-202D01*
G01Y1515722D01*
G03X691860Y1515590I200J0D01*
G02Y1512678I-1664J-1456D01*
G03X691810Y1512546I150J-132D01*
G01Y1510604D01*
G03X691860Y1510472I200J0D01*
G02Y1507560I-1664J-1456D01*
G03X691810Y1507428I150J-132D01*
G01Y1506806D01*
G02X691607Y1506604I-203J1D01*
G01X688787D01*
G02X688584Y1506806I-1J202D01*
G01Y1507428D01*
G03X688534Y1507560I-200J0D01*
G02Y1510472I1664J1456D01*
G03X688584Y1510604I-150J132D01*
G01Y1512546D01*
G03X688534Y1512678I-200J0D01*
G02Y1515590I1664J1456D01*
G03X688584Y1515722I-150J132D01*
G01Y1516344D01*
G02X688787Y1516546I203J-1D01*
G37*
G36*
G01X1173747D02*
X1176567D01*
G02X1176770Y1516344I1J-202D01*
G01Y1515722D01*
G03X1176820Y1515590I200J0D01*
G02Y1512678I-1664J-1456D01*
G03X1176770Y1512546I150J-132D01*
G01Y1510604D01*
G03X1176820Y1510472I200J0D01*
G02Y1507560I-1664J-1456D01*
G03X1176770Y1507428I150J-132D01*
G01Y1506806D01*
G02X1176567Y1506604I-203J1D01*
G01X1173747D01*
G02X1173544Y1506806I-1J202D01*
G01Y1507428D01*
G03X1173494Y1507560I-200J0D01*
G02Y1510472I1664J1456D01*
G03X1173544Y1510604I-150J132D01*
G01Y1512546D01*
G03X1173494Y1512678I-200J0D01*
G02Y1515590I1664J1456D01*
G03X1173544Y1515722I-150J132D01*
G01Y1516344D01*
G02X1173747Y1516546I203J-1D01*
G37*
G36*
G01X1329653D02*
X1332473D01*
G02X1332676Y1516344I1J-202D01*
G01Y1515722D01*
G03X1332726Y1515590I200J0D01*
G02Y1512678I-1664J-1456D01*
G03X1332676Y1512546I150J-132D01*
G01Y1510604D01*
G03X1332726Y1510472I200J0D01*
G02Y1507560I-1664J-1456D01*
G03X1332676Y1507428I150J-132D01*
G01Y1506806D01*
G02X1332473Y1506604I-203J1D01*
G01X1329653D01*
G02X1329450Y1506806I-1J202D01*
G01Y1507428D01*
G03X1329400Y1507560I-200J0D01*
G02Y1510472I1664J1456D01*
G03X1329450Y1510604I-150J132D01*
G01Y1512546D01*
G03X1329400Y1512678I-200J0D01*
G02Y1515590I1664J1456D01*
G03X1329450Y1515722I-150J132D01*
G01Y1516344D01*
G02X1329653Y1516546I203J-1D01*
G37*
G36*
G01X1364299D02*
X1367119D01*
G02X1367322Y1516344I1J-202D01*
G01Y1515722D01*
G03X1367372Y1515590I200J0D01*
G02Y1512678I-1664J-1456D01*
G03X1367322Y1512546I150J-132D01*
G01Y1510604D01*
G03X1367372Y1510472I200J0D01*
G02Y1507560I-1664J-1456D01*
G03X1367322Y1507428I150J-132D01*
G01Y1506806D01*
G02X1367119Y1506604I-203J1D01*
G01X1364299D01*
G02X1364096Y1506806I-1J202D01*
G01Y1507428D01*
G03X1364046Y1507560I-200J0D01*
G02Y1510472I1664J1456D01*
G03X1364096Y1510604I-150J132D01*
G01Y1512546D01*
G03X1364046Y1512678I-200J0D01*
G02Y1515590I1664J1456D01*
G03X1364096Y1515722I-150J132D01*
G01Y1516344D01*
G02X1364299Y1516546I203J-1D01*
G37*
G36*
G01X1502881D02*
X1505701D01*
G02X1505904Y1516344I1J-202D01*
G01Y1515722D01*
G03X1505954Y1515590I200J0D01*
G02Y1512678I-1664J-1456D01*
G03X1505904Y1512546I150J-132D01*
G01Y1510604D01*
G03X1505954Y1510472I200J0D01*
G02Y1507560I-1664J-1456D01*
G03X1505904Y1507428I150J-132D01*
G01Y1506806D01*
G02X1505701Y1506604I-203J1D01*
G01X1502881D01*
G02X1502678Y1506806I-1J202D01*
G01Y1507428D01*
G03X1502628Y1507560I-200J0D01*
G02Y1510472I1664J1456D01*
G03X1502678Y1510604I-150J132D01*
G01Y1512546D01*
G03X1502628Y1512678I-200J0D01*
G02Y1515590I1664J1456D01*
G03X1502678Y1515722I-150J132D01*
G01Y1516344D01*
G02X1502881Y1516546I203J-1D01*
G37*
G36*
G01X1537527D02*
X1540347D01*
G02X1540550Y1516344I1J-202D01*
G01Y1515722D01*
G03X1540600Y1515590I200J0D01*
G02Y1512678I-1664J-1456D01*
G03X1540550Y1512546I150J-132D01*
G01Y1510604D01*
G03X1540600Y1510472I200J0D01*
G02Y1507560I-1664J-1456D01*
G03X1540550Y1507428I150J-132D01*
G01Y1506806D01*
G02X1540347Y1506604I-203J1D01*
G01X1537527D01*
G02X1537324Y1506806I-1J202D01*
G01Y1507428D01*
G03X1537274Y1507560I-200J0D01*
G02Y1510472I1664J1456D01*
G03X1537324Y1510604I-150J132D01*
G01Y1512546D01*
G03X1537274Y1512678I-200J0D01*
G02Y1515590I1664J1456D01*
G03X1537324Y1515722I-150J132D01*
G01Y1516344D01*
G02X1537527Y1516546I203J-1D01*
G37*
G36*
G01X1710755D02*
X1713575D01*
G02X1713778Y1516344I1J-202D01*
G01Y1515722D01*
G03X1713828Y1515590I200J0D01*
G02Y1512678I-1664J-1456D01*
G03X1713778Y1512546I150J-132D01*
G01Y1510604D01*
G03X1713828Y1510472I200J0D01*
G02Y1507560I-1664J-1456D01*
G03X1713778Y1507428I150J-132D01*
G01Y1506806D01*
G02X1713575Y1506604I-203J1D01*
G01X1710755D01*
G02X1710552Y1506806I-1J202D01*
G01Y1507428D01*
G03X1710502Y1507560I-200J0D01*
G02Y1510472I1664J1456D01*
G03X1710552Y1510604I-150J132D01*
G01Y1512546D01*
G03X1710502Y1512678I-200J0D01*
G02Y1515590I1664J1456D01*
G03X1710552Y1515722I-150J132D01*
G01Y1516344D01*
G02X1710755Y1516546I203J-1D01*
G37*
G36*
G01X108472Y1568516D02*
X111292D01*
G02X111494Y1568313I-1J-203D01*
G01Y1567693D01*
G03X111544Y1567561I200J0D01*
G02Y1564645I-1661J-1458D01*
G03X111494Y1564513I150J-132D01*
G01Y1562575D01*
G03X111544Y1562443I200J0D01*
G02Y1559527I-1661J-1458D01*
G03X111494Y1559395I150J-132D01*
G01Y1558775D01*
G02X111292Y1558572I-202J-1D01*
G01X108472D01*
G02X108270Y1558775I1J203D01*
G01Y1559395D01*
G03X108220Y1559527I-200J0D01*
G02Y1562443I1661J1458D01*
G03X108270Y1562575I-150J132D01*
G01Y1564513D01*
G03X108220Y1564645I-200J0D01*
G02Y1567561I1661J1458D01*
G03X108270Y1567693I-150J132D01*
G01Y1568313D01*
G02X108472Y1568516I202J1D01*
G37*
G36*
G01X125795D02*
X128615D01*
G02X128818Y1568313I0J-203D01*
G01Y1567691D01*
G03X128868Y1567559I200J0D01*
G02Y1564647I-1664J-1456D01*
G03X128818Y1564515I150J-132D01*
G01Y1562573D01*
G03X128868Y1562441I200J0D01*
G02Y1559529I-1664J-1456D01*
G03X128818Y1559397I150J-132D01*
G01Y1558775D01*
G02X128615Y1558572I-203J0D01*
G01X125795D01*
G02X125592Y1558775I0J203D01*
G01Y1559397D01*
G03X125542Y1559529I-200J0D01*
G02Y1562441I1664J1456D01*
G03X125592Y1562573I-150J132D01*
G01Y1564515D01*
G03X125542Y1564647I-200J0D01*
G02Y1567559I1664J1456D01*
G03X125592Y1567691I-150J132D01*
G01Y1568313D01*
G02X125795Y1568516I203J0D01*
G37*
G36*
G01X143118D02*
X145938D01*
G02X146140Y1568313I-1J-203D01*
G01Y1567693D01*
G03X146190Y1567561I200J0D01*
G02Y1564645I-1661J-1458D01*
G03X146140Y1564513I150J-132D01*
G01Y1562575D01*
G03X146190Y1562443I200J0D01*
G02Y1559527I-1661J-1458D01*
G03X146140Y1559395I150J-132D01*
G01Y1558775D01*
G02X145938Y1558572I-202J-1D01*
G01X143118D01*
G02X142916Y1558775I1J203D01*
G01Y1559395D01*
G03X142866Y1559527I-200J0D01*
G02Y1562443I1661J1458D01*
G03X142916Y1562575I-150J132D01*
G01Y1564513D01*
G03X142866Y1564645I-200J0D01*
G02Y1567561I1661J1458D01*
G03X142916Y1567693I-150J132D01*
G01Y1568313D01*
G02X143118Y1568516I202J1D01*
G37*
G36*
G01X160440D02*
X163260D01*
G02X163462Y1568313I-1J-203D01*
G01Y1567693D01*
G03X163512Y1567561I200J0D01*
G02Y1564645I-1661J-1458D01*
G03X163462Y1564513I150J-132D01*
G01Y1562575D01*
G03X163512Y1562443I200J0D01*
G02Y1559527I-1661J-1458D01*
G03X163462Y1559395I150J-132D01*
G01Y1558775D01*
G02X163260Y1558572I-202J-1D01*
G01X160440D01*
G02X160238Y1558775I1J203D01*
G01Y1559395D01*
G03X160188Y1559527I-200J0D01*
G02Y1562443I1661J1458D01*
G03X160238Y1562575I-150J132D01*
G01Y1564513D01*
G03X160188Y1564645I-200J0D01*
G02Y1567561I1661J1458D01*
G03X160238Y1567693I-150J132D01*
G01Y1568313D01*
G02X160440Y1568516I202J1D01*
G37*
G36*
G01X281700D02*
X284520D01*
G02X284722Y1568313I-1J-203D01*
G01Y1567693D01*
G03X284772Y1567561I200J0D01*
G02Y1564645I-1661J-1458D01*
G03X284722Y1564513I150J-132D01*
G01Y1562575D01*
G03X284772Y1562443I200J0D01*
G02Y1559527I-1661J-1458D01*
G03X284722Y1559395I150J-132D01*
G01Y1558775D01*
G02X284520Y1558572I-202J-1D01*
G01X281700D01*
G02X281498Y1558775I1J203D01*
G01Y1559395D01*
G03X281448Y1559527I-200J0D01*
G02Y1562443I1661J1458D01*
G03X281498Y1562575I-150J132D01*
G01Y1564513D01*
G03X281448Y1564645I-200J0D01*
G02Y1567561I1661J1458D01*
G03X281498Y1567693I-150J132D01*
G01Y1568313D01*
G02X281700Y1568516I202J1D01*
G37*
G36*
G01X299023D02*
X301843D01*
G02X302046Y1568313I0J-203D01*
G01Y1567691D01*
G03X302096Y1567559I200J0D01*
G02Y1564647I-1664J-1456D01*
G03X302046Y1564515I150J-132D01*
G01Y1562573D01*
G03X302096Y1562441I200J0D01*
G02Y1559529I-1664J-1456D01*
G03X302046Y1559397I150J-132D01*
G01Y1558775D01*
G02X301843Y1558572I-203J0D01*
G01X299023D01*
G02X298820Y1558775I0J203D01*
G01Y1559397D01*
G03X298770Y1559529I-200J0D01*
G02Y1562441I1664J1456D01*
G03X298820Y1562573I-150J132D01*
G01Y1564515D01*
G03X298770Y1564647I-200J0D01*
G02Y1567559I1664J1456D01*
G03X298820Y1567691I-150J132D01*
G01Y1568313D01*
G02X299023Y1568516I203J0D01*
G37*
G36*
G01X316346D02*
X319166D01*
G02X319368Y1568313I-1J-203D01*
G01Y1567693D01*
G03X319418Y1567561I200J0D01*
G02Y1564645I-1661J-1458D01*
G03X319368Y1564513I150J-132D01*
G01Y1562575D01*
G03X319418Y1562443I200J0D01*
G02Y1559527I-1661J-1458D01*
G03X319368Y1559395I150J-132D01*
G01Y1558775D01*
G02X319166Y1558572I-202J-1D01*
G01X316346D01*
G02X316144Y1558775I1J203D01*
G01Y1559395D01*
G03X316094Y1559527I-200J0D01*
G02Y1562443I1661J1458D01*
G03X316144Y1562575I-150J132D01*
G01Y1564513D01*
G03X316094Y1564645I-200J0D01*
G02Y1567561I1661J1458D01*
G03X316144Y1567693I-150J132D01*
G01Y1568313D01*
G02X316346Y1568516I202J1D01*
G37*
G36*
G01X333668D02*
X336488D01*
G02X336690Y1568313I-1J-203D01*
G01Y1567693D01*
G03X336740Y1567561I200J0D01*
G02Y1564645I-1661J-1458D01*
G03X336690Y1564513I150J-132D01*
G01Y1562575D01*
G03X336740Y1562443I200J0D01*
G02Y1559527I-1661J-1458D01*
G03X336690Y1559395I150J-132D01*
G01Y1558775D01*
G02X336488Y1558572I-202J-1D01*
G01X333668D01*
G02X333466Y1558775I1J203D01*
G01Y1559395D01*
G03X333416Y1559527I-200J0D01*
G02Y1562443I1661J1458D01*
G03X333466Y1562575I-150J132D01*
G01Y1564513D01*
G03X333416Y1564645I-200J0D01*
G02Y1567561I1661J1458D01*
G03X333466Y1567693I-150J132D01*
G01Y1568313D01*
G02X333668Y1568516I202J1D01*
G37*
G36*
G01X628157D02*
X630977D01*
G02X631180Y1568313I0J-203D01*
G01Y1567691D01*
G03X631230Y1567559I200J0D01*
G02Y1564647I-1664J-1456D01*
G03X631180Y1564515I150J-132D01*
G01Y1562573D01*
G03X631230Y1562441I200J0D01*
G02Y1559529I-1664J-1456D01*
G03X631180Y1559397I150J-132D01*
G01Y1558775D01*
G02X630977Y1558572I-203J0D01*
G01X628157D01*
G02X627954Y1558775I0J203D01*
G01Y1559397D01*
G03X627904Y1559529I-200J0D01*
G02Y1562441I1664J1456D01*
G03X627954Y1562573I-150J132D01*
G01Y1564515D01*
G03X627904Y1564647I-200J0D01*
G02Y1567559I1664J1456D01*
G03X627954Y1567691I-150J132D01*
G01Y1568313D01*
G02X628157Y1568516I203J0D01*
G37*
G36*
G01X645480D02*
X648300D01*
G02X648502Y1568313I-1J-203D01*
G01Y1567693D01*
G03X648552Y1567561I200J0D01*
G02Y1564645I-1661J-1458D01*
G03X648502Y1564513I150J-132D01*
G01Y1562575D01*
G03X648552Y1562443I200J0D01*
G02Y1559527I-1661J-1458D01*
G03X648502Y1559395I150J-132D01*
G01Y1558775D01*
G02X648300Y1558572I-202J-1D01*
G01X645480D01*
G02X645278Y1558775I1J203D01*
G01Y1559395D01*
G03X645228Y1559527I-200J0D01*
G02Y1562443I1661J1458D01*
G03X645278Y1562575I-150J132D01*
G01Y1564513D01*
G03X645228Y1564645I-200J0D01*
G02Y1567561I1661J1458D01*
G03X645278Y1567693I-150J132D01*
G01Y1568313D01*
G02X645480Y1568516I202J1D01*
G37*
G36*
G01X662803D02*
X665623D01*
G02X665826Y1568313I0J-203D01*
G01Y1567691D01*
G03X665876Y1567559I200J0D01*
G02Y1564647I-1664J-1456D01*
G03X665826Y1564515I150J-132D01*
G01Y1562573D01*
G03X665876Y1562441I200J0D01*
G02Y1559529I-1664J-1456D01*
G03X665826Y1559397I150J-132D01*
G01Y1558775D01*
G02X665623Y1558572I-203J0D01*
G01X662803D01*
G02X662600Y1558775I0J203D01*
G01Y1559397D01*
G03X662550Y1559529I-200J0D01*
G02Y1562441I1664J1456D01*
G03X662600Y1562573I-150J132D01*
G01Y1564515D01*
G03X662550Y1564647I-200J0D01*
G02Y1567559I1664J1456D01*
G03X662600Y1567691I-150J132D01*
G01Y1568313D01*
G02X662803Y1568516I203J0D01*
G37*
G36*
G01X680125D02*
X682945D01*
G02X683148Y1568313I0J-203D01*
G01Y1567691D01*
G03X683198Y1567559I200J0D01*
G02Y1564647I-1664J-1456D01*
G03X683148Y1564515I150J-132D01*
G01Y1562573D01*
G03X683198Y1562441I200J0D01*
G02Y1559529I-1664J-1456D01*
G03X683148Y1559397I150J-132D01*
G01Y1558775D01*
G02X682945Y1558572I-203J0D01*
G01X680125D01*
G02X679922Y1558775I0J203D01*
G01Y1559397D01*
G03X679872Y1559529I-200J0D01*
G02Y1562441I1664J1456D01*
G03X679922Y1562573I-150J132D01*
G01Y1564515D01*
G03X679872Y1564647I-200J0D01*
G02Y1567559I1664J1456D01*
G03X679922Y1567691I-150J132D01*
G01Y1568313D01*
G02X680125Y1568516I203J0D01*
G37*
G36*
G01X1130440D02*
X1133260D01*
G02X1133462Y1568313I-1J-203D01*
G01Y1567693D01*
G03X1133512Y1567561I200J0D01*
G02Y1564645I-1661J-1458D01*
G03X1133462Y1564513I150J-132D01*
G01Y1562575D01*
G03X1133512Y1562443I200J0D01*
G02Y1559527I-1661J-1458D01*
G03X1133462Y1559395I150J-132D01*
G01Y1558775D01*
G02X1133260Y1558572I-202J-1D01*
G01X1130440D01*
G02X1130238Y1558775I1J203D01*
G01Y1559395D01*
G03X1130188Y1559527I-200J0D01*
G02Y1562443I1661J1458D01*
G03X1130238Y1562575I-150J132D01*
G01Y1564513D01*
G03X1130188Y1564645I-200J0D01*
G02Y1567561I1661J1458D01*
G03X1130238Y1567693I-150J132D01*
G01Y1568313D01*
G02X1130440Y1568516I202J1D01*
G37*
G36*
G01X1147763D02*
X1150583D01*
G02X1150786Y1568313I0J-203D01*
G01Y1567691D01*
G03X1150836Y1567559I200J0D01*
G02Y1564647I-1664J-1456D01*
G03X1150786Y1564515I150J-132D01*
G01Y1562573D01*
G03X1150836Y1562441I200J0D01*
G02Y1559529I-1664J-1456D01*
G03X1150786Y1559397I150J-132D01*
G01Y1558775D01*
G02X1150583Y1558572I-203J0D01*
G01X1147763D01*
G02X1147560Y1558775I0J203D01*
G01Y1559397D01*
G03X1147510Y1559529I-200J0D01*
G02Y1562441I1664J1456D01*
G03X1147560Y1562573I-150J132D01*
G01Y1564515D01*
G03X1147510Y1564647I-200J0D01*
G02Y1567559I1664J1456D01*
G03X1147560Y1567691I-150J132D01*
G01Y1568313D01*
G02X1147763Y1568516I203J0D01*
G37*
G36*
G01X1165086D02*
X1167906D01*
G02X1168108Y1568313I-1J-203D01*
G01Y1567693D01*
G03X1168158Y1567561I200J0D01*
G02Y1564645I-1661J-1458D01*
G03X1168108Y1564513I150J-132D01*
G01Y1562575D01*
G03X1168158Y1562443I200J0D01*
G02Y1559527I-1661J-1458D01*
G03X1168108Y1559395I150J-132D01*
G01Y1558775D01*
G02X1167906Y1558572I-202J-1D01*
G01X1165086D01*
G02X1164884Y1558775I1J203D01*
G01Y1559395D01*
G03X1164834Y1559527I-200J0D01*
G02Y1562443I1661J1458D01*
G03X1164884Y1562575I-150J132D01*
G01Y1564513D01*
G03X1164834Y1564645I-200J0D01*
G02Y1567561I1661J1458D01*
G03X1164884Y1567693I-150J132D01*
G01Y1568313D01*
G02X1165086Y1568516I202J1D01*
G37*
G36*
G01X1182408D02*
X1185228D01*
G02X1185430Y1568313I-1J-203D01*
G01Y1567693D01*
G03X1185480Y1567561I200J0D01*
G02Y1564645I-1661J-1458D01*
G03X1185430Y1564513I150J-132D01*
G01Y1562575D01*
G03X1185480Y1562443I200J0D01*
G02Y1559527I-1661J-1458D01*
G03X1185430Y1559395I150J-132D01*
G01Y1558775D01*
G02X1185228Y1558572I-202J-1D01*
G01X1182408D01*
G02X1182206Y1558775I1J203D01*
G01Y1559395D01*
G03X1182156Y1559527I-200J0D01*
G02Y1562443I1661J1458D01*
G03X1182206Y1562575I-150J132D01*
G01Y1564513D01*
G03X1182156Y1564645I-200J0D01*
G02Y1567561I1661J1458D01*
G03X1182206Y1567693I-150J132D01*
G01Y1568313D01*
G02X1182408Y1568516I202J1D01*
G37*
G36*
G01X1303669D02*
X1306489D01*
G02X1306692Y1568313I0J-203D01*
G01Y1567691D01*
G03X1306742Y1567559I200J0D01*
G02Y1564647I-1664J-1456D01*
G03X1306692Y1564515I150J-132D01*
G01Y1562573D01*
G03X1306742Y1562441I200J0D01*
G02Y1559529I-1664J-1456D01*
G03X1306692Y1559397I150J-132D01*
G01Y1558775D01*
G02X1306489Y1558572I-203J0D01*
G01X1303669D01*
G02X1303466Y1558775I0J203D01*
G01Y1559397D01*
G03X1303416Y1559529I-200J0D01*
G02Y1562441I1664J1456D01*
G03X1303466Y1562573I-150J132D01*
G01Y1564515D01*
G03X1303416Y1564647I-200J0D01*
G02Y1567559I1664J1456D01*
G03X1303466Y1567691I-150J132D01*
G01Y1568313D01*
G02X1303669Y1568516I203J0D01*
G37*
G36*
G01X1320992D02*
X1323812D01*
G02X1324014Y1568313I-1J-203D01*
G01Y1567693D01*
G03X1324064Y1567561I200J0D01*
G02Y1564645I-1661J-1458D01*
G03X1324014Y1564513I150J-132D01*
G01Y1562575D01*
G03X1324064Y1562443I200J0D01*
G02Y1559527I-1661J-1458D01*
G03X1324014Y1559395I150J-132D01*
G01Y1558775D01*
G02X1323812Y1558572I-202J-1D01*
G01X1320992D01*
G02X1320790Y1558775I1J203D01*
G01Y1559395D01*
G03X1320740Y1559527I-200J0D01*
G02Y1562443I1661J1458D01*
G03X1320790Y1562575I-150J132D01*
G01Y1564513D01*
G03X1320740Y1564645I-200J0D01*
G02Y1567561I1661J1458D01*
G03X1320790Y1567693I-150J132D01*
G01Y1568313D01*
G02X1320992Y1568516I202J1D01*
G37*
G36*
G01X1338315D02*
X1341135D01*
G02X1341338Y1568313I0J-203D01*
G01Y1567691D01*
G03X1341388Y1567559I200J0D01*
G02Y1564647I-1664J-1456D01*
G03X1341338Y1564515I150J-132D01*
G01Y1562573D01*
G03X1341388Y1562441I200J0D01*
G02Y1559529I-1664J-1456D01*
G03X1341338Y1559397I150J-132D01*
G01Y1558775D01*
G02X1341135Y1558572I-203J0D01*
G01X1338315D01*
G02X1338112Y1558775I0J203D01*
G01Y1559397D01*
G03X1338062Y1559529I-200J0D01*
G02Y1562441I1664J1456D01*
G03X1338112Y1562573I-150J132D01*
G01Y1564515D01*
G03X1338062Y1564647I-200J0D01*
G02Y1567559I1664J1456D01*
G03X1338112Y1567691I-150J132D01*
G01Y1568313D01*
G02X1338315Y1568516I203J0D01*
G37*
G36*
G01X1355637D02*
X1358457D01*
G02X1358660Y1568313I0J-203D01*
G01Y1567691D01*
G03X1358710Y1567559I200J0D01*
G02Y1564647I-1664J-1456D01*
G03X1358660Y1564515I150J-132D01*
G01Y1562573D01*
G03X1358710Y1562441I200J0D01*
G02Y1559529I-1664J-1456D01*
G03X1358660Y1559397I150J-132D01*
G01Y1558775D01*
G02X1358457Y1558572I-203J0D01*
G01X1355637D01*
G02X1355434Y1558775I0J203D01*
G01Y1559397D01*
G03X1355384Y1559529I-200J0D01*
G02Y1562441I1664J1456D01*
G03X1355434Y1562573I-150J132D01*
G01Y1564515D01*
G03X1355384Y1564647I-200J0D01*
G02Y1567559I1664J1456D01*
G03X1355434Y1567691I-150J132D01*
G01Y1568313D01*
G02X1355637Y1568516I203J0D01*
G37*
G36*
G01X1476897D02*
X1479717D01*
G02X1479920Y1568313I0J-203D01*
G01Y1567691D01*
G03X1479970Y1567559I200J0D01*
G02Y1564647I-1664J-1456D01*
G03X1479920Y1564515I150J-132D01*
G01Y1562573D01*
G03X1479970Y1562441I200J0D01*
G02Y1559529I-1664J-1456D01*
G03X1479920Y1559397I150J-132D01*
G01Y1558775D01*
G02X1479717Y1558572I-203J0D01*
G01X1476897D01*
G02X1476694Y1558775I0J203D01*
G01Y1559397D01*
G03X1476644Y1559529I-200J0D01*
G02Y1562441I1664J1456D01*
G03X1476694Y1562573I-150J132D01*
G01Y1564515D01*
G03X1476644Y1564647I-200J0D01*
G02Y1567559I1664J1456D01*
G03X1476694Y1567691I-150J132D01*
G01Y1568313D01*
G02X1476897Y1568516I203J0D01*
G37*
G36*
G01X1650125D02*
X1652945D01*
G02X1653148Y1568313I0J-203D01*
G01Y1567691D01*
G03X1653198Y1567559I200J0D01*
G02Y1564647I-1664J-1456D01*
G03X1653148Y1564515I150J-132D01*
G01Y1562573D01*
G03X1653198Y1562441I200J0D01*
G02Y1559529I-1664J-1456D01*
G03X1653148Y1559397I150J-132D01*
G01Y1558775D01*
G02X1652945Y1558572I-203J0D01*
G01X1650125D01*
G02X1649922Y1558775I0J203D01*
G01Y1559397D01*
G03X1649872Y1559529I-200J0D01*
G02Y1562441I1664J1456D01*
G03X1649922Y1562573I-150J132D01*
G01Y1564515D01*
G03X1649872Y1564647I-200J0D01*
G02Y1567559I1664J1456D01*
G03X1649922Y1567691I-150J132D01*
G01Y1568313D01*
G02X1650125Y1568516I203J0D01*
G37*
G36*
G01X1667448D02*
X1670268D01*
G02X1670470Y1568313I-1J-203D01*
G01Y1567693D01*
G03X1670520Y1567561I200J0D01*
G02Y1564645I-1661J-1458D01*
G03X1670470Y1564513I150J-132D01*
G01Y1562575D01*
G03X1670520Y1562443I200J0D01*
G02Y1559527I-1661J-1458D01*
G03X1670470Y1559395I150J-132D01*
G01Y1558775D01*
G02X1670268Y1558572I-202J-1D01*
G01X1667448D01*
G02X1667246Y1558775I1J203D01*
G01Y1559395D01*
G03X1667196Y1559527I-200J0D01*
G02Y1562443I1661J1458D01*
G03X1667246Y1562575I-150J132D01*
G01Y1564513D01*
G03X1667196Y1564645I-200J0D01*
G02Y1567561I1661J1458D01*
G03X1667246Y1567693I-150J132D01*
G01Y1568313D01*
G02X1667448Y1568516I202J1D01*
G37*
G36*
G01X1684771D02*
X1687591D01*
G02X1687794Y1568313I0J-203D01*
G01Y1567691D01*
G03X1687844Y1567559I200J0D01*
G02Y1564647I-1664J-1456D01*
G03X1687794Y1564515I150J-132D01*
G01Y1562573D01*
G03X1687844Y1562441I200J0D01*
G02Y1559529I-1664J-1456D01*
G03X1687794Y1559397I150J-132D01*
G01Y1558775D01*
G02X1687591Y1558572I-203J0D01*
G01X1684771D01*
G02X1684568Y1558775I0J203D01*
G01Y1559397D01*
G03X1684518Y1559529I-200J0D01*
G02Y1562441I1664J1456D01*
G03X1684568Y1562573I-150J132D01*
G01Y1564515D01*
G03X1684518Y1564647I-200J0D01*
G02Y1567559I1664J1456D01*
G03X1684568Y1567691I-150J132D01*
G01Y1568313D01*
G02X1684771Y1568516I203J0D01*
G37*
G36*
G01X1702093D02*
X1704913D01*
G02X1705116Y1568313I0J-203D01*
G01Y1567691D01*
G03X1705166Y1567559I200J0D01*
G02Y1564647I-1664J-1456D01*
G03X1705116Y1564515I150J-132D01*
G01Y1562573D01*
G03X1705166Y1562441I200J0D01*
G02Y1559529I-1664J-1456D01*
G03X1705116Y1559397I150J-132D01*
G01Y1558775D01*
G02X1704913Y1558572I-203J0D01*
G01X1702093D01*
G02X1701890Y1558775I0J203D01*
G01Y1559397D01*
G03X1701840Y1559529I-200J0D01*
G02Y1562441I1664J1456D01*
G03X1701890Y1562573I-150J132D01*
G01Y1564515D01*
G03X1701840Y1564647I-200J0D01*
G02Y1567559I1664J1456D01*
G03X1701890Y1567691I-150J132D01*
G01Y1568313D01*
G02X1702093Y1568516I203J0D01*
G37*
G36*
G01X134456Y1572846D02*
X137276D01*
G02X137478Y1572644I0J-202D01*
G01Y1572024D01*
G03X137528Y1571892I200J0D01*
G02Y1568976I-1661J-1458D01*
G03X137478Y1568844I150J-132D01*
G01Y1566905D01*
G03X137528Y1566773I200J0D01*
G02Y1563857I-1661J-1458D01*
G03X137478Y1563725I150J-132D01*
G01Y1563106D01*
G02X137276Y1562904I-202J0D01*
G01X134456D01*
G02X134254Y1563106I0J202D01*
G01Y1563725D01*
G03X134204Y1563857I-200J0D01*
G02Y1566773I1661J1458D01*
G03X134254Y1566905I-150J132D01*
G01Y1568844D01*
G03X134204Y1568976I-200J0D01*
G02Y1571892I1661J1458D01*
G03X134254Y1572024I-150J132D01*
G01Y1572644D01*
G02X134456Y1572846I202J0D01*
G37*
G36*
G01X169102D02*
X171922D01*
G02X172124Y1572644I0J-202D01*
G01Y1572024D01*
G03X172174Y1571892I200J0D01*
G02Y1568976I-1661J-1458D01*
G03X172124Y1568844I150J-132D01*
G01Y1566905D01*
G03X172174Y1566773I200J0D01*
G02Y1563857I-1661J-1458D01*
G03X172124Y1563725I150J-132D01*
G01Y1563106D01*
G02X171922Y1562904I-202J0D01*
G01X169102D01*
G02X168900Y1563106I0J202D01*
G01Y1563725D01*
G03X168850Y1563857I-200J0D01*
G02Y1566773I1661J1458D01*
G03X168900Y1566905I-150J132D01*
G01Y1568844D01*
G03X168850Y1568976I-200J0D01*
G02Y1571892I1661J1458D01*
G03X168900Y1572024I-150J132D01*
G01Y1572644D01*
G02X169102Y1572846I202J0D01*
G37*
G36*
G01X307684D02*
X310504D01*
G02X310706Y1572644I0J-202D01*
G01Y1572024D01*
G03X310756Y1571892I200J0D01*
G02Y1568976I-1661J-1458D01*
G03X310706Y1568844I150J-132D01*
G01Y1566905D01*
G03X310756Y1566773I200J0D01*
G02Y1563857I-1661J-1458D01*
G03X310706Y1563725I150J-132D01*
G01Y1563106D01*
G02X310504Y1562904I-202J0D01*
G01X307684D01*
G02X307482Y1563106I0J202D01*
G01Y1563725D01*
G03X307432Y1563857I-200J0D01*
G02Y1566773I1661J1458D01*
G03X307482Y1566905I-150J132D01*
G01Y1568844D01*
G03X307432Y1568976I-200J0D01*
G02Y1571892I1661J1458D01*
G03X307482Y1572024I-150J132D01*
G01Y1572644D01*
G02X307684Y1572846I202J0D01*
G37*
G36*
G01X342330D02*
X345150D01*
G02X345352Y1572644I0J-202D01*
G01Y1572024D01*
G03X345402Y1571892I200J0D01*
G02Y1568976I-1661J-1458D01*
G03X345352Y1568844I150J-132D01*
G01Y1566905D01*
G03X345402Y1566773I200J0D01*
G02Y1563857I-1661J-1458D01*
G03X345352Y1563725I150J-132D01*
G01Y1563106D01*
G02X345150Y1562904I-202J0D01*
G01X342330D01*
G02X342128Y1563106I0J202D01*
G01Y1563725D01*
G03X342078Y1563857I-200J0D01*
G02Y1566773I1661J1458D01*
G03X342128Y1566905I-150J132D01*
G01Y1568844D01*
G03X342078Y1568976I-200J0D01*
G02Y1571892I1661J1458D01*
G03X342128Y1572024I-150J132D01*
G01Y1572644D01*
G02X342330Y1572846I202J0D01*
G37*
G36*
G01X636818D02*
X639638D01*
G02X639840Y1572644I0J-202D01*
G01Y1572024D01*
G03X639890Y1571892I200J0D01*
G02Y1568976I-1661J-1458D01*
G03X639840Y1568844I150J-132D01*
G01Y1566905D01*
G03X639890Y1566773I200J0D01*
G02Y1563857I-1661J-1458D01*
G03X639840Y1563725I150J-132D01*
G01Y1563106D01*
G02X639638Y1562904I-202J0D01*
G01X636818D01*
G02X636616Y1563106I0J202D01*
G01Y1563725D01*
G03X636566Y1563857I-200J0D01*
G02Y1566773I1661J1458D01*
G03X636616Y1566905I-150J132D01*
G01Y1568844D01*
G03X636566Y1568976I-200J0D01*
G02Y1571892I1661J1458D01*
G03X636616Y1572024I-150J132D01*
G01Y1572644D01*
G02X636818Y1572846I202J0D01*
G37*
G36*
G01X671464D02*
X674284D01*
G02X674486Y1572644I0J-202D01*
G01Y1572024D01*
G03X674536Y1571892I200J0D01*
G02Y1568976I-1661J-1458D01*
G03X674486Y1568844I150J-132D01*
G01Y1566905D01*
G03X674536Y1566773I200J0D01*
G02Y1563857I-1661J-1458D01*
G03X674486Y1563725I150J-132D01*
G01Y1563106D01*
G02X674284Y1562904I-202J0D01*
G01X671464D01*
G02X671262Y1563106I0J202D01*
G01Y1563725D01*
G03X671212Y1563857I-200J0D01*
G02Y1566773I1661J1458D01*
G03X671262Y1566905I-150J132D01*
G01Y1568844D01*
G03X671212Y1568976I-200J0D01*
G02Y1571892I1661J1458D01*
G03X671262Y1572024I-150J132D01*
G01Y1572644D01*
G02X671464Y1572846I202J0D01*
G37*
G36*
G01X1156424D02*
X1159244D01*
G02X1159446Y1572644I0J-202D01*
G01Y1572024D01*
G03X1159496Y1571892I200J0D01*
G02Y1568976I-1661J-1458D01*
G03X1159446Y1568844I150J-132D01*
G01Y1566905D01*
G03X1159496Y1566773I200J0D01*
G02Y1563857I-1661J-1458D01*
G03X1159446Y1563725I150J-132D01*
G01Y1563106D01*
G02X1159244Y1562904I-202J0D01*
G01X1156424D01*
G02X1156222Y1563106I0J202D01*
G01Y1563725D01*
G03X1156172Y1563857I-200J0D01*
G02Y1566773I1661J1458D01*
G03X1156222Y1566905I-150J132D01*
G01Y1568844D01*
G03X1156172Y1568976I-200J0D01*
G02Y1571892I1661J1458D01*
G03X1156222Y1572024I-150J132D01*
G01Y1572644D01*
G02X1156424Y1572846I202J0D01*
G37*
G36*
G01X1191070D02*
X1193890D01*
G02X1194092Y1572644I0J-202D01*
G01Y1572024D01*
G03X1194142Y1571892I200J0D01*
G02Y1568976I-1661J-1458D01*
G03X1194092Y1568844I150J-132D01*
G01Y1566905D01*
G03X1194142Y1566773I200J0D01*
G02Y1563857I-1661J-1458D01*
G03X1194092Y1563725I150J-132D01*
G01Y1563106D01*
G02X1193890Y1562904I-202J0D01*
G01X1191070D01*
G02X1190868Y1563106I0J202D01*
G01Y1563725D01*
G03X1190818Y1563857I-200J0D01*
G02Y1566773I1661J1458D01*
G03X1190868Y1566905I-150J132D01*
G01Y1568844D01*
G03X1190818Y1568976I-200J0D01*
G02Y1571892I1661J1458D01*
G03X1190868Y1572024I-150J132D01*
G01Y1572644D01*
G02X1191070Y1572846I202J0D01*
G37*
G36*
G01X1312330D02*
X1315150D01*
G02X1315352Y1572644I0J-202D01*
G01Y1572024D01*
G03X1315402Y1571892I200J0D01*
G02Y1568976I-1661J-1458D01*
G03X1315352Y1568844I150J-132D01*
G01Y1566905D01*
G03X1315402Y1566773I200J0D01*
G02Y1563857I-1661J-1458D01*
G03X1315352Y1563725I150J-132D01*
G01Y1563106D01*
G02X1315150Y1562904I-202J0D01*
G01X1312330D01*
G02X1312128Y1563106I0J202D01*
G01Y1563725D01*
G03X1312078Y1563857I-200J0D01*
G02Y1566773I1661J1458D01*
G03X1312128Y1566905I-150J132D01*
G01Y1568844D01*
G03X1312078Y1568976I-200J0D01*
G02Y1571892I1661J1458D01*
G03X1312128Y1572024I-150J132D01*
G01Y1572644D01*
G02X1312330Y1572846I202J0D01*
G37*
G36*
G01X1346976D02*
X1349796D01*
G02X1349998Y1572644I0J-202D01*
G01Y1572024D01*
G03X1350048Y1571892I200J0D01*
G02Y1568976I-1661J-1458D01*
G03X1349998Y1568844I150J-132D01*
G01Y1566905D01*
G03X1350048Y1566773I200J0D01*
G02Y1563857I-1661J-1458D01*
G03X1349998Y1563725I150J-132D01*
G01Y1563106D01*
G02X1349796Y1562904I-202J0D01*
G01X1346976D01*
G02X1346774Y1563106I0J202D01*
G01Y1563725D01*
G03X1346724Y1563857I-200J0D01*
G02Y1566773I1661J1458D01*
G03X1346774Y1566905I-150J132D01*
G01Y1568844D01*
G03X1346724Y1568976I-200J0D01*
G02Y1571892I1661J1458D01*
G03X1346774Y1572024I-150J132D01*
G01Y1572644D01*
G02X1346976Y1572846I202J0D01*
G37*
G36*
G01X1658786D02*
X1661606D01*
G02X1661808Y1572644I0J-202D01*
G01Y1572024D01*
G03X1661858Y1571892I200J0D01*
G02Y1568976I-1661J-1458D01*
G03X1661808Y1568844I150J-132D01*
G01Y1566905D01*
G03X1661858Y1566773I200J0D01*
G02Y1563857I-1661J-1458D01*
G03X1661808Y1563725I150J-132D01*
G01Y1563106D01*
G02X1661606Y1562904I-202J0D01*
G01X1658786D01*
G02X1658584Y1563106I0J202D01*
G01Y1563725D01*
G03X1658534Y1563857I-200J0D01*
G02Y1566773I1661J1458D01*
G03X1658584Y1566905I-150J132D01*
G01Y1568844D01*
G03X1658534Y1568976I-200J0D01*
G02Y1571892I1661J1458D01*
G03X1658584Y1572024I-150J132D01*
G01Y1572644D01*
G02X1658786Y1572846I202J0D01*
G37*
G36*
G01X1693432D02*
X1696252D01*
G02X1696454Y1572644I0J-202D01*
G01Y1572024D01*
G03X1696504Y1571892I200J0D01*
G02Y1568976I-1661J-1458D01*
G03X1696454Y1568844I150J-132D01*
G01Y1566905D01*
G03X1696504Y1566773I200J0D01*
G02Y1563857I-1661J-1458D01*
G03X1696454Y1563725I150J-132D01*
G01Y1563106D01*
G02X1696252Y1562904I-202J0D01*
G01X1693432D01*
G02X1693230Y1563106I0J202D01*
G01Y1563725D01*
G03X1693180Y1563857I-200J0D01*
G02Y1566773I1661J1458D01*
G03X1693230Y1566905I-150J132D01*
G01Y1568844D01*
G03X1693180Y1568976I-200J0D01*
G02Y1571892I1661J1458D01*
G03X1693230Y1572024I-150J132D01*
G01Y1572644D01*
G02X1693432Y1572846I202J0D01*
G37*
G36*
G01X117133D02*
X119953D01*
G02X120156Y1572644I1J-202D01*
G01Y1572022D01*
G03X120206Y1571890I200J0D01*
G02Y1568978I-1664J-1456D01*
G03X120156Y1568846I150J-132D01*
G01Y1566903D01*
G03X120206Y1566771I200J0D01*
G02Y1563859I-1664J-1456D01*
G03X120156Y1563727I150J-132D01*
G01Y1563106D01*
G02X119953Y1562904I-203J1D01*
G01X117133D01*
G02X116930Y1563106I-1J202D01*
G01Y1563727D01*
G03X116880Y1563859I-200J0D01*
G02Y1566771I1664J1456D01*
G03X116930Y1566903I-150J132D01*
G01Y1568846D01*
G03X116880Y1568978I-200J0D01*
G02Y1571890I1664J1456D01*
G03X116930Y1572022I-150J132D01*
G01Y1572644D01*
G02X117133Y1572846I203J-1D01*
G37*
G36*
G01X151779D02*
X154599D01*
G02X154802Y1572644I1J-202D01*
G01Y1572022D01*
G03X154852Y1571890I200J0D01*
G02Y1568978I-1664J-1456D01*
G03X154802Y1568846I150J-132D01*
G01Y1566903D01*
G03X154852Y1566771I200J0D01*
G02Y1563859I-1664J-1456D01*
G03X154802Y1563727I150J-132D01*
G01Y1563106D01*
G02X154599Y1562904I-203J1D01*
G01X151779D01*
G02X151576Y1563106I-1J202D01*
G01Y1563727D01*
G03X151526Y1563859I-200J0D01*
G02Y1566771I1664J1456D01*
G03X151576Y1566903I-150J132D01*
G01Y1568846D01*
G03X151526Y1568978I-200J0D01*
G02Y1571890I1664J1456D01*
G03X151576Y1572022I-150J132D01*
G01Y1572644D01*
G02X151779Y1572846I203J-1D01*
G37*
G36*
G01X290361D02*
X293181D01*
G02X293384Y1572644I1J-202D01*
G01Y1572022D01*
G03X293434Y1571890I200J0D01*
G02Y1568978I-1664J-1456D01*
G03X293384Y1568846I150J-132D01*
G01Y1566903D01*
G03X293434Y1566771I200J0D01*
G02Y1563859I-1664J-1456D01*
G03X293384Y1563727I150J-132D01*
G01Y1563106D01*
G02X293181Y1562904I-203J1D01*
G01X290361D01*
G02X290158Y1563106I-1J202D01*
G01Y1563727D01*
G03X290108Y1563859I-200J0D01*
G02Y1566771I1664J1456D01*
G03X290158Y1566903I-150J132D01*
G01Y1568846D01*
G03X290108Y1568978I-200J0D01*
G02Y1571890I1664J1456D01*
G03X290158Y1572022I-150J132D01*
G01Y1572644D01*
G02X290361Y1572846I203J-1D01*
G37*
G36*
G01X325007D02*
X327827D01*
G02X328030Y1572644I1J-202D01*
G01Y1572022D01*
G03X328080Y1571890I200J0D01*
G02Y1568978I-1664J-1456D01*
G03X328030Y1568846I150J-132D01*
G01Y1566903D01*
G03X328080Y1566771I200J0D01*
G02Y1563859I-1664J-1456D01*
G03X328030Y1563727I150J-132D01*
G01Y1563106D01*
G02X327827Y1562904I-203J1D01*
G01X325007D01*
G02X324804Y1563106I-1J202D01*
G01Y1563727D01*
G03X324754Y1563859I-200J0D01*
G02Y1566771I1664J1456D01*
G03X324804Y1566903I-150J132D01*
G01Y1568846D01*
G03X324754Y1568978I-200J0D01*
G02Y1571890I1664J1456D01*
G03X324804Y1572022I-150J132D01*
G01Y1572644D01*
G02X325007Y1572846I203J-1D01*
G37*
G36*
G01X515559D02*
X518379D01*
G02X518582Y1572644I1J-202D01*
G01Y1572022D01*
G03X518632Y1571890I200J0D01*
G02Y1568978I-1664J-1456D01*
G03X518582Y1568846I150J-132D01*
G01Y1566903D01*
G03X518632Y1566771I200J0D01*
G02Y1563859I-1664J-1456D01*
G03X518582Y1563727I150J-132D01*
G01Y1563106D01*
G02X518379Y1562904I-203J1D01*
G01X515559D01*
G02X515356Y1563106I-1J202D01*
G01Y1563727D01*
G03X515306Y1563859I-200J0D01*
G02Y1566771I1664J1456D01*
G03X515356Y1566903I-150J132D01*
G01Y1568846D01*
G03X515306Y1568978I-200J0D01*
G02Y1571890I1664J1456D01*
G03X515356Y1572022I-150J132D01*
G01Y1572644D01*
G02X515559Y1572846I203J-1D01*
G37*
G36*
G01X654141D02*
X656961D01*
G02X657164Y1572644I1J-202D01*
G01Y1572022D01*
G03X657214Y1571890I200J0D01*
G02Y1568978I-1664J-1456D01*
G03X657164Y1568846I150J-132D01*
G01Y1566903D01*
G03X657214Y1566771I200J0D01*
G02Y1563859I-1664J-1456D01*
G03X657164Y1563727I150J-132D01*
G01Y1563106D01*
G02X656961Y1562904I-203J1D01*
G01X654141D01*
G02X653938Y1563106I-1J202D01*
G01Y1563727D01*
G03X653888Y1563859I-200J0D01*
G02Y1566771I1664J1456D01*
G03X653938Y1566903I-150J132D01*
G01Y1568846D01*
G03X653888Y1568978I-200J0D01*
G02Y1571890I1664J1456D01*
G03X653938Y1572022I-150J132D01*
G01Y1572644D01*
G02X654141Y1572846I203J-1D01*
G37*
G36*
G01X688787D02*
X691607D01*
G02X691810Y1572644I1J-202D01*
G01Y1572022D01*
G03X691860Y1571890I200J0D01*
G02Y1568978I-1664J-1456D01*
G03X691810Y1568846I150J-132D01*
G01Y1566903D01*
G03X691860Y1566771I200J0D01*
G02Y1563859I-1664J-1456D01*
G03X691810Y1563727I150J-132D01*
G01Y1563106D01*
G02X691607Y1562904I-203J1D01*
G01X688787D01*
G02X688584Y1563106I-1J202D01*
G01Y1563727D01*
G03X688534Y1563859I-200J0D01*
G02Y1566771I1664J1456D01*
G03X688584Y1566903I-150J132D01*
G01Y1568846D01*
G03X688534Y1568978I-200J0D01*
G02Y1571890I1664J1456D01*
G03X688584Y1572022I-150J132D01*
G01Y1572644D01*
G02X688787Y1572846I203J-1D01*
G37*
G36*
G01X1139101D02*
X1141921D01*
G02X1142124Y1572644I1J-202D01*
G01Y1572022D01*
G03X1142174Y1571890I200J0D01*
G02Y1568978I-1664J-1456D01*
G03X1142124Y1568846I150J-132D01*
G01Y1566903D01*
G03X1142174Y1566771I200J0D01*
G02Y1563859I-1664J-1456D01*
G03X1142124Y1563727I150J-132D01*
G01Y1563106D01*
G02X1141921Y1562904I-203J1D01*
G01X1139101D01*
G02X1138898Y1563106I-1J202D01*
G01Y1563727D01*
G03X1138848Y1563859I-200J0D01*
G02Y1566771I1664J1456D01*
G03X1138898Y1566903I-150J132D01*
G01Y1568846D01*
G03X1138848Y1568978I-200J0D01*
G02Y1571890I1664J1456D01*
G03X1138898Y1572022I-150J132D01*
G01Y1572644D01*
G02X1139101Y1572846I203J-1D01*
G37*
G36*
G01X1173747D02*
X1176567D01*
G02X1176770Y1572644I1J-202D01*
G01Y1572022D01*
G03X1176820Y1571890I200J0D01*
G02Y1568978I-1664J-1456D01*
G03X1176770Y1568846I150J-132D01*
G01Y1566903D01*
G03X1176820Y1566771I200J0D01*
G02Y1563859I-1664J-1456D01*
G03X1176770Y1563727I150J-132D01*
G01Y1563106D01*
G02X1176567Y1562904I-203J1D01*
G01X1173747D01*
G02X1173544Y1563106I-1J202D01*
G01Y1563727D01*
G03X1173494Y1563859I-200J0D01*
G02Y1566771I1664J1456D01*
G03X1173544Y1566903I-150J132D01*
G01Y1568846D01*
G03X1173494Y1568978I-200J0D01*
G02Y1571890I1664J1456D01*
G03X1173544Y1572022I-150J132D01*
G01Y1572644D01*
G02X1173747Y1572846I203J-1D01*
G37*
G36*
G01X1329653D02*
X1332473D01*
G02X1332676Y1572644I1J-202D01*
G01Y1572022D01*
G03X1332726Y1571890I200J0D01*
G02Y1568978I-1664J-1456D01*
G03X1332676Y1568846I150J-132D01*
G01Y1566903D01*
G03X1332726Y1566771I200J0D01*
G02Y1563859I-1664J-1456D01*
G03X1332676Y1563727I150J-132D01*
G01Y1563106D01*
G02X1332473Y1562904I-203J1D01*
G01X1329653D01*
G02X1329450Y1563106I-1J202D01*
G01Y1563727D01*
G03X1329400Y1563859I-200J0D01*
G02Y1566771I1664J1456D01*
G03X1329450Y1566903I-150J132D01*
G01Y1568846D01*
G03X1329400Y1568978I-200J0D01*
G02Y1571890I1664J1456D01*
G03X1329450Y1572022I-150J132D01*
G01Y1572644D01*
G02X1329653Y1572846I203J-1D01*
G37*
G36*
G01X1364299D02*
X1367119D01*
G02X1367322Y1572644I1J-202D01*
G01Y1572022D01*
G03X1367372Y1571890I200J0D01*
G02Y1568978I-1664J-1456D01*
G03X1367322Y1568846I150J-132D01*
G01Y1566903D01*
G03X1367372Y1566771I200J0D01*
G02Y1563859I-1664J-1456D01*
G03X1367322Y1563727I150J-132D01*
G01Y1563106D01*
G02X1367119Y1562904I-203J1D01*
G01X1364299D01*
G02X1364096Y1563106I-1J202D01*
G01Y1563727D01*
G03X1364046Y1563859I-200J0D01*
G02Y1566771I1664J1456D01*
G03X1364096Y1566903I-150J132D01*
G01Y1568846D01*
G03X1364046Y1568978I-200J0D01*
G02Y1571890I1664J1456D01*
G03X1364096Y1572022I-150J132D01*
G01Y1572644D01*
G02X1364299Y1572846I203J-1D01*
G37*
G36*
G01X1676109D02*
X1678929D01*
G02X1679132Y1572644I1J-202D01*
G01Y1572022D01*
G03X1679182Y1571890I200J0D01*
G02Y1568978I-1664J-1456D01*
G03X1679132Y1568846I150J-132D01*
G01Y1566903D01*
G03X1679182Y1566771I200J0D01*
G02Y1563859I-1664J-1456D01*
G03X1679132Y1563727I150J-132D01*
G01Y1563106D01*
G02X1678929Y1562904I-203J1D01*
G01X1676109D01*
G02X1675906Y1563106I-1J202D01*
G01Y1563727D01*
G03X1675856Y1563859I-200J0D01*
G02Y1566771I1664J1456D01*
G03X1675906Y1566903I-150J132D01*
G01Y1568846D01*
G03X1675856Y1568978I-200J0D01*
G02Y1571890I1664J1456D01*
G03X1675906Y1572022I-150J132D01*
G01Y1572644D01*
G02X1676109Y1572846I203J-1D01*
G37*
G36*
G01X1710755D02*
X1713575D01*
G02X1713778Y1572644I1J-202D01*
G01Y1572022D01*
G03X1713828Y1571890I200J0D01*
G02Y1568978I-1664J-1456D01*
G03X1713778Y1568846I150J-132D01*
G01Y1566903D01*
G03X1713828Y1566771I200J0D01*
G02Y1563859I-1664J-1456D01*
G03X1713778Y1563727I150J-132D01*
G01Y1563106D01*
G02X1713575Y1562904I-203J1D01*
G01X1710755D01*
G02X1710552Y1563106I-1J202D01*
G01Y1563727D01*
G03X1710502Y1563859I-200J0D01*
G02Y1566771I1664J1456D01*
G03X1710552Y1566903I-150J132D01*
G01Y1568846D01*
G03X1710502Y1568978I-200J0D01*
G02Y1571890I1664J1456D01*
G03X1710552Y1572022I-150J132D01*
G01Y1572644D01*
G02X1710755Y1572846I203J-1D01*
G37*
G36*
G01X108472Y1583870D02*
X111292D01*
G02X111494Y1583667I-1J-203D01*
G01Y1583047D01*
G03X111544Y1582915I200J0D01*
G02Y1579999I-1661J-1458D01*
G03X111494Y1579867I150J-132D01*
G01Y1577929D01*
G03X111544Y1577797I200J0D01*
G02Y1574881I-1661J-1458D01*
G03X111494Y1574749I150J-132D01*
G01Y1574129D01*
G02X111292Y1573926I-202J-1D01*
G01X108472D01*
G02X108270Y1574129I1J203D01*
G01Y1574749D01*
G03X108220Y1574881I-200J0D01*
G02Y1577797I1661J1458D01*
G03X108270Y1577929I-150J132D01*
G01Y1579867D01*
G03X108220Y1579999I-200J0D01*
G02Y1582915I1661J1458D01*
G03X108270Y1583047I-150J132D01*
G01Y1583667D01*
G02X108472Y1583870I202J1D01*
G37*
G36*
G01X125795D02*
X128615D01*
G02X128818Y1583667I0J-203D01*
G01Y1583045D01*
G03X128868Y1582913I200J0D01*
G02Y1580001I-1664J-1456D01*
G03X128818Y1579869I150J-132D01*
G01Y1577927D01*
G03X128868Y1577795I200J0D01*
G02Y1574883I-1664J-1456D01*
G03X128818Y1574751I150J-132D01*
G01Y1574129D01*
G02X128615Y1573926I-203J0D01*
G01X125795D01*
G02X125592Y1574129I0J203D01*
G01Y1574751D01*
G03X125542Y1574883I-200J0D01*
G02Y1577795I1664J1456D01*
G03X125592Y1577927I-150J132D01*
G01Y1579869D01*
G03X125542Y1580001I-200J0D01*
G02Y1582913I1664J1456D01*
G03X125592Y1583045I-150J132D01*
G01Y1583667D01*
G02X125795Y1583870I203J0D01*
G37*
G36*
G01X143118D02*
X145938D01*
G02X146140Y1583667I-1J-203D01*
G01Y1583047D01*
G03X146190Y1582915I200J0D01*
G02Y1579999I-1661J-1458D01*
G03X146140Y1579867I150J-132D01*
G01Y1577929D01*
G03X146190Y1577797I200J0D01*
G02Y1574881I-1661J-1458D01*
G03X146140Y1574749I150J-132D01*
G01Y1574129D01*
G02X145938Y1573926I-202J-1D01*
G01X143118D01*
G02X142916Y1574129I1J203D01*
G01Y1574749D01*
G03X142866Y1574881I-200J0D01*
G02Y1577797I1661J1458D01*
G03X142916Y1577929I-150J132D01*
G01Y1579867D01*
G03X142866Y1579999I-200J0D01*
G02Y1582915I1661J1458D01*
G03X142916Y1583047I-150J132D01*
G01Y1583667D01*
G02X143118Y1583870I202J1D01*
G37*
G36*
G01X160440D02*
X163260D01*
G02X163462Y1583667I-1J-203D01*
G01Y1583047D01*
G03X163512Y1582915I200J0D01*
G02Y1579999I-1661J-1458D01*
G03X163462Y1579867I150J-132D01*
G01Y1577929D01*
G03X163512Y1577797I200J0D01*
G02Y1574881I-1661J-1458D01*
G03X163462Y1574749I150J-132D01*
G01Y1574129D01*
G02X163260Y1573926I-202J-1D01*
G01X160440D01*
G02X160238Y1574129I1J203D01*
G01Y1574749D01*
G03X160188Y1574881I-200J0D01*
G02Y1577797I1661J1458D01*
G03X160238Y1577929I-150J132D01*
G01Y1579867D01*
G03X160188Y1579999I-200J0D01*
G02Y1582915I1661J1458D01*
G03X160238Y1583047I-150J132D01*
G01Y1583667D01*
G02X160440Y1583870I202J1D01*
G37*
G36*
G01X281700D02*
X284520D01*
G02X284722Y1583667I-1J-203D01*
G01Y1583047D01*
G03X284772Y1582915I200J0D01*
G02Y1579999I-1661J-1458D01*
G03X284722Y1579867I150J-132D01*
G01Y1577929D01*
G03X284772Y1577797I200J0D01*
G02Y1574881I-1661J-1458D01*
G03X284722Y1574749I150J-132D01*
G01Y1574129D01*
G02X284520Y1573926I-202J-1D01*
G01X281700D01*
G02X281498Y1574129I1J203D01*
G01Y1574749D01*
G03X281448Y1574881I-200J0D01*
G02Y1577797I1661J1458D01*
G03X281498Y1577929I-150J132D01*
G01Y1579867D01*
G03X281448Y1579999I-200J0D01*
G02Y1582915I1661J1458D01*
G03X281498Y1583047I-150J132D01*
G01Y1583667D01*
G02X281700Y1583870I202J1D01*
G37*
G36*
G01X299023D02*
X301843D01*
G02X302046Y1583667I0J-203D01*
G01Y1583045D01*
G03X302096Y1582913I200J0D01*
G02Y1580001I-1664J-1456D01*
G03X302046Y1579869I150J-132D01*
G01Y1577927D01*
G03X302096Y1577795I200J0D01*
G02Y1574883I-1664J-1456D01*
G03X302046Y1574751I150J-132D01*
G01Y1574129D01*
G02X301843Y1573926I-203J0D01*
G01X299023D01*
G02X298820Y1574129I0J203D01*
G01Y1574751D01*
G03X298770Y1574883I-200J0D01*
G02Y1577795I1664J1456D01*
G03X298820Y1577927I-150J132D01*
G01Y1579869D01*
G03X298770Y1580001I-200J0D01*
G02Y1582913I1664J1456D01*
G03X298820Y1583045I-150J132D01*
G01Y1583667D01*
G02X299023Y1583870I203J0D01*
G37*
G36*
G01X316346D02*
X319166D01*
G02X319368Y1583667I-1J-203D01*
G01Y1583047D01*
G03X319418Y1582915I200J0D01*
G02Y1579999I-1661J-1458D01*
G03X319368Y1579867I150J-132D01*
G01Y1577929D01*
G03X319418Y1577797I200J0D01*
G02Y1574881I-1661J-1458D01*
G03X319368Y1574749I150J-132D01*
G01Y1574129D01*
G02X319166Y1573926I-202J-1D01*
G01X316346D01*
G02X316144Y1574129I1J203D01*
G01Y1574749D01*
G03X316094Y1574881I-200J0D01*
G02Y1577797I1661J1458D01*
G03X316144Y1577929I-150J132D01*
G01Y1579867D01*
G03X316094Y1579999I-200J0D01*
G02Y1582915I1661J1458D01*
G03X316144Y1583047I-150J132D01*
G01Y1583667D01*
G02X316346Y1583870I202J1D01*
G37*
G36*
G01X333668D02*
X336488D01*
G02X336690Y1583667I-1J-203D01*
G01Y1583047D01*
G03X336740Y1582915I200J0D01*
G02Y1579999I-1661J-1458D01*
G03X336690Y1579867I150J-132D01*
G01Y1577929D01*
G03X336740Y1577797I200J0D01*
G02Y1574881I-1661J-1458D01*
G03X336690Y1574749I150J-132D01*
G01Y1574129D01*
G02X336488Y1573926I-202J-1D01*
G01X333668D01*
G02X333466Y1574129I1J203D01*
G01Y1574749D01*
G03X333416Y1574881I-200J0D01*
G02Y1577797I1661J1458D01*
G03X333466Y1577929I-150J132D01*
G01Y1579867D01*
G03X333416Y1579999I-200J0D01*
G02Y1582915I1661J1458D01*
G03X333466Y1583047I-150J132D01*
G01Y1583667D01*
G02X333668Y1583870I202J1D01*
G37*
G36*
G01X628157D02*
X630977D01*
G02X631180Y1583667I0J-203D01*
G01Y1583045D01*
G03X631230Y1582913I200J0D01*
G02Y1580001I-1664J-1456D01*
G03X631180Y1579869I150J-132D01*
G01Y1577927D01*
G03X631230Y1577795I200J0D01*
G02Y1574883I-1664J-1456D01*
G03X631180Y1574751I150J-132D01*
G01Y1574129D01*
G02X630977Y1573926I-203J0D01*
G01X628157D01*
G02X627954Y1574129I0J203D01*
G01Y1574751D01*
G03X627904Y1574883I-200J0D01*
G02Y1577795I1664J1456D01*
G03X627954Y1577927I-150J132D01*
G01Y1579869D01*
G03X627904Y1580001I-200J0D01*
G02Y1582913I1664J1456D01*
G03X627954Y1583045I-150J132D01*
G01Y1583667D01*
G02X628157Y1583870I203J0D01*
G37*
G36*
G01X645480D02*
X648300D01*
G02X648502Y1583667I-1J-203D01*
G01Y1583047D01*
G03X648552Y1582915I200J0D01*
G02Y1579999I-1661J-1458D01*
G03X648502Y1579867I150J-132D01*
G01Y1577929D01*
G03X648552Y1577797I200J0D01*
G02Y1574881I-1661J-1458D01*
G03X648502Y1574749I150J-132D01*
G01Y1574129D01*
G02X648300Y1573926I-202J-1D01*
G01X645480D01*
G02X645278Y1574129I1J203D01*
G01Y1574749D01*
G03X645228Y1574881I-200J0D01*
G02Y1577797I1661J1458D01*
G03X645278Y1577929I-150J132D01*
G01Y1579867D01*
G03X645228Y1579999I-200J0D01*
G02Y1582915I1661J1458D01*
G03X645278Y1583047I-150J132D01*
G01Y1583667D01*
G02X645480Y1583870I202J1D01*
G37*
G36*
G01X662803D02*
X665623D01*
G02X665826Y1583667I0J-203D01*
G01Y1583045D01*
G03X665876Y1582913I200J0D01*
G02Y1580001I-1664J-1456D01*
G03X665826Y1579869I150J-132D01*
G01Y1577927D01*
G03X665876Y1577795I200J0D01*
G02Y1574883I-1664J-1456D01*
G03X665826Y1574751I150J-132D01*
G01Y1574129D01*
G02X665623Y1573926I-203J0D01*
G01X662803D01*
G02X662600Y1574129I0J203D01*
G01Y1574751D01*
G03X662550Y1574883I-200J0D01*
G02Y1577795I1664J1456D01*
G03X662600Y1577927I-150J132D01*
G01Y1579869D01*
G03X662550Y1580001I-200J0D01*
G02Y1582913I1664J1456D01*
G03X662600Y1583045I-150J132D01*
G01Y1583667D01*
G02X662803Y1583870I203J0D01*
G37*
G36*
G01X680125D02*
X682945D01*
G02X683148Y1583667I0J-203D01*
G01Y1583045D01*
G03X683198Y1582913I200J0D01*
G02Y1580001I-1664J-1456D01*
G03X683148Y1579869I150J-132D01*
G01Y1577927D01*
G03X683198Y1577795I200J0D01*
G02Y1574883I-1664J-1456D01*
G03X683148Y1574751I150J-132D01*
G01Y1574129D01*
G02X682945Y1573926I-203J0D01*
G01X680125D01*
G02X679922Y1574129I0J203D01*
G01Y1574751D01*
G03X679872Y1574883I-200J0D01*
G02Y1577795I1664J1456D01*
G03X679922Y1577927I-150J132D01*
G01Y1579869D01*
G03X679872Y1580001I-200J0D01*
G02Y1582913I1664J1456D01*
G03X679922Y1583045I-150J132D01*
G01Y1583667D01*
G02X680125Y1583870I203J0D01*
G37*
G36*
G01X1130440D02*
X1133260D01*
G02X1133462Y1583667I-1J-203D01*
G01Y1583047D01*
G03X1133512Y1582915I200J0D01*
G02Y1579999I-1661J-1458D01*
G03X1133462Y1579867I150J-132D01*
G01Y1577929D01*
G03X1133512Y1577797I200J0D01*
G02Y1574881I-1661J-1458D01*
G03X1133462Y1574749I150J-132D01*
G01Y1574129D01*
G02X1133260Y1573926I-202J-1D01*
G01X1130440D01*
G02X1130238Y1574129I1J203D01*
G01Y1574749D01*
G03X1130188Y1574881I-200J0D01*
G02Y1577797I1661J1458D01*
G03X1130238Y1577929I-150J132D01*
G01Y1579867D01*
G03X1130188Y1579999I-200J0D01*
G02Y1582915I1661J1458D01*
G03X1130238Y1583047I-150J132D01*
G01Y1583667D01*
G02X1130440Y1583870I202J1D01*
G37*
G36*
G01X1147763D02*
X1150583D01*
G02X1150786Y1583667I0J-203D01*
G01Y1583045D01*
G03X1150836Y1582913I200J0D01*
G02Y1580001I-1664J-1456D01*
G03X1150786Y1579869I150J-132D01*
G01Y1577927D01*
G03X1150836Y1577795I200J0D01*
G02Y1574883I-1664J-1456D01*
G03X1150786Y1574751I150J-132D01*
G01Y1574129D01*
G02X1150583Y1573926I-203J0D01*
G01X1147763D01*
G02X1147560Y1574129I0J203D01*
G01Y1574751D01*
G03X1147510Y1574883I-200J0D01*
G02Y1577795I1664J1456D01*
G03X1147560Y1577927I-150J132D01*
G01Y1579869D01*
G03X1147510Y1580001I-200J0D01*
G02Y1582913I1664J1456D01*
G03X1147560Y1583045I-150J132D01*
G01Y1583667D01*
G02X1147763Y1583870I203J0D01*
G37*
G36*
G01X1165086D02*
X1167906D01*
G02X1168108Y1583667I-1J-203D01*
G01Y1583047D01*
G03X1168158Y1582915I200J0D01*
G02Y1579999I-1661J-1458D01*
G03X1168108Y1579867I150J-132D01*
G01Y1577929D01*
G03X1168158Y1577797I200J0D01*
G02Y1574881I-1661J-1458D01*
G03X1168108Y1574749I150J-132D01*
G01Y1574129D01*
G02X1167906Y1573926I-202J-1D01*
G01X1165086D01*
G02X1164884Y1574129I1J203D01*
G01Y1574749D01*
G03X1164834Y1574881I-200J0D01*
G02Y1577797I1661J1458D01*
G03X1164884Y1577929I-150J132D01*
G01Y1579867D01*
G03X1164834Y1579999I-200J0D01*
G02Y1582915I1661J1458D01*
G03X1164884Y1583047I-150J132D01*
G01Y1583667D01*
G02X1165086Y1583870I202J1D01*
G37*
G36*
G01X1182408D02*
X1185228D01*
G02X1185430Y1583667I-1J-203D01*
G01Y1583047D01*
G03X1185480Y1582915I200J0D01*
G02Y1579999I-1661J-1458D01*
G03X1185430Y1579867I150J-132D01*
G01Y1577929D01*
G03X1185480Y1577797I200J0D01*
G02Y1574881I-1661J-1458D01*
G03X1185430Y1574749I150J-132D01*
G01Y1574129D01*
G02X1185228Y1573926I-202J-1D01*
G01X1182408D01*
G02X1182206Y1574129I1J203D01*
G01Y1574749D01*
G03X1182156Y1574881I-200J0D01*
G02Y1577797I1661J1458D01*
G03X1182206Y1577929I-150J132D01*
G01Y1579867D01*
G03X1182156Y1579999I-200J0D01*
G02Y1582915I1661J1458D01*
G03X1182206Y1583047I-150J132D01*
G01Y1583667D01*
G02X1182408Y1583870I202J1D01*
G37*
G36*
G01X1303669D02*
X1306489D01*
G02X1306692Y1583667I0J-203D01*
G01Y1583045D01*
G03X1306742Y1582913I200J0D01*
G02Y1580001I-1664J-1456D01*
G03X1306692Y1579869I150J-132D01*
G01Y1577927D01*
G03X1306742Y1577795I200J0D01*
G02Y1574883I-1664J-1456D01*
G03X1306692Y1574751I150J-132D01*
G01Y1574129D01*
G02X1306489Y1573926I-203J0D01*
G01X1303669D01*
G02X1303466Y1574129I0J203D01*
G01Y1574751D01*
G03X1303416Y1574883I-200J0D01*
G02Y1577795I1664J1456D01*
G03X1303466Y1577927I-150J132D01*
G01Y1579869D01*
G03X1303416Y1580001I-200J0D01*
G02Y1582913I1664J1456D01*
G03X1303466Y1583045I-150J132D01*
G01Y1583667D01*
G02X1303669Y1583870I203J0D01*
G37*
G36*
G01X1320992D02*
X1323812D01*
G02X1324014Y1583667I-1J-203D01*
G01Y1583047D01*
G03X1324064Y1582915I200J0D01*
G02Y1579999I-1661J-1458D01*
G03X1324014Y1579867I150J-132D01*
G01Y1577929D01*
G03X1324064Y1577797I200J0D01*
G02Y1574881I-1661J-1458D01*
G03X1324014Y1574749I150J-132D01*
G01Y1574129D01*
G02X1323812Y1573926I-202J-1D01*
G01X1320992D01*
G02X1320790Y1574129I1J203D01*
G01Y1574749D01*
G03X1320740Y1574881I-200J0D01*
G02Y1577797I1661J1458D01*
G03X1320790Y1577929I-150J132D01*
G01Y1579867D01*
G03X1320740Y1579999I-200J0D01*
G02Y1582915I1661J1458D01*
G03X1320790Y1583047I-150J132D01*
G01Y1583667D01*
G02X1320992Y1583870I202J1D01*
G37*
G36*
G01X1338315D02*
X1341135D01*
G02X1341338Y1583667I0J-203D01*
G01Y1583045D01*
G03X1341388Y1582913I200J0D01*
G02Y1580001I-1664J-1456D01*
G03X1341338Y1579869I150J-132D01*
G01Y1577927D01*
G03X1341388Y1577795I200J0D01*
G02Y1574883I-1664J-1456D01*
G03X1341338Y1574751I150J-132D01*
G01Y1574129D01*
G02X1341135Y1573926I-203J0D01*
G01X1338315D01*
G02X1338112Y1574129I0J203D01*
G01Y1574751D01*
G03X1338062Y1574883I-200J0D01*
G02Y1577795I1664J1456D01*
G03X1338112Y1577927I-150J132D01*
G01Y1579869D01*
G03X1338062Y1580001I-200J0D01*
G02Y1582913I1664J1456D01*
G03X1338112Y1583045I-150J132D01*
G01Y1583667D01*
G02X1338315Y1583870I203J0D01*
G37*
G36*
G01X1355637D02*
X1358457D01*
G02X1358660Y1583667I0J-203D01*
G01Y1583045D01*
G03X1358710Y1582913I200J0D01*
G02Y1580001I-1664J-1456D01*
G03X1358660Y1579869I150J-132D01*
G01Y1577927D01*
G03X1358710Y1577795I200J0D01*
G02Y1574883I-1664J-1456D01*
G03X1358660Y1574751I150J-132D01*
G01Y1574129D01*
G02X1358457Y1573926I-203J0D01*
G01X1355637D01*
G02X1355434Y1574129I0J203D01*
G01Y1574751D01*
G03X1355384Y1574883I-200J0D01*
G02Y1577795I1664J1456D01*
G03X1355434Y1577927I-150J132D01*
G01Y1579869D01*
G03X1355384Y1580001I-200J0D01*
G02Y1582913I1664J1456D01*
G03X1355434Y1583045I-150J132D01*
G01Y1583667D01*
G02X1355637Y1583870I203J0D01*
G37*
G36*
G01X1476897D02*
X1479717D01*
G02X1479920Y1583667I0J-203D01*
G01Y1583045D01*
G03X1479970Y1582913I200J0D01*
G02Y1580001I-1664J-1456D01*
G03X1479920Y1579869I150J-132D01*
G01Y1577927D01*
G03X1479970Y1577795I200J0D01*
G02Y1574883I-1664J-1456D01*
G03X1479920Y1574751I150J-132D01*
G01Y1574129D01*
G02X1479717Y1573926I-203J0D01*
G01X1476897D01*
G02X1476694Y1574129I0J203D01*
G01Y1574751D01*
G03X1476644Y1574883I-200J0D01*
G02Y1577795I1664J1456D01*
G03X1476694Y1577927I-150J132D01*
G01Y1579869D01*
G03X1476644Y1580001I-200J0D01*
G02Y1582913I1664J1456D01*
G03X1476694Y1583045I-150J132D01*
G01Y1583667D01*
G02X1476897Y1583870I203J0D01*
G37*
G36*
G01X1650125D02*
X1652945D01*
G02X1653148Y1583667I0J-203D01*
G01Y1583045D01*
G03X1653198Y1582913I200J0D01*
G02Y1580001I-1664J-1456D01*
G03X1653148Y1579869I150J-132D01*
G01Y1577927D01*
G03X1653198Y1577795I200J0D01*
G02Y1574883I-1664J-1456D01*
G03X1653148Y1574751I150J-132D01*
G01Y1574129D01*
G02X1652945Y1573926I-203J0D01*
G01X1650125D01*
G02X1649922Y1574129I0J203D01*
G01Y1574751D01*
G03X1649872Y1574883I-200J0D01*
G02Y1577795I1664J1456D01*
G03X1649922Y1577927I-150J132D01*
G01Y1579869D01*
G03X1649872Y1580001I-200J0D01*
G02Y1582913I1664J1456D01*
G03X1649922Y1583045I-150J132D01*
G01Y1583667D01*
G02X1650125Y1583870I203J0D01*
G37*
G36*
G01X1667448D02*
X1670268D01*
G02X1670470Y1583667I-1J-203D01*
G01Y1583047D01*
G03X1670520Y1582915I200J0D01*
G02Y1579999I-1661J-1458D01*
G03X1670470Y1579867I150J-132D01*
G01Y1577929D01*
G03X1670520Y1577797I200J0D01*
G02Y1574881I-1661J-1458D01*
G03X1670470Y1574749I150J-132D01*
G01Y1574129D01*
G02X1670268Y1573926I-202J-1D01*
G01X1667448D01*
G02X1667246Y1574129I1J203D01*
G01Y1574749D01*
G03X1667196Y1574881I-200J0D01*
G02Y1577797I1661J1458D01*
G03X1667246Y1577929I-150J132D01*
G01Y1579867D01*
G03X1667196Y1579999I-200J0D01*
G02Y1582915I1661J1458D01*
G03X1667246Y1583047I-150J132D01*
G01Y1583667D01*
G02X1667448Y1583870I202J1D01*
G37*
G36*
G01X1684771D02*
X1687591D01*
G02X1687794Y1583667I0J-203D01*
G01Y1583045D01*
G03X1687844Y1582913I200J0D01*
G02Y1580001I-1664J-1456D01*
G03X1687794Y1579869I150J-132D01*
G01Y1577927D01*
G03X1687844Y1577795I200J0D01*
G02Y1574883I-1664J-1456D01*
G03X1687794Y1574751I150J-132D01*
G01Y1574129D01*
G02X1687591Y1573926I-203J0D01*
G01X1684771D01*
G02X1684568Y1574129I0J203D01*
G01Y1574751D01*
G03X1684518Y1574883I-200J0D01*
G02Y1577795I1664J1456D01*
G03X1684568Y1577927I-150J132D01*
G01Y1579869D01*
G03X1684518Y1580001I-200J0D01*
G02Y1582913I1664J1456D01*
G03X1684568Y1583045I-150J132D01*
G01Y1583667D01*
G02X1684771Y1583870I203J0D01*
G37*
G36*
G01X1702093D02*
X1704913D01*
G02X1705116Y1583667I0J-203D01*
G01Y1583045D01*
G03X1705166Y1582913I200J0D01*
G02Y1580001I-1664J-1456D01*
G03X1705116Y1579869I150J-132D01*
G01Y1577927D01*
G03X1705166Y1577795I200J0D01*
G02Y1574883I-1664J-1456D01*
G03X1705116Y1574751I150J-132D01*
G01Y1574129D01*
G02X1704913Y1573926I-203J0D01*
G01X1702093D01*
G02X1701890Y1574129I0J203D01*
G01Y1574751D01*
G03X1701840Y1574883I-200J0D01*
G02Y1577795I1664J1456D01*
G03X1701890Y1577927I-150J132D01*
G01Y1579869D01*
G03X1701840Y1580001I-200J0D01*
G02Y1582913I1664J1456D01*
G03X1701890Y1583045I-150J132D01*
G01Y1583667D01*
G02X1702093Y1583870I203J0D01*
G37*
G36*
G01X134456Y1588200D02*
X137276D01*
G02X137478Y1587998I0J-202D01*
G01Y1587378D01*
G03X137528Y1587246I200J0D01*
G02Y1584330I-1661J-1458D01*
G03X137478Y1584198I150J-132D01*
G01Y1582260D01*
G03X137528Y1582128I200J0D01*
G02Y1579212I-1661J-1458D01*
G03X137478Y1579080I150J-132D01*
G01Y1578460D01*
G02X137276Y1578258I-202J0D01*
G01X134456D01*
G02X134254Y1578460I0J202D01*
G01Y1579080D01*
G03X134204Y1579212I-200J0D01*
G02Y1582128I1661J1458D01*
G03X134254Y1582260I-150J132D01*
G01Y1584198D01*
G03X134204Y1584330I-200J0D01*
G02Y1587246I1661J1458D01*
G03X134254Y1587378I-150J132D01*
G01Y1587998D01*
G02X134456Y1588200I202J0D01*
G37*
G36*
G01X169102D02*
X171922D01*
G02X172124Y1587998I0J-202D01*
G01Y1587378D01*
G03X172174Y1587246I200J0D01*
G02Y1584330I-1661J-1458D01*
G03X172124Y1584198I150J-132D01*
G01Y1582260D01*
G03X172174Y1582128I200J0D01*
G02Y1579212I-1661J-1458D01*
G03X172124Y1579080I150J-132D01*
G01Y1578460D01*
G02X171922Y1578258I-202J0D01*
G01X169102D01*
G02X168900Y1578460I0J202D01*
G01Y1579080D01*
G03X168850Y1579212I-200J0D01*
G02Y1582128I1661J1458D01*
G03X168900Y1582260I-150J132D01*
G01Y1584198D01*
G03X168850Y1584330I-200J0D01*
G02Y1587246I1661J1458D01*
G03X168900Y1587378I-150J132D01*
G01Y1587998D01*
G02X169102Y1588200I202J0D01*
G37*
G36*
G01X307684D02*
X310504D01*
G02X310706Y1587998I0J-202D01*
G01Y1587378D01*
G03X310756Y1587246I200J0D01*
G02Y1584330I-1661J-1458D01*
G03X310706Y1584198I150J-132D01*
G01Y1582260D01*
G03X310756Y1582128I200J0D01*
G02Y1579212I-1661J-1458D01*
G03X310706Y1579080I150J-132D01*
G01Y1578460D01*
G02X310504Y1578258I-202J0D01*
G01X307684D01*
G02X307482Y1578460I0J202D01*
G01Y1579080D01*
G03X307432Y1579212I-200J0D01*
G02Y1582128I1661J1458D01*
G03X307482Y1582260I-150J132D01*
G01Y1584198D01*
G03X307432Y1584330I-200J0D01*
G02Y1587246I1661J1458D01*
G03X307482Y1587378I-150J132D01*
G01Y1587998D01*
G02X307684Y1588200I202J0D01*
G37*
G36*
G01X342330D02*
X345150D01*
G02X345352Y1587998I0J-202D01*
G01Y1587378D01*
G03X345402Y1587246I200J0D01*
G02Y1584330I-1661J-1458D01*
G03X345352Y1584198I150J-132D01*
G01Y1582260D01*
G03X345402Y1582128I200J0D01*
G02Y1579212I-1661J-1458D01*
G03X345352Y1579080I150J-132D01*
G01Y1578460D01*
G02X345150Y1578258I-202J0D01*
G01X342330D01*
G02X342128Y1578460I0J202D01*
G01Y1579080D01*
G03X342078Y1579212I-200J0D01*
G02Y1582128I1661J1458D01*
G03X342128Y1582260I-150J132D01*
G01Y1584198D01*
G03X342078Y1584330I-200J0D01*
G02Y1587246I1661J1458D01*
G03X342128Y1587378I-150J132D01*
G01Y1587998D01*
G02X342330Y1588200I202J0D01*
G37*
G36*
G01X636818D02*
X639638D01*
G02X639840Y1587998I0J-202D01*
G01Y1587378D01*
G03X639890Y1587246I200J0D01*
G02Y1584330I-1661J-1458D01*
G03X639840Y1584198I150J-132D01*
G01Y1582260D01*
G03X639890Y1582128I200J0D01*
G02Y1579212I-1661J-1458D01*
G03X639840Y1579080I150J-132D01*
G01Y1578460D01*
G02X639638Y1578258I-202J0D01*
G01X636818D01*
G02X636616Y1578460I0J202D01*
G01Y1579080D01*
G03X636566Y1579212I-200J0D01*
G02Y1582128I1661J1458D01*
G03X636616Y1582260I-150J132D01*
G01Y1584198D01*
G03X636566Y1584330I-200J0D01*
G02Y1587246I1661J1458D01*
G03X636616Y1587378I-150J132D01*
G01Y1587998D01*
G02X636818Y1588200I202J0D01*
G37*
G36*
G01X671464D02*
X674284D01*
G02X674486Y1587998I0J-202D01*
G01Y1587378D01*
G03X674536Y1587246I200J0D01*
G02Y1584330I-1661J-1458D01*
G03X674486Y1584198I150J-132D01*
G01Y1582260D01*
G03X674536Y1582128I200J0D01*
G02Y1579212I-1661J-1458D01*
G03X674486Y1579080I150J-132D01*
G01Y1578460D01*
G02X674284Y1578258I-202J0D01*
G01X671464D01*
G02X671262Y1578460I0J202D01*
G01Y1579080D01*
G03X671212Y1579212I-200J0D01*
G02Y1582128I1661J1458D01*
G03X671262Y1582260I-150J132D01*
G01Y1584198D01*
G03X671212Y1584330I-200J0D01*
G02Y1587246I1661J1458D01*
G03X671262Y1587378I-150J132D01*
G01Y1587998D01*
G02X671464Y1588200I202J0D01*
G37*
G36*
G01X1156424D02*
X1159244D01*
G02X1159446Y1587998I0J-202D01*
G01Y1587378D01*
G03X1159496Y1587246I200J0D01*
G02Y1584330I-1661J-1458D01*
G03X1159446Y1584198I150J-132D01*
G01Y1582260D01*
G03X1159496Y1582128I200J0D01*
G02Y1579212I-1661J-1458D01*
G03X1159446Y1579080I150J-132D01*
G01Y1578460D01*
G02X1159244Y1578258I-202J0D01*
G01X1156424D01*
G02X1156222Y1578460I0J202D01*
G01Y1579080D01*
G03X1156172Y1579212I-200J0D01*
G02Y1582128I1661J1458D01*
G03X1156222Y1582260I-150J132D01*
G01Y1584198D01*
G03X1156172Y1584330I-200J0D01*
G02Y1587246I1661J1458D01*
G03X1156222Y1587378I-150J132D01*
G01Y1587998D01*
G02X1156424Y1588200I202J0D01*
G37*
G36*
G01X1191070D02*
X1193890D01*
G02X1194092Y1587998I0J-202D01*
G01Y1587378D01*
G03X1194142Y1587246I200J0D01*
G02Y1584330I-1661J-1458D01*
G03X1194092Y1584198I150J-132D01*
G01Y1582260D01*
G03X1194142Y1582128I200J0D01*
G02Y1579212I-1661J-1458D01*
G03X1194092Y1579080I150J-132D01*
G01Y1578460D01*
G02X1193890Y1578258I-202J0D01*
G01X1191070D01*
G02X1190868Y1578460I0J202D01*
G01Y1579080D01*
G03X1190818Y1579212I-200J0D01*
G02Y1582128I1661J1458D01*
G03X1190868Y1582260I-150J132D01*
G01Y1584198D01*
G03X1190818Y1584330I-200J0D01*
G02Y1587246I1661J1458D01*
G03X1190868Y1587378I-150J132D01*
G01Y1587998D01*
G02X1191070Y1588200I202J0D01*
G37*
G36*
G01X1312330D02*
X1315150D01*
G02X1315352Y1587998I0J-202D01*
G01Y1587378D01*
G03X1315402Y1587246I200J0D01*
G02Y1584330I-1661J-1458D01*
G03X1315352Y1584198I150J-132D01*
G01Y1582260D01*
G03X1315402Y1582128I200J0D01*
G02Y1579212I-1661J-1458D01*
G03X1315352Y1579080I150J-132D01*
G01Y1578460D01*
G02X1315150Y1578258I-202J0D01*
G01X1312330D01*
G02X1312128Y1578460I0J202D01*
G01Y1579080D01*
G03X1312078Y1579212I-200J0D01*
G02Y1582128I1661J1458D01*
G03X1312128Y1582260I-150J132D01*
G01Y1584198D01*
G03X1312078Y1584330I-200J0D01*
G02Y1587246I1661J1458D01*
G03X1312128Y1587378I-150J132D01*
G01Y1587998D01*
G02X1312330Y1588200I202J0D01*
G37*
G36*
G01X1346976D02*
X1349796D01*
G02X1349998Y1587998I0J-202D01*
G01Y1587378D01*
G03X1350048Y1587246I200J0D01*
G02Y1584330I-1661J-1458D01*
G03X1349998Y1584198I150J-132D01*
G01Y1582260D01*
G03X1350048Y1582128I200J0D01*
G02Y1579212I-1661J-1458D01*
G03X1349998Y1579080I150J-132D01*
G01Y1578460D01*
G02X1349796Y1578258I-202J0D01*
G01X1346976D01*
G02X1346774Y1578460I0J202D01*
G01Y1579080D01*
G03X1346724Y1579212I-200J0D01*
G02Y1582128I1661J1458D01*
G03X1346774Y1582260I-150J132D01*
G01Y1584198D01*
G03X1346724Y1584330I-200J0D01*
G02Y1587246I1661J1458D01*
G03X1346774Y1587378I-150J132D01*
G01Y1587998D01*
G02X1346976Y1588200I202J0D01*
G37*
G36*
G01X1658786D02*
X1661606D01*
G02X1661808Y1587998I0J-202D01*
G01Y1587378D01*
G03X1661858Y1587246I200J0D01*
G02Y1584330I-1661J-1458D01*
G03X1661808Y1584198I150J-132D01*
G01Y1582260D01*
G03X1661858Y1582128I200J0D01*
G02Y1579212I-1661J-1458D01*
G03X1661808Y1579080I150J-132D01*
G01Y1578460D01*
G02X1661606Y1578258I-202J0D01*
G01X1658786D01*
G02X1658584Y1578460I0J202D01*
G01Y1579080D01*
G03X1658534Y1579212I-200J0D01*
G02Y1582128I1661J1458D01*
G03X1658584Y1582260I-150J132D01*
G01Y1584198D01*
G03X1658534Y1584330I-200J0D01*
G02Y1587246I1661J1458D01*
G03X1658584Y1587378I-150J132D01*
G01Y1587998D01*
G02X1658786Y1588200I202J0D01*
G37*
G36*
G01X1693432D02*
X1696252D01*
G02X1696454Y1587998I0J-202D01*
G01Y1587378D01*
G03X1696504Y1587246I200J0D01*
G02Y1584330I-1661J-1458D01*
G03X1696454Y1584198I150J-132D01*
G01Y1582260D01*
G03X1696504Y1582128I200J0D01*
G02Y1579212I-1661J-1458D01*
G03X1696454Y1579080I150J-132D01*
G01Y1578460D01*
G02X1696252Y1578258I-202J0D01*
G01X1693432D01*
G02X1693230Y1578460I0J202D01*
G01Y1579080D01*
G03X1693180Y1579212I-200J0D01*
G02Y1582128I1661J1458D01*
G03X1693230Y1582260I-150J132D01*
G01Y1584198D01*
G03X1693180Y1584330I-200J0D01*
G02Y1587246I1661J1458D01*
G03X1693230Y1587378I-150J132D01*
G01Y1587998D01*
G02X1693432Y1588200I202J0D01*
G37*
G36*
G01X117133D02*
X119953D01*
G02X120156Y1587998I1J-202D01*
G01Y1587376D01*
G03X120206Y1587244I200J0D01*
G02Y1584332I-1664J-1456D01*
G03X120156Y1584200I150J-132D01*
G01Y1582258D01*
G03X120206Y1582126I200J0D01*
G02Y1579214I-1664J-1456D01*
G03X120156Y1579082I150J-132D01*
G01Y1578460D01*
G02X119953Y1578258I-203J1D01*
G01X117133D01*
G02X116930Y1578460I-1J202D01*
G01Y1579082D01*
G03X116880Y1579214I-200J0D01*
G02Y1582126I1664J1456D01*
G03X116930Y1582258I-150J132D01*
G01Y1584200D01*
G03X116880Y1584332I-200J0D01*
G02Y1587244I1664J1456D01*
G03X116930Y1587376I-150J132D01*
G01Y1587998D01*
G02X117133Y1588200I203J-1D01*
G37*
G36*
G01X151779D02*
X154599D01*
G02X154802Y1587998I1J-202D01*
G01Y1587376D01*
G03X154852Y1587244I200J0D01*
G02Y1584332I-1664J-1456D01*
G03X154802Y1584200I150J-132D01*
G01Y1582258D01*
G03X154852Y1582126I200J0D01*
G02Y1579214I-1664J-1456D01*
G03X154802Y1579082I150J-132D01*
G01Y1578460D01*
G02X154599Y1578258I-203J1D01*
G01X151779D01*
G02X151576Y1578460I-1J202D01*
G01Y1579082D01*
G03X151526Y1579214I-200J0D01*
G02Y1582126I1664J1456D01*
G03X151576Y1582258I-150J132D01*
G01Y1584200D01*
G03X151526Y1584332I-200J0D01*
G02Y1587244I1664J1456D01*
G03X151576Y1587376I-150J132D01*
G01Y1587998D01*
G02X151779Y1588200I203J-1D01*
G37*
G36*
G01X290361D02*
X293181D01*
G02X293384Y1587998I1J-202D01*
G01Y1587376D01*
G03X293434Y1587244I200J0D01*
G02Y1584332I-1664J-1456D01*
G03X293384Y1584200I150J-132D01*
G01Y1582258D01*
G03X293434Y1582126I200J0D01*
G02Y1579214I-1664J-1456D01*
G03X293384Y1579082I150J-132D01*
G01Y1578460D01*
G02X293181Y1578258I-203J1D01*
G01X290361D01*
G02X290158Y1578460I-1J202D01*
G01Y1579082D01*
G03X290108Y1579214I-200J0D01*
G02Y1582126I1664J1456D01*
G03X290158Y1582258I-150J132D01*
G01Y1584200D01*
G03X290108Y1584332I-200J0D01*
G02Y1587244I1664J1456D01*
G03X290158Y1587376I-150J132D01*
G01Y1587998D01*
G02X290361Y1588200I203J-1D01*
G37*
G36*
G01X325007D02*
X327827D01*
G02X328030Y1587998I1J-202D01*
G01Y1587376D01*
G03X328080Y1587244I200J0D01*
G02Y1584332I-1664J-1456D01*
G03X328030Y1584200I150J-132D01*
G01Y1582258D01*
G03X328080Y1582126I200J0D01*
G02Y1579214I-1664J-1456D01*
G03X328030Y1579082I150J-132D01*
G01Y1578460D01*
G02X327827Y1578258I-203J1D01*
G01X325007D01*
G02X324804Y1578460I-1J202D01*
G01Y1579082D01*
G03X324754Y1579214I-200J0D01*
G02Y1582126I1664J1456D01*
G03X324804Y1582258I-150J132D01*
G01Y1584200D01*
G03X324754Y1584332I-200J0D01*
G02Y1587244I1664J1456D01*
G03X324804Y1587376I-150J132D01*
G01Y1587998D01*
G02X325007Y1588200I203J-1D01*
G37*
G36*
G01X515559D02*
X518379D01*
G02X518582Y1587998I1J-202D01*
G01Y1587376D01*
G03X518632Y1587244I200J0D01*
G02Y1584332I-1664J-1456D01*
G03X518582Y1584200I150J-132D01*
G01Y1582258D01*
G03X518632Y1582126I200J0D01*
G02Y1579214I-1664J-1456D01*
G03X518582Y1579082I150J-132D01*
G01Y1578460D01*
G02X518379Y1578258I-203J1D01*
G01X515559D01*
G02X515356Y1578460I-1J202D01*
G01Y1579082D01*
G03X515306Y1579214I-200J0D01*
G02Y1582126I1664J1456D01*
G03X515356Y1582258I-150J132D01*
G01Y1584200D01*
G03X515306Y1584332I-200J0D01*
G02Y1587244I1664J1456D01*
G03X515356Y1587376I-150J132D01*
G01Y1587998D01*
G02X515559Y1588200I203J-1D01*
G37*
G36*
G01X654141D02*
X656961D01*
G02X657164Y1587998I1J-202D01*
G01Y1587376D01*
G03X657214Y1587244I200J0D01*
G02Y1584332I-1664J-1456D01*
G03X657164Y1584200I150J-132D01*
G01Y1582258D01*
G03X657214Y1582126I200J0D01*
G02Y1579214I-1664J-1456D01*
G03X657164Y1579082I150J-132D01*
G01Y1578460D01*
G02X656961Y1578258I-203J1D01*
G01X654141D01*
G02X653938Y1578460I-1J202D01*
G01Y1579082D01*
G03X653888Y1579214I-200J0D01*
G02Y1582126I1664J1456D01*
G03X653938Y1582258I-150J132D01*
G01Y1584200D01*
G03X653888Y1584332I-200J0D01*
G02Y1587244I1664J1456D01*
G03X653938Y1587376I-150J132D01*
G01Y1587998D01*
G02X654141Y1588200I203J-1D01*
G37*
G36*
G01X688787D02*
X691607D01*
G02X691810Y1587998I1J-202D01*
G01Y1587376D01*
G03X691860Y1587244I200J0D01*
G02Y1584332I-1664J-1456D01*
G03X691810Y1584200I150J-132D01*
G01Y1582258D01*
G03X691860Y1582126I200J0D01*
G02Y1579214I-1664J-1456D01*
G03X691810Y1579082I150J-132D01*
G01Y1578460D01*
G02X691607Y1578258I-203J1D01*
G01X688787D01*
G02X688584Y1578460I-1J202D01*
G01Y1579082D01*
G03X688534Y1579214I-200J0D01*
G02Y1582126I1664J1456D01*
G03X688584Y1582258I-150J132D01*
G01Y1584200D01*
G03X688534Y1584332I-200J0D01*
G02Y1587244I1664J1456D01*
G03X688584Y1587376I-150J132D01*
G01Y1587998D01*
G02X688787Y1588200I203J-1D01*
G37*
G36*
G01X1139101D02*
X1141921D01*
G02X1142124Y1587998I1J-202D01*
G01Y1587376D01*
G03X1142174Y1587244I200J0D01*
G02Y1584332I-1664J-1456D01*
G03X1142124Y1584200I150J-132D01*
G01Y1582258D01*
G03X1142174Y1582126I200J0D01*
G02Y1579214I-1664J-1456D01*
G03X1142124Y1579082I150J-132D01*
G01Y1578460D01*
G02X1141921Y1578258I-203J1D01*
G01X1139101D01*
G02X1138898Y1578460I-1J202D01*
G01Y1579082D01*
G03X1138848Y1579214I-200J0D01*
G02Y1582126I1664J1456D01*
G03X1138898Y1582258I-150J132D01*
G01Y1584200D01*
G03X1138848Y1584332I-200J0D01*
G02Y1587244I1664J1456D01*
G03X1138898Y1587376I-150J132D01*
G01Y1587998D01*
G02X1139101Y1588200I203J-1D01*
G37*
G36*
G01X1173747D02*
X1176567D01*
G02X1176770Y1587998I1J-202D01*
G01Y1587376D01*
G03X1176820Y1587244I200J0D01*
G02Y1584332I-1664J-1456D01*
G03X1176770Y1584200I150J-132D01*
G01Y1582258D01*
G03X1176820Y1582126I200J0D01*
G02Y1579214I-1664J-1456D01*
G03X1176770Y1579082I150J-132D01*
G01Y1578460D01*
G02X1176567Y1578258I-203J1D01*
G01X1173747D01*
G02X1173544Y1578460I-1J202D01*
G01Y1579082D01*
G03X1173494Y1579214I-200J0D01*
G02Y1582126I1664J1456D01*
G03X1173544Y1582258I-150J132D01*
G01Y1584200D01*
G03X1173494Y1584332I-200J0D01*
G02Y1587244I1664J1456D01*
G03X1173544Y1587376I-150J132D01*
G01Y1587998D01*
G02X1173747Y1588200I203J-1D01*
G37*
G36*
G01X1329653D02*
X1332473D01*
G02X1332676Y1587998I1J-202D01*
G01Y1587376D01*
G03X1332726Y1587244I200J0D01*
G02Y1584332I-1664J-1456D01*
G03X1332676Y1584200I150J-132D01*
G01Y1582258D01*
G03X1332726Y1582126I200J0D01*
G02Y1579214I-1664J-1456D01*
G03X1332676Y1579082I150J-132D01*
G01Y1578460D01*
G02X1332473Y1578258I-203J1D01*
G01X1329653D01*
G02X1329450Y1578460I-1J202D01*
G01Y1579082D01*
G03X1329400Y1579214I-200J0D01*
G02Y1582126I1664J1456D01*
G03X1329450Y1582258I-150J132D01*
G01Y1584200D01*
G03X1329400Y1584332I-200J0D01*
G02Y1587244I1664J1456D01*
G03X1329450Y1587376I-150J132D01*
G01Y1587998D01*
G02X1329653Y1588200I203J-1D01*
G37*
G36*
G01X1364299D02*
X1367119D01*
G02X1367322Y1587998I1J-202D01*
G01Y1587376D01*
G03X1367372Y1587244I200J0D01*
G02Y1584332I-1664J-1456D01*
G03X1367322Y1584200I150J-132D01*
G01Y1582258D01*
G03X1367372Y1582126I200J0D01*
G02Y1579214I-1664J-1456D01*
G03X1367322Y1579082I150J-132D01*
G01Y1578460D01*
G02X1367119Y1578258I-203J1D01*
G01X1364299D01*
G02X1364096Y1578460I-1J202D01*
G01Y1579082D01*
G03X1364046Y1579214I-200J0D01*
G02Y1582126I1664J1456D01*
G03X1364096Y1582258I-150J132D01*
G01Y1584200D01*
G03X1364046Y1584332I-200J0D01*
G02Y1587244I1664J1456D01*
G03X1364096Y1587376I-150J132D01*
G01Y1587998D01*
G02X1364299Y1588200I203J-1D01*
G37*
G36*
G01X1676109D02*
X1678929D01*
G02X1679132Y1587998I1J-202D01*
G01Y1587376D01*
G03X1679182Y1587244I200J0D01*
G02Y1584332I-1664J-1456D01*
G03X1679132Y1584200I150J-132D01*
G01Y1582258D01*
G03X1679182Y1582126I200J0D01*
G02Y1579214I-1664J-1456D01*
G03X1679132Y1579082I150J-132D01*
G01Y1578460D01*
G02X1678929Y1578258I-203J1D01*
G01X1676109D01*
G02X1675906Y1578460I-1J202D01*
G01Y1579082D01*
G03X1675856Y1579214I-200J0D01*
G02Y1582126I1664J1456D01*
G03X1675906Y1582258I-150J132D01*
G01Y1584200D01*
G03X1675856Y1584332I-200J0D01*
G02Y1587244I1664J1456D01*
G03X1675906Y1587376I-150J132D01*
G01Y1587998D01*
G02X1676109Y1588200I203J-1D01*
G37*
G36*
G01X1710755D02*
X1713575D01*
G02X1713778Y1587998I1J-202D01*
G01Y1587376D01*
G03X1713828Y1587244I200J0D01*
G02Y1584332I-1664J-1456D01*
G03X1713778Y1584200I150J-132D01*
G01Y1582258D01*
G03X1713828Y1582126I200J0D01*
G02Y1579214I-1664J-1456D01*
G03X1713778Y1579082I150J-132D01*
G01Y1578460D01*
G02X1713575Y1578258I-203J1D01*
G01X1710755D01*
G02X1710552Y1578460I-1J202D01*
G01Y1579082D01*
G03X1710502Y1579214I-200J0D01*
G02Y1582126I1664J1456D01*
G03X1710552Y1582258I-150J132D01*
G01Y1584200D01*
G03X1710502Y1584332I-200J0D01*
G02Y1587244I1664J1456D01*
G03X1710552Y1587376I-150J132D01*
G01Y1587998D01*
G02X1710755Y1588200I203J-1D01*
G37*
G36*
G01X108472Y1599224D02*
X111292D01*
G02X111494Y1599021I-1J-203D01*
G01Y1598401D01*
G03X111544Y1598269I200J0D01*
G02Y1595353I-1661J-1458D01*
G03X111494Y1595221I150J-132D01*
G01Y1593283D01*
G03X111544Y1593151I200J0D01*
G02Y1590235I-1661J-1458D01*
G03X111494Y1590103I150J-132D01*
G01Y1589483D01*
G02X111292Y1589280I-202J-1D01*
G01X108472D01*
G02X108270Y1589483I1J203D01*
G01Y1590103D01*
G03X108220Y1590235I-200J0D01*
G02Y1593151I1661J1458D01*
G03X108270Y1593283I-150J132D01*
G01Y1595221D01*
G03X108220Y1595353I-200J0D01*
G02Y1598269I1661J1458D01*
G03X108270Y1598401I-150J132D01*
G01Y1599021D01*
G02X108472Y1599224I202J1D01*
G37*
G36*
G01X125795D02*
X128615D01*
G02X128818Y1599021I0J-203D01*
G01Y1598399D01*
G03X128868Y1598267I200J0D01*
G02Y1595355I-1664J-1456D01*
G03X128818Y1595223I150J-132D01*
G01Y1593281D01*
G03X128868Y1593149I200J0D01*
G02Y1590237I-1664J-1456D01*
G03X128818Y1590105I150J-132D01*
G01Y1589483D01*
G02X128615Y1589280I-203J0D01*
G01X125795D01*
G02X125592Y1589483I0J203D01*
G01Y1590105D01*
G03X125542Y1590237I-200J0D01*
G02Y1593149I1664J1456D01*
G03X125592Y1593281I-150J132D01*
G01Y1595223D01*
G03X125542Y1595355I-200J0D01*
G02Y1598267I1664J1456D01*
G03X125592Y1598399I-150J132D01*
G01Y1599021D01*
G02X125795Y1599224I203J0D01*
G37*
G36*
G01X143118D02*
X145938D01*
G02X146140Y1599021I-1J-203D01*
G01Y1598401D01*
G03X146190Y1598269I200J0D01*
G02Y1595353I-1661J-1458D01*
G03X146140Y1595221I150J-132D01*
G01Y1593283D01*
G03X146190Y1593151I200J0D01*
G02Y1590235I-1661J-1458D01*
G03X146140Y1590103I150J-132D01*
G01Y1589483D01*
G02X145938Y1589280I-202J-1D01*
G01X143118D01*
G02X142916Y1589483I1J203D01*
G01Y1590103D01*
G03X142866Y1590235I-200J0D01*
G02Y1593151I1661J1458D01*
G03X142916Y1593283I-150J132D01*
G01Y1595221D01*
G03X142866Y1595353I-200J0D01*
G02Y1598269I1661J1458D01*
G03X142916Y1598401I-150J132D01*
G01Y1599021D01*
G02X143118Y1599224I202J1D01*
G37*
G36*
G01X160440D02*
X163260D01*
G02X163462Y1599021I-1J-203D01*
G01Y1598401D01*
G03X163512Y1598269I200J0D01*
G02Y1595353I-1661J-1458D01*
G03X163462Y1595221I150J-132D01*
G01Y1593283D01*
G03X163512Y1593151I200J0D01*
G02Y1590235I-1661J-1458D01*
G03X163462Y1590103I150J-132D01*
G01Y1589483D01*
G02X163260Y1589280I-202J-1D01*
G01X160440D01*
G02X160238Y1589483I1J203D01*
G01Y1590103D01*
G03X160188Y1590235I-200J0D01*
G02Y1593151I1661J1458D01*
G03X160238Y1593283I-150J132D01*
G01Y1595221D01*
G03X160188Y1595353I-200J0D01*
G02Y1598269I1661J1458D01*
G03X160238Y1598401I-150J132D01*
G01Y1599021D01*
G02X160440Y1599224I202J1D01*
G37*
G36*
G01X281700D02*
X284520D01*
G02X284722Y1599021I-1J-203D01*
G01Y1598401D01*
G03X284772Y1598269I200J0D01*
G02Y1595353I-1661J-1458D01*
G03X284722Y1595221I150J-132D01*
G01Y1593283D01*
G03X284772Y1593151I200J0D01*
G02Y1590235I-1661J-1458D01*
G03X284722Y1590103I150J-132D01*
G01Y1589483D01*
G02X284520Y1589280I-202J-1D01*
G01X281700D01*
G02X281498Y1589483I1J203D01*
G01Y1590103D01*
G03X281448Y1590235I-200J0D01*
G02Y1593151I1661J1458D01*
G03X281498Y1593283I-150J132D01*
G01Y1595221D01*
G03X281448Y1595353I-200J0D01*
G02Y1598269I1661J1458D01*
G03X281498Y1598401I-150J132D01*
G01Y1599021D01*
G02X281700Y1599224I202J1D01*
G37*
G36*
G01X299023D02*
X301843D01*
G02X302046Y1599021I0J-203D01*
G01Y1598399D01*
G03X302096Y1598267I200J0D01*
G02Y1595355I-1664J-1456D01*
G03X302046Y1595223I150J-132D01*
G01Y1593281D01*
G03X302096Y1593149I200J0D01*
G02Y1590237I-1664J-1456D01*
G03X302046Y1590105I150J-132D01*
G01Y1589483D01*
G02X301843Y1589280I-203J0D01*
G01X299023D01*
G02X298820Y1589483I0J203D01*
G01Y1590105D01*
G03X298770Y1590237I-200J0D01*
G02Y1593149I1664J1456D01*
G03X298820Y1593281I-150J132D01*
G01Y1595223D01*
G03X298770Y1595355I-200J0D01*
G02Y1598267I1664J1456D01*
G03X298820Y1598399I-150J132D01*
G01Y1599021D01*
G02X299023Y1599224I203J0D01*
G37*
G36*
G01X316346D02*
X319166D01*
G02X319368Y1599021I-1J-203D01*
G01Y1598401D01*
G03X319418Y1598269I200J0D01*
G02Y1595353I-1661J-1458D01*
G03X319368Y1595221I150J-132D01*
G01Y1593283D01*
G03X319418Y1593151I200J0D01*
G02Y1590235I-1661J-1458D01*
G03X319368Y1590103I150J-132D01*
G01Y1589483D01*
G02X319166Y1589280I-202J-1D01*
G01X316346D01*
G02X316144Y1589483I1J203D01*
G01Y1590103D01*
G03X316094Y1590235I-200J0D01*
G02Y1593151I1661J1458D01*
G03X316144Y1593283I-150J132D01*
G01Y1595221D01*
G03X316094Y1595353I-200J0D01*
G02Y1598269I1661J1458D01*
G03X316144Y1598401I-150J132D01*
G01Y1599021D01*
G02X316346Y1599224I202J1D01*
G37*
G36*
G01X333668D02*
X336488D01*
G02X336690Y1599021I-1J-203D01*
G01Y1598401D01*
G03X336740Y1598269I200J0D01*
G02Y1595353I-1661J-1458D01*
G03X336690Y1595221I150J-132D01*
G01Y1593283D01*
G03X336740Y1593151I200J0D01*
G02Y1590235I-1661J-1458D01*
G03X336690Y1590103I150J-132D01*
G01Y1589483D01*
G02X336488Y1589280I-202J-1D01*
G01X333668D01*
G02X333466Y1589483I1J203D01*
G01Y1590103D01*
G03X333416Y1590235I-200J0D01*
G02Y1593151I1661J1458D01*
G03X333466Y1593283I-150J132D01*
G01Y1595221D01*
G03X333416Y1595353I-200J0D01*
G02Y1598269I1661J1458D01*
G03X333466Y1598401I-150J132D01*
G01Y1599021D01*
G02X333668Y1599224I202J1D01*
G37*
G36*
G01X628157D02*
X630977D01*
G02X631180Y1599021I0J-203D01*
G01Y1598399D01*
G03X631230Y1598267I200J0D01*
G02Y1595355I-1664J-1456D01*
G03X631180Y1595223I150J-132D01*
G01Y1593281D01*
G03X631230Y1593149I200J0D01*
G02Y1590237I-1664J-1456D01*
G03X631180Y1590105I150J-132D01*
G01Y1589483D01*
G02X630977Y1589280I-203J0D01*
G01X628157D01*
G02X627954Y1589483I0J203D01*
G01Y1590105D01*
G03X627904Y1590237I-200J0D01*
G02Y1593149I1664J1456D01*
G03X627954Y1593281I-150J132D01*
G01Y1595223D01*
G03X627904Y1595355I-200J0D01*
G02Y1598267I1664J1456D01*
G03X627954Y1598399I-150J132D01*
G01Y1599021D01*
G02X628157Y1599224I203J0D01*
G37*
G36*
G01X645480D02*
X648300D01*
G02X648502Y1599021I-1J-203D01*
G01Y1598401D01*
G03X648552Y1598269I200J0D01*
G02Y1595353I-1661J-1458D01*
G03X648502Y1595221I150J-132D01*
G01Y1593283D01*
G03X648552Y1593151I200J0D01*
G02Y1590235I-1661J-1458D01*
G03X648502Y1590103I150J-132D01*
G01Y1589483D01*
G02X648300Y1589280I-202J-1D01*
G01X645480D01*
G02X645278Y1589483I1J203D01*
G01Y1590103D01*
G03X645228Y1590235I-200J0D01*
G02Y1593151I1661J1458D01*
G03X645278Y1593283I-150J132D01*
G01Y1595221D01*
G03X645228Y1595353I-200J0D01*
G02Y1598269I1661J1458D01*
G03X645278Y1598401I-150J132D01*
G01Y1599021D01*
G02X645480Y1599224I202J1D01*
G37*
G36*
G01X662803D02*
X665623D01*
G02X665826Y1599021I0J-203D01*
G01Y1598399D01*
G03X665876Y1598267I200J0D01*
G02Y1595355I-1664J-1456D01*
G03X665826Y1595223I150J-132D01*
G01Y1593281D01*
G03X665876Y1593149I200J0D01*
G02Y1590237I-1664J-1456D01*
G03X665826Y1590105I150J-132D01*
G01Y1589483D01*
G02X665623Y1589280I-203J0D01*
G01X662803D01*
G02X662600Y1589483I0J203D01*
G01Y1590105D01*
G03X662550Y1590237I-200J0D01*
G02Y1593149I1664J1456D01*
G03X662600Y1593281I-150J132D01*
G01Y1595223D01*
G03X662550Y1595355I-200J0D01*
G02Y1598267I1664J1456D01*
G03X662600Y1598399I-150J132D01*
G01Y1599021D01*
G02X662803Y1599224I203J0D01*
G37*
G36*
G01X680125D02*
X682945D01*
G02X683148Y1599021I0J-203D01*
G01Y1598399D01*
G03X683198Y1598267I200J0D01*
G02Y1595355I-1664J-1456D01*
G03X683148Y1595223I150J-132D01*
G01Y1593281D01*
G03X683198Y1593149I200J0D01*
G02Y1590237I-1664J-1456D01*
G03X683148Y1590105I150J-132D01*
G01Y1589483D01*
G02X682945Y1589280I-203J0D01*
G01X680125D01*
G02X679922Y1589483I0J203D01*
G01Y1590105D01*
G03X679872Y1590237I-200J0D01*
G02Y1593149I1664J1456D01*
G03X679922Y1593281I-150J132D01*
G01Y1595223D01*
G03X679872Y1595355I-200J0D01*
G02Y1598267I1664J1456D01*
G03X679922Y1598399I-150J132D01*
G01Y1599021D01*
G02X680125Y1599224I203J0D01*
G37*
G36*
G01X1130440D02*
X1133260D01*
G02X1133462Y1599021I-1J-203D01*
G01Y1598401D01*
G03X1133512Y1598269I200J0D01*
G02Y1595353I-1661J-1458D01*
G03X1133462Y1595221I150J-132D01*
G01Y1593283D01*
G03X1133512Y1593151I200J0D01*
G02Y1590235I-1661J-1458D01*
G03X1133462Y1590103I150J-132D01*
G01Y1589483D01*
G02X1133260Y1589280I-202J-1D01*
G01X1130440D01*
G02X1130238Y1589483I1J203D01*
G01Y1590103D01*
G03X1130188Y1590235I-200J0D01*
G02Y1593151I1661J1458D01*
G03X1130238Y1593283I-150J132D01*
G01Y1595221D01*
G03X1130188Y1595353I-200J0D01*
G02Y1598269I1661J1458D01*
G03X1130238Y1598401I-150J132D01*
G01Y1599021D01*
G02X1130440Y1599224I202J1D01*
G37*
G36*
G01X1147763D02*
X1150583D01*
G02X1150786Y1599021I0J-203D01*
G01Y1598399D01*
G03X1150836Y1598267I200J0D01*
G02Y1595355I-1664J-1456D01*
G03X1150786Y1595223I150J-132D01*
G01Y1593281D01*
G03X1150836Y1593149I200J0D01*
G02Y1590237I-1664J-1456D01*
G03X1150786Y1590105I150J-132D01*
G01Y1589483D01*
G02X1150583Y1589280I-203J0D01*
G01X1147763D01*
G02X1147560Y1589483I0J203D01*
G01Y1590105D01*
G03X1147510Y1590237I-200J0D01*
G02Y1593149I1664J1456D01*
G03X1147560Y1593281I-150J132D01*
G01Y1595223D01*
G03X1147510Y1595355I-200J0D01*
G02Y1598267I1664J1456D01*
G03X1147560Y1598399I-150J132D01*
G01Y1599021D01*
G02X1147763Y1599224I203J0D01*
G37*
G36*
G01X1165086D02*
X1167906D01*
G02X1168108Y1599021I-1J-203D01*
G01Y1598401D01*
G03X1168158Y1598269I200J0D01*
G02Y1595353I-1661J-1458D01*
G03X1168108Y1595221I150J-132D01*
G01Y1593283D01*
G03X1168158Y1593151I200J0D01*
G02Y1590235I-1661J-1458D01*
G03X1168108Y1590103I150J-132D01*
G01Y1589483D01*
G02X1167906Y1589280I-202J-1D01*
G01X1165086D01*
G02X1164884Y1589483I1J203D01*
G01Y1590103D01*
G03X1164834Y1590235I-200J0D01*
G02Y1593151I1661J1458D01*
G03X1164884Y1593283I-150J132D01*
G01Y1595221D01*
G03X1164834Y1595353I-200J0D01*
G02Y1598269I1661J1458D01*
G03X1164884Y1598401I-150J132D01*
G01Y1599021D01*
G02X1165086Y1599224I202J1D01*
G37*
G36*
G01X1182408D02*
X1185228D01*
G02X1185430Y1599021I-1J-203D01*
G01Y1598401D01*
G03X1185480Y1598269I200J0D01*
G02Y1595353I-1661J-1458D01*
G03X1185430Y1595221I150J-132D01*
G01Y1593283D01*
G03X1185480Y1593151I200J0D01*
G02Y1590235I-1661J-1458D01*
G03X1185430Y1590103I150J-132D01*
G01Y1589483D01*
G02X1185228Y1589280I-202J-1D01*
G01X1182408D01*
G02X1182206Y1589483I1J203D01*
G01Y1590103D01*
G03X1182156Y1590235I-200J0D01*
G02Y1593151I1661J1458D01*
G03X1182206Y1593283I-150J132D01*
G01Y1595221D01*
G03X1182156Y1595353I-200J0D01*
G02Y1598269I1661J1458D01*
G03X1182206Y1598401I-150J132D01*
G01Y1599021D01*
G02X1182408Y1599224I202J1D01*
G37*
G36*
G01X1303669D02*
X1306489D01*
G02X1306692Y1599021I0J-203D01*
G01Y1598399D01*
G03X1306742Y1598267I200J0D01*
G02Y1595355I-1664J-1456D01*
G03X1306692Y1595223I150J-132D01*
G01Y1593281D01*
G03X1306742Y1593149I200J0D01*
G02Y1590237I-1664J-1456D01*
G03X1306692Y1590105I150J-132D01*
G01Y1589483D01*
G02X1306489Y1589280I-203J0D01*
G01X1303669D01*
G02X1303466Y1589483I0J203D01*
G01Y1590105D01*
G03X1303416Y1590237I-200J0D01*
G02Y1593149I1664J1456D01*
G03X1303466Y1593281I-150J132D01*
G01Y1595223D01*
G03X1303416Y1595355I-200J0D01*
G02Y1598267I1664J1456D01*
G03X1303466Y1598399I-150J132D01*
G01Y1599021D01*
G02X1303669Y1599224I203J0D01*
G37*
G36*
G01X1320992D02*
X1323812D01*
G02X1324014Y1599021I-1J-203D01*
G01Y1598401D01*
G03X1324064Y1598269I200J0D01*
G02Y1595353I-1661J-1458D01*
G03X1324014Y1595221I150J-132D01*
G01Y1593283D01*
G03X1324064Y1593151I200J0D01*
G02Y1590235I-1661J-1458D01*
G03X1324014Y1590103I150J-132D01*
G01Y1589483D01*
G02X1323812Y1589280I-202J-1D01*
G01X1320992D01*
G02X1320790Y1589483I1J203D01*
G01Y1590103D01*
G03X1320740Y1590235I-200J0D01*
G02Y1593151I1661J1458D01*
G03X1320790Y1593283I-150J132D01*
G01Y1595221D01*
G03X1320740Y1595353I-200J0D01*
G02Y1598269I1661J1458D01*
G03X1320790Y1598401I-150J132D01*
G01Y1599021D01*
G02X1320992Y1599224I202J1D01*
G37*
G36*
G01X1338315D02*
X1341135D01*
G02X1341338Y1599021I0J-203D01*
G01Y1598399D01*
G03X1341388Y1598267I200J0D01*
G02Y1595355I-1664J-1456D01*
G03X1341338Y1595223I150J-132D01*
G01Y1593281D01*
G03X1341388Y1593149I200J0D01*
G02Y1590237I-1664J-1456D01*
G03X1341338Y1590105I150J-132D01*
G01Y1589483D01*
G02X1341135Y1589280I-203J0D01*
G01X1338315D01*
G02X1338112Y1589483I0J203D01*
G01Y1590105D01*
G03X1338062Y1590237I-200J0D01*
G02Y1593149I1664J1456D01*
G03X1338112Y1593281I-150J132D01*
G01Y1595223D01*
G03X1338062Y1595355I-200J0D01*
G02Y1598267I1664J1456D01*
G03X1338112Y1598399I-150J132D01*
G01Y1599021D01*
G02X1338315Y1599224I203J0D01*
G37*
G36*
G01X1355637D02*
X1358457D01*
G02X1358660Y1599021I0J-203D01*
G01Y1598399D01*
G03X1358710Y1598267I200J0D01*
G02Y1595355I-1664J-1456D01*
G03X1358660Y1595223I150J-132D01*
G01Y1593281D01*
G03X1358710Y1593149I200J0D01*
G02Y1590237I-1664J-1456D01*
G03X1358660Y1590105I150J-132D01*
G01Y1589483D01*
G02X1358457Y1589280I-203J0D01*
G01X1355637D01*
G02X1355434Y1589483I0J203D01*
G01Y1590105D01*
G03X1355384Y1590237I-200J0D01*
G02Y1593149I1664J1456D01*
G03X1355434Y1593281I-150J132D01*
G01Y1595223D01*
G03X1355384Y1595355I-200J0D01*
G02Y1598267I1664J1456D01*
G03X1355434Y1598399I-150J132D01*
G01Y1599021D01*
G02X1355637Y1599224I203J0D01*
G37*
G36*
G01X1476897D02*
X1479717D01*
G02X1479920Y1599021I0J-203D01*
G01Y1598399D01*
G03X1479970Y1598267I200J0D01*
G02Y1595355I-1664J-1456D01*
G03X1479920Y1595223I150J-132D01*
G01Y1593281D01*
G03X1479970Y1593149I200J0D01*
G02Y1590237I-1664J-1456D01*
G03X1479920Y1590105I150J-132D01*
G01Y1589483D01*
G02X1479717Y1589280I-203J0D01*
G01X1476897D01*
G02X1476694Y1589483I0J203D01*
G01Y1590105D01*
G03X1476644Y1590237I-200J0D01*
G02Y1593149I1664J1456D01*
G03X1476694Y1593281I-150J132D01*
G01Y1595223D01*
G03X1476644Y1595355I-200J0D01*
G02Y1598267I1664J1456D01*
G03X1476694Y1598399I-150J132D01*
G01Y1599021D01*
G02X1476897Y1599224I203J0D01*
G37*
G36*
G01X1650125D02*
X1652945D01*
G02X1653148Y1599021I0J-203D01*
G01Y1598399D01*
G03X1653198Y1598267I200J0D01*
G02Y1595355I-1664J-1456D01*
G03X1653148Y1595223I150J-132D01*
G01Y1593281D01*
G03X1653198Y1593149I200J0D01*
G02Y1590237I-1664J-1456D01*
G03X1653148Y1590105I150J-132D01*
G01Y1589483D01*
G02X1652945Y1589280I-203J0D01*
G01X1650125D01*
G02X1649922Y1589483I0J203D01*
G01Y1590105D01*
G03X1649872Y1590237I-200J0D01*
G02Y1593149I1664J1456D01*
G03X1649922Y1593281I-150J132D01*
G01Y1595223D01*
G03X1649872Y1595355I-200J0D01*
G02Y1598267I1664J1456D01*
G03X1649922Y1598399I-150J132D01*
G01Y1599021D01*
G02X1650125Y1599224I203J0D01*
G37*
G36*
G01X1667448D02*
X1670268D01*
G02X1670470Y1599021I-1J-203D01*
G01Y1598401D01*
G03X1670520Y1598269I200J0D01*
G02Y1595353I-1661J-1458D01*
G03X1670470Y1595221I150J-132D01*
G01Y1593283D01*
G03X1670520Y1593151I200J0D01*
G02Y1590235I-1661J-1458D01*
G03X1670470Y1590103I150J-132D01*
G01Y1589483D01*
G02X1670268Y1589280I-202J-1D01*
G01X1667448D01*
G02X1667246Y1589483I1J203D01*
G01Y1590103D01*
G03X1667196Y1590235I-200J0D01*
G02Y1593151I1661J1458D01*
G03X1667246Y1593283I-150J132D01*
G01Y1595221D01*
G03X1667196Y1595353I-200J0D01*
G02Y1598269I1661J1458D01*
G03X1667246Y1598401I-150J132D01*
G01Y1599021D01*
G02X1667448Y1599224I202J1D01*
G37*
G36*
G01X1684771D02*
X1687591D01*
G02X1687794Y1599021I0J-203D01*
G01Y1598399D01*
G03X1687844Y1598267I200J0D01*
G02Y1595355I-1664J-1456D01*
G03X1687794Y1595223I150J-132D01*
G01Y1593281D01*
G03X1687844Y1593149I200J0D01*
G02Y1590237I-1664J-1456D01*
G03X1687794Y1590105I150J-132D01*
G01Y1589483D01*
G02X1687591Y1589280I-203J0D01*
G01X1684771D01*
G02X1684568Y1589483I0J203D01*
G01Y1590105D01*
G03X1684518Y1590237I-200J0D01*
G02Y1593149I1664J1456D01*
G03X1684568Y1593281I-150J132D01*
G01Y1595223D01*
G03X1684518Y1595355I-200J0D01*
G02Y1598267I1664J1456D01*
G03X1684568Y1598399I-150J132D01*
G01Y1599021D01*
G02X1684771Y1599224I203J0D01*
G37*
G36*
G01X1702093D02*
X1704913D01*
G02X1705116Y1599021I0J-203D01*
G01Y1598399D01*
G03X1705166Y1598267I200J0D01*
G02Y1595355I-1664J-1456D01*
G03X1705116Y1595223I150J-132D01*
G01Y1593281D01*
G03X1705166Y1593149I200J0D01*
G02Y1590237I-1664J-1456D01*
G03X1705116Y1590105I150J-132D01*
G01Y1589483D01*
G02X1704913Y1589280I-203J0D01*
G01X1702093D01*
G02X1701890Y1589483I0J203D01*
G01Y1590105D01*
G03X1701840Y1590237I-200J0D01*
G02Y1593149I1664J1456D01*
G03X1701890Y1593281I-150J132D01*
G01Y1595223D01*
G03X1701840Y1595355I-200J0D01*
G02Y1598267I1664J1456D01*
G03X1701890Y1598399I-150J132D01*
G01Y1599021D01*
G02X1702093Y1599224I203J0D01*
G37*
G36*
G01X134456Y1603554D02*
X137276D01*
G02X137478Y1603352I0J-202D01*
G01Y1602732D01*
G03X137528Y1602600I200J0D01*
G02Y1599684I-1661J-1458D01*
G03X137478Y1599552I150J-132D01*
G01Y1597614D01*
G03X137528Y1597482I200J0D01*
G02Y1594566I-1661J-1458D01*
G03X137478Y1594434I150J-132D01*
G01Y1593814D01*
G02X137276Y1593612I-202J0D01*
G01X134456D01*
G02X134254Y1593814I0J202D01*
G01Y1594434D01*
G03X134204Y1594566I-200J0D01*
G02Y1597482I1661J1458D01*
G03X134254Y1597614I-150J132D01*
G01Y1599552D01*
G03X134204Y1599684I-200J0D01*
G02Y1602600I1661J1458D01*
G03X134254Y1602732I-150J132D01*
G01Y1603352D01*
G02X134456Y1603554I202J0D01*
G37*
G36*
G01X169102D02*
X171922D01*
G02X172124Y1603352I0J-202D01*
G01Y1602732D01*
G03X172174Y1602600I200J0D01*
G02Y1599684I-1661J-1458D01*
G03X172124Y1599552I150J-132D01*
G01Y1597614D01*
G03X172174Y1597482I200J0D01*
G02Y1594566I-1661J-1458D01*
G03X172124Y1594434I150J-132D01*
G01Y1593814D01*
G02X171922Y1593612I-202J0D01*
G01X169102D01*
G02X168900Y1593814I0J202D01*
G01Y1594434D01*
G03X168850Y1594566I-200J0D01*
G02Y1597482I1661J1458D01*
G03X168900Y1597614I-150J132D01*
G01Y1599552D01*
G03X168850Y1599684I-200J0D01*
G02Y1602600I1661J1458D01*
G03X168900Y1602732I-150J132D01*
G01Y1603352D01*
G02X169102Y1603554I202J0D01*
G37*
G36*
G01X307684D02*
X310504D01*
G02X310706Y1603352I0J-202D01*
G01Y1602732D01*
G03X310756Y1602600I200J0D01*
G02Y1599684I-1661J-1458D01*
G03X310706Y1599552I150J-132D01*
G01Y1597614D01*
G03X310756Y1597482I200J0D01*
G02Y1594566I-1661J-1458D01*
G03X310706Y1594434I150J-132D01*
G01Y1593814D01*
G02X310504Y1593612I-202J0D01*
G01X307684D01*
G02X307482Y1593814I0J202D01*
G01Y1594434D01*
G03X307432Y1594566I-200J0D01*
G02Y1597482I1661J1458D01*
G03X307482Y1597614I-150J132D01*
G01Y1599552D01*
G03X307432Y1599684I-200J0D01*
G02Y1602600I1661J1458D01*
G03X307482Y1602732I-150J132D01*
G01Y1603352D01*
G02X307684Y1603554I202J0D01*
G37*
G36*
G01X342330D02*
X345150D01*
G02X345352Y1603352I0J-202D01*
G01Y1602732D01*
G03X345402Y1602600I200J0D01*
G02Y1599684I-1661J-1458D01*
G03X345352Y1599552I150J-132D01*
G01Y1597614D01*
G03X345402Y1597482I200J0D01*
G02Y1594566I-1661J-1458D01*
G03X345352Y1594434I150J-132D01*
G01Y1593814D01*
G02X345150Y1593612I-202J0D01*
G01X342330D01*
G02X342128Y1593814I0J202D01*
G01Y1594434D01*
G03X342078Y1594566I-200J0D01*
G02Y1597482I1661J1458D01*
G03X342128Y1597614I-150J132D01*
G01Y1599552D01*
G03X342078Y1599684I-200J0D01*
G02Y1602600I1661J1458D01*
G03X342128Y1602732I-150J132D01*
G01Y1603352D01*
G02X342330Y1603554I202J0D01*
G37*
G36*
G01X636818D02*
X639638D01*
G02X639840Y1603352I0J-202D01*
G01Y1602732D01*
G03X639890Y1602600I200J0D01*
G02Y1599684I-1661J-1458D01*
G03X639840Y1599552I150J-132D01*
G01Y1597614D01*
G03X639890Y1597482I200J0D01*
G02Y1594566I-1661J-1458D01*
G03X639840Y1594434I150J-132D01*
G01Y1593814D01*
G02X639638Y1593612I-202J0D01*
G01X636818D01*
G02X636616Y1593814I0J202D01*
G01Y1594434D01*
G03X636566Y1594566I-200J0D01*
G02Y1597482I1661J1458D01*
G03X636616Y1597614I-150J132D01*
G01Y1599552D01*
G03X636566Y1599684I-200J0D01*
G02Y1602600I1661J1458D01*
G03X636616Y1602732I-150J132D01*
G01Y1603352D01*
G02X636818Y1603554I202J0D01*
G37*
G36*
G01X671464D02*
X674284D01*
G02X674486Y1603352I0J-202D01*
G01Y1602732D01*
G03X674536Y1602600I200J0D01*
G02Y1599684I-1661J-1458D01*
G03X674486Y1599552I150J-132D01*
G01Y1597614D01*
G03X674536Y1597482I200J0D01*
G02Y1594566I-1661J-1458D01*
G03X674486Y1594434I150J-132D01*
G01Y1593814D01*
G02X674284Y1593612I-202J0D01*
G01X671464D01*
G02X671262Y1593814I0J202D01*
G01Y1594434D01*
G03X671212Y1594566I-200J0D01*
G02Y1597482I1661J1458D01*
G03X671262Y1597614I-150J132D01*
G01Y1599552D01*
G03X671212Y1599684I-200J0D01*
G02Y1602600I1661J1458D01*
G03X671262Y1602732I-150J132D01*
G01Y1603352D01*
G02X671464Y1603554I202J0D01*
G37*
G36*
G01X1156424D02*
X1159244D01*
G02X1159446Y1603352I0J-202D01*
G01Y1602732D01*
G03X1159496Y1602600I200J0D01*
G02Y1599684I-1661J-1458D01*
G03X1159446Y1599552I150J-132D01*
G01Y1597614D01*
G03X1159496Y1597482I200J0D01*
G02Y1594566I-1661J-1458D01*
G03X1159446Y1594434I150J-132D01*
G01Y1593814D01*
G02X1159244Y1593612I-202J0D01*
G01X1156424D01*
G02X1156222Y1593814I0J202D01*
G01Y1594434D01*
G03X1156172Y1594566I-200J0D01*
G02Y1597482I1661J1458D01*
G03X1156222Y1597614I-150J132D01*
G01Y1599552D01*
G03X1156172Y1599684I-200J0D01*
G02Y1602600I1661J1458D01*
G03X1156222Y1602732I-150J132D01*
G01Y1603352D01*
G02X1156424Y1603554I202J0D01*
G37*
G36*
G01X1191070D02*
X1193890D01*
G02X1194092Y1603352I0J-202D01*
G01Y1602732D01*
G03X1194142Y1602600I200J0D01*
G02Y1599684I-1661J-1458D01*
G03X1194092Y1599552I150J-132D01*
G01Y1597614D01*
G03X1194142Y1597482I200J0D01*
G02Y1594566I-1661J-1458D01*
G03X1194092Y1594434I150J-132D01*
G01Y1593814D01*
G02X1193890Y1593612I-202J0D01*
G01X1191070D01*
G02X1190868Y1593814I0J202D01*
G01Y1594434D01*
G03X1190818Y1594566I-200J0D01*
G02Y1597482I1661J1458D01*
G03X1190868Y1597614I-150J132D01*
G01Y1599552D01*
G03X1190818Y1599684I-200J0D01*
G02Y1602600I1661J1458D01*
G03X1190868Y1602732I-150J132D01*
G01Y1603352D01*
G02X1191070Y1603554I202J0D01*
G37*
G36*
G01X1312330D02*
X1315150D01*
G02X1315352Y1603352I0J-202D01*
G01Y1602732D01*
G03X1315402Y1602600I200J0D01*
G02Y1599684I-1661J-1458D01*
G03X1315352Y1599552I150J-132D01*
G01Y1597614D01*
G03X1315402Y1597482I200J0D01*
G02Y1594566I-1661J-1458D01*
G03X1315352Y1594434I150J-132D01*
G01Y1593814D01*
G02X1315150Y1593612I-202J0D01*
G01X1312330D01*
G02X1312128Y1593814I0J202D01*
G01Y1594434D01*
G03X1312078Y1594566I-200J0D01*
G02Y1597482I1661J1458D01*
G03X1312128Y1597614I-150J132D01*
G01Y1599552D01*
G03X1312078Y1599684I-200J0D01*
G02Y1602600I1661J1458D01*
G03X1312128Y1602732I-150J132D01*
G01Y1603352D01*
G02X1312330Y1603554I202J0D01*
G37*
G36*
G01X1346976D02*
X1349796D01*
G02X1349998Y1603352I0J-202D01*
G01Y1602732D01*
G03X1350048Y1602600I200J0D01*
G02Y1599684I-1661J-1458D01*
G03X1349998Y1599552I150J-132D01*
G01Y1597614D01*
G03X1350048Y1597482I200J0D01*
G02Y1594566I-1661J-1458D01*
G03X1349998Y1594434I150J-132D01*
G01Y1593814D01*
G02X1349796Y1593612I-202J0D01*
G01X1346976D01*
G02X1346774Y1593814I0J202D01*
G01Y1594434D01*
G03X1346724Y1594566I-200J0D01*
G02Y1597482I1661J1458D01*
G03X1346774Y1597614I-150J132D01*
G01Y1599552D01*
G03X1346724Y1599684I-200J0D01*
G02Y1602600I1661J1458D01*
G03X1346774Y1602732I-150J132D01*
G01Y1603352D01*
G02X1346976Y1603554I202J0D01*
G37*
G36*
G01X1658786D02*
X1661606D01*
G02X1661808Y1603352I0J-202D01*
G01Y1602732D01*
G03X1661858Y1602600I200J0D01*
G02Y1599684I-1661J-1458D01*
G03X1661808Y1599552I150J-132D01*
G01Y1597614D01*
G03X1661858Y1597482I200J0D01*
G02Y1594566I-1661J-1458D01*
G03X1661808Y1594434I150J-132D01*
G01Y1593814D01*
G02X1661606Y1593612I-202J0D01*
G01X1658786D01*
G02X1658584Y1593814I0J202D01*
G01Y1594434D01*
G03X1658534Y1594566I-200J0D01*
G02Y1597482I1661J1458D01*
G03X1658584Y1597614I-150J132D01*
G01Y1599552D01*
G03X1658534Y1599684I-200J0D01*
G02Y1602600I1661J1458D01*
G03X1658584Y1602732I-150J132D01*
G01Y1603352D01*
G02X1658786Y1603554I202J0D01*
G37*
G36*
G01X1693432D02*
X1696252D01*
G02X1696454Y1603352I0J-202D01*
G01Y1602732D01*
G03X1696504Y1602600I200J0D01*
G02Y1599684I-1661J-1458D01*
G03X1696454Y1599552I150J-132D01*
G01Y1597614D01*
G03X1696504Y1597482I200J0D01*
G02Y1594566I-1661J-1458D01*
G03X1696454Y1594434I150J-132D01*
G01Y1593814D01*
G02X1696252Y1593612I-202J0D01*
G01X1693432D01*
G02X1693230Y1593814I0J202D01*
G01Y1594434D01*
G03X1693180Y1594566I-200J0D01*
G02Y1597482I1661J1458D01*
G03X1693230Y1597614I-150J132D01*
G01Y1599552D01*
G03X1693180Y1599684I-200J0D01*
G02Y1602600I1661J1458D01*
G03X1693230Y1602732I-150J132D01*
G01Y1603352D01*
G02X1693432Y1603554I202J0D01*
G37*
G36*
G01X117133D02*
X119953D01*
G02X120156Y1603352I1J-202D01*
G01Y1602730D01*
G03X120206Y1602598I200J0D01*
G02Y1599686I-1664J-1456D01*
G03X120156Y1599554I150J-132D01*
G01Y1597612D01*
G03X120206Y1597480I200J0D01*
G02Y1594568I-1664J-1456D01*
G03X120156Y1594436I150J-132D01*
G01Y1593814D01*
G02X119953Y1593612I-203J1D01*
G01X117133D01*
G02X116930Y1593814I-1J202D01*
G01Y1594436D01*
G03X116880Y1594568I-200J0D01*
G02Y1597480I1664J1456D01*
G03X116930Y1597612I-150J132D01*
G01Y1599554D01*
G03X116880Y1599686I-200J0D01*
G02Y1602598I1664J1456D01*
G03X116930Y1602730I-150J132D01*
G01Y1603352D01*
G02X117133Y1603554I203J-1D01*
G37*
G36*
G01X151779D02*
X154599D01*
G02X154802Y1603352I1J-202D01*
G01Y1602730D01*
G03X154852Y1602598I200J0D01*
G02Y1599686I-1664J-1456D01*
G03X154802Y1599554I150J-132D01*
G01Y1597612D01*
G03X154852Y1597480I200J0D01*
G02Y1594568I-1664J-1456D01*
G03X154802Y1594436I150J-132D01*
G01Y1593814D01*
G02X154599Y1593612I-203J1D01*
G01X151779D01*
G02X151576Y1593814I-1J202D01*
G01Y1594436D01*
G03X151526Y1594568I-200J0D01*
G02Y1597480I1664J1456D01*
G03X151576Y1597612I-150J132D01*
G01Y1599554D01*
G03X151526Y1599686I-200J0D01*
G02Y1602598I1664J1456D01*
G03X151576Y1602730I-150J132D01*
G01Y1603352D01*
G02X151779Y1603554I203J-1D01*
G37*
G36*
G01X186425D02*
X189245D01*
G02X189448Y1603352I1J-202D01*
G01Y1602730D01*
G03X189498Y1602598I200J0D01*
G02Y1599686I-1664J-1456D01*
G03X189448Y1599554I150J-132D01*
G01Y1597612D01*
G03X189498Y1597480I200J0D01*
G02Y1594568I-1664J-1456D01*
G03X189448Y1594436I150J-132D01*
G01Y1593814D01*
G02X189245Y1593612I-203J1D01*
G01X186425D01*
G02X186222Y1593814I-1J202D01*
G01Y1594436D01*
G03X186172Y1594568I-200J0D01*
G02Y1597480I1664J1456D01*
G03X186222Y1597612I-150J132D01*
G01Y1599554D01*
G03X186172Y1599686I-200J0D01*
G02Y1602598I1664J1456D01*
G03X186222Y1602730I-150J132D01*
G01Y1603352D01*
G02X186425Y1603554I203J-1D01*
G37*
G36*
G01X290361D02*
X293181D01*
G02X293384Y1603352I1J-202D01*
G01Y1602730D01*
G03X293434Y1602598I200J0D01*
G02Y1599686I-1664J-1456D01*
G03X293384Y1599554I150J-132D01*
G01Y1597612D01*
G03X293434Y1597480I200J0D01*
G02Y1594568I-1664J-1456D01*
G03X293384Y1594436I150J-132D01*
G01Y1593814D01*
G02X293181Y1593612I-203J1D01*
G01X290361D01*
G02X290158Y1593814I-1J202D01*
G01Y1594436D01*
G03X290108Y1594568I-200J0D01*
G02Y1597480I1664J1456D01*
G03X290158Y1597612I-150J132D01*
G01Y1599554D01*
G03X290108Y1599686I-200J0D01*
G02Y1602598I1664J1456D01*
G03X290158Y1602730I-150J132D01*
G01Y1603352D01*
G02X290361Y1603554I203J-1D01*
G37*
G36*
G01X325007D02*
X327827D01*
G02X328030Y1603352I1J-202D01*
G01Y1602730D01*
G03X328080Y1602598I200J0D01*
G02Y1599686I-1664J-1456D01*
G03X328030Y1599554I150J-132D01*
G01Y1597612D01*
G03X328080Y1597480I200J0D01*
G02Y1594568I-1664J-1456D01*
G03X328030Y1594436I150J-132D01*
G01Y1593814D01*
G02X327827Y1593612I-203J1D01*
G01X325007D01*
G02X324804Y1593814I-1J202D01*
G01Y1594436D01*
G03X324754Y1594568I-200J0D01*
G02Y1597480I1664J1456D01*
G03X324804Y1597612I-150J132D01*
G01Y1599554D01*
G03X324754Y1599686I-200J0D01*
G02Y1602598I1664J1456D01*
G03X324804Y1602730I-150J132D01*
G01Y1603352D01*
G02X325007Y1603554I203J-1D01*
G37*
G36*
G01X359653D02*
X362473D01*
G02X362676Y1603352I1J-202D01*
G01Y1602730D01*
G03X362726Y1602598I200J0D01*
G02Y1599686I-1664J-1456D01*
G03X362676Y1599554I150J-132D01*
G01Y1597612D01*
G03X362726Y1597480I200J0D01*
G02Y1594568I-1664J-1456D01*
G03X362676Y1594436I150J-132D01*
G01Y1593814D01*
G02X362473Y1593612I-203J1D01*
G01X359653D01*
G02X359450Y1593814I-1J202D01*
G01Y1594436D01*
G03X359400Y1594568I-200J0D01*
G02Y1597480I1664J1456D01*
G03X359450Y1597612I-150J132D01*
G01Y1599554D01*
G03X359400Y1599686I-200J0D01*
G02Y1602598I1664J1456D01*
G03X359450Y1602730I-150J132D01*
G01Y1603352D01*
G02X359653Y1603554I203J-1D01*
G37*
G36*
G01X515559D02*
X518379D01*
G02X518582Y1603352I1J-202D01*
G01Y1602730D01*
G03X518632Y1602598I200J0D01*
G02Y1599686I-1664J-1456D01*
G03X518582Y1599554I150J-132D01*
G01Y1597612D01*
G03X518632Y1597480I200J0D01*
G02Y1594568I-1664J-1456D01*
G03X518582Y1594436I150J-132D01*
G01Y1593814D01*
G02X518379Y1593612I-203J1D01*
G01X515559D01*
G02X515356Y1593814I-1J202D01*
G01Y1594436D01*
G03X515306Y1594568I-200J0D01*
G02Y1597480I1664J1456D01*
G03X515356Y1597612I-150J132D01*
G01Y1599554D01*
G03X515306Y1599686I-200J0D01*
G02Y1602598I1664J1456D01*
G03X515356Y1602730I-150J132D01*
G01Y1603352D01*
G02X515559Y1603554I203J-1D01*
G37*
G36*
G01X654141D02*
X656961D01*
G02X657164Y1603352I1J-202D01*
G01Y1602730D01*
G03X657214Y1602598I200J0D01*
G02Y1599686I-1664J-1456D01*
G03X657164Y1599554I150J-132D01*
G01Y1597612D01*
G03X657214Y1597480I200J0D01*
G02Y1594568I-1664J-1456D01*
G03X657164Y1594436I150J-132D01*
G01Y1593814D01*
G02X656961Y1593612I-203J1D01*
G01X654141D01*
G02X653938Y1593814I-1J202D01*
G01Y1594436D01*
G03X653888Y1594568I-200J0D01*
G02Y1597480I1664J1456D01*
G03X653938Y1597612I-150J132D01*
G01Y1599554D01*
G03X653888Y1599686I-200J0D01*
G02Y1602598I1664J1456D01*
G03X653938Y1602730I-150J132D01*
G01Y1603352D01*
G02X654141Y1603554I203J-1D01*
G37*
G36*
G01X688787D02*
X691607D01*
G02X691810Y1603352I1J-202D01*
G01Y1602730D01*
G03X691860Y1602598I200J0D01*
G02Y1599686I-1664J-1456D01*
G03X691810Y1599554I150J-132D01*
G01Y1597612D01*
G03X691860Y1597480I200J0D01*
G02Y1594568I-1664J-1456D01*
G03X691810Y1594436I150J-132D01*
G01Y1593814D01*
G02X691607Y1593612I-203J1D01*
G01X688787D01*
G02X688584Y1593814I-1J202D01*
G01Y1594436D01*
G03X688534Y1594568I-200J0D01*
G02Y1597480I1664J1456D01*
G03X688584Y1597612I-150J132D01*
G01Y1599554D01*
G03X688534Y1599686I-200J0D01*
G02Y1602598I1664J1456D01*
G03X688584Y1602730I-150J132D01*
G01Y1603352D01*
G02X688787Y1603554I203J-1D01*
G37*
G36*
G01X1139101D02*
X1141921D01*
G02X1142124Y1603352I1J-202D01*
G01Y1602730D01*
G03X1142174Y1602598I200J0D01*
G02Y1599686I-1664J-1456D01*
G03X1142124Y1599554I150J-132D01*
G01Y1597612D01*
G03X1142174Y1597480I200J0D01*
G02Y1594568I-1664J-1456D01*
G03X1142124Y1594436I150J-132D01*
G01Y1593814D01*
G02X1141921Y1593612I-203J1D01*
G01X1139101D01*
G02X1138898Y1593814I-1J202D01*
G01Y1594436D01*
G03X1138848Y1594568I-200J0D01*
G02Y1597480I1664J1456D01*
G03X1138898Y1597612I-150J132D01*
G01Y1599554D01*
G03X1138848Y1599686I-200J0D01*
G02Y1602598I1664J1456D01*
G03X1138898Y1602730I-150J132D01*
G01Y1603352D01*
G02X1139101Y1603554I203J-1D01*
G37*
G36*
G01X1173747D02*
X1176567D01*
G02X1176770Y1603352I1J-202D01*
G01Y1602730D01*
G03X1176820Y1602598I200J0D01*
G02Y1599686I-1664J-1456D01*
G03X1176770Y1599554I150J-132D01*
G01Y1597612D01*
G03X1176820Y1597480I200J0D01*
G02Y1594568I-1664J-1456D01*
G03X1176770Y1594436I150J-132D01*
G01Y1593814D01*
G02X1176567Y1593612I-203J1D01*
G01X1173747D01*
G02X1173544Y1593814I-1J202D01*
G01Y1594436D01*
G03X1173494Y1594568I-200J0D01*
G02Y1597480I1664J1456D01*
G03X1173544Y1597612I-150J132D01*
G01Y1599554D01*
G03X1173494Y1599686I-200J0D01*
G02Y1602598I1664J1456D01*
G03X1173544Y1602730I-150J132D01*
G01Y1603352D01*
G02X1173747Y1603554I203J-1D01*
G37*
G36*
G01X1329653D02*
X1332473D01*
G02X1332676Y1603352I1J-202D01*
G01Y1602730D01*
G03X1332726Y1602598I200J0D01*
G02Y1599686I-1664J-1456D01*
G03X1332676Y1599554I150J-132D01*
G01Y1597612D01*
G03X1332726Y1597480I200J0D01*
G02Y1594568I-1664J-1456D01*
G03X1332676Y1594436I150J-132D01*
G01Y1593814D01*
G02X1332473Y1593612I-203J1D01*
G01X1329653D01*
G02X1329450Y1593814I-1J202D01*
G01Y1594436D01*
G03X1329400Y1594568I-200J0D01*
G02Y1597480I1664J1456D01*
G03X1329450Y1597612I-150J132D01*
G01Y1599554D01*
G03X1329400Y1599686I-200J0D01*
G02Y1602598I1664J1456D01*
G03X1329450Y1602730I-150J132D01*
G01Y1603352D01*
G02X1329653Y1603554I203J-1D01*
G37*
G36*
G01X1364299D02*
X1367119D01*
G02X1367322Y1603352I1J-202D01*
G01Y1602730D01*
G03X1367372Y1602598I200J0D01*
G02Y1599686I-1664J-1456D01*
G03X1367322Y1599554I150J-132D01*
G01Y1597612D01*
G03X1367372Y1597480I200J0D01*
G02Y1594568I-1664J-1456D01*
G03X1367322Y1594436I150J-132D01*
G01Y1593814D01*
G02X1367119Y1593612I-203J1D01*
G01X1364299D01*
G02X1364096Y1593814I-1J202D01*
G01Y1594436D01*
G03X1364046Y1594568I-200J0D01*
G02Y1597480I1664J1456D01*
G03X1364096Y1597612I-150J132D01*
G01Y1599554D01*
G03X1364046Y1599686I-200J0D01*
G02Y1602598I1664J1456D01*
G03X1364096Y1602730I-150J132D01*
G01Y1603352D01*
G02X1364299Y1603554I203J-1D01*
G37*
G36*
G01X1676109D02*
X1678929D01*
G02X1679132Y1603352I1J-202D01*
G01Y1602730D01*
G03X1679182Y1602598I200J0D01*
G02Y1599686I-1664J-1456D01*
G03X1679132Y1599554I150J-132D01*
G01Y1597612D01*
G03X1679182Y1597480I200J0D01*
G02Y1594568I-1664J-1456D01*
G03X1679132Y1594436I150J-132D01*
G01Y1593814D01*
G02X1678929Y1593612I-203J1D01*
G01X1676109D01*
G02X1675906Y1593814I-1J202D01*
G01Y1594436D01*
G03X1675856Y1594568I-200J0D01*
G02Y1597480I1664J1456D01*
G03X1675906Y1597612I-150J132D01*
G01Y1599554D01*
G03X1675856Y1599686I-200J0D01*
G02Y1602598I1664J1456D01*
G03X1675906Y1602730I-150J132D01*
G01Y1603352D01*
G02X1676109Y1603554I203J-1D01*
G37*
G36*
G01X1710755D02*
X1713575D01*
G02X1713778Y1603352I1J-202D01*
G01Y1602730D01*
G03X1713828Y1602598I200J0D01*
G02Y1599686I-1664J-1456D01*
G03X1713778Y1599554I150J-132D01*
G01Y1597612D01*
G03X1713828Y1597480I200J0D01*
G02Y1594568I-1664J-1456D01*
G03X1713778Y1594436I150J-132D01*
G01Y1593814D01*
G02X1713575Y1593612I-203J1D01*
G01X1710755D01*
G02X1710552Y1593814I-1J202D01*
G01Y1594436D01*
G03X1710502Y1594568I-200J0D01*
G02Y1597480I1664J1456D01*
G03X1710552Y1597612I-150J132D01*
G01Y1599554D01*
G03X1710502Y1599686I-200J0D01*
G02Y1602598I1664J1456D01*
G03X1710552Y1602730I-150J132D01*
G01Y1603352D01*
G02X1710755Y1603554I203J-1D01*
G37*
G36*
G01X108472Y1614578D02*
X111292D01*
G02X111494Y1614376I0J-202D01*
G01Y1613756D01*
G03X111544Y1613624I200J0D01*
G02Y1610708I-1661J-1458D01*
G03X111494Y1610576I150J-132D01*
G01Y1608638D01*
G03X111544Y1608506I200J0D01*
G02Y1605590I-1661J-1458D01*
G03X111494Y1605458I150J-132D01*
G01Y1604838D01*
G02X111292Y1604636I-202J0D01*
G01X108472D01*
G02X108270Y1604838I0J202D01*
G01Y1605458D01*
G03X108220Y1605590I-200J0D01*
G02Y1608506I1661J1458D01*
G03X108270Y1608638I-150J132D01*
G01Y1610576D01*
G03X108220Y1610708I-200J0D01*
G02Y1613624I1661J1458D01*
G03X108270Y1613756I-150J132D01*
G01Y1614376D01*
G02X108472Y1614578I202J0D01*
G37*
G36*
G01X143118D02*
X145938D01*
G02X146140Y1614376I0J-202D01*
G01Y1613756D01*
G03X146190Y1613624I200J0D01*
G02Y1610708I-1661J-1458D01*
G03X146140Y1610576I150J-132D01*
G01Y1608638D01*
G03X146190Y1608506I200J0D01*
G02Y1605590I-1661J-1458D01*
G03X146140Y1605458I150J-132D01*
G01Y1604838D01*
G02X145938Y1604636I-202J0D01*
G01X143118D01*
G02X142916Y1604838I0J202D01*
G01Y1605458D01*
G03X142866Y1605590I-200J0D01*
G02Y1608506I1661J1458D01*
G03X142916Y1608638I-150J132D01*
G01Y1610576D01*
G03X142866Y1610708I-200J0D01*
G02Y1613624I1661J1458D01*
G03X142916Y1613756I-150J132D01*
G01Y1614376D01*
G02X143118Y1614578I202J0D01*
G37*
G36*
G01X160440D02*
X163260D01*
G02X163462Y1614376I0J-202D01*
G01Y1613756D01*
G03X163512Y1613624I200J0D01*
G02Y1610708I-1661J-1458D01*
G03X163462Y1610576I150J-132D01*
G01Y1608638D01*
G03X163512Y1608506I200J0D01*
G02Y1605590I-1661J-1458D01*
G03X163462Y1605458I150J-132D01*
G01Y1604838D01*
G02X163260Y1604636I-202J0D01*
G01X160440D01*
G02X160238Y1604838I0J202D01*
G01Y1605458D01*
G03X160188Y1605590I-200J0D01*
G02Y1608506I1661J1458D01*
G03X160238Y1608638I-150J132D01*
G01Y1610576D01*
G03X160188Y1610708I-200J0D01*
G02Y1613624I1661J1458D01*
G03X160238Y1613756I-150J132D01*
G01Y1614376D01*
G02X160440Y1614578I202J0D01*
G37*
G36*
G01X281700D02*
X284520D01*
G02X284722Y1614376I0J-202D01*
G01Y1613756D01*
G03X284772Y1613624I200J0D01*
G02Y1610708I-1661J-1458D01*
G03X284722Y1610576I150J-132D01*
G01Y1608638D01*
G03X284772Y1608506I200J0D01*
G02Y1605590I-1661J-1458D01*
G03X284722Y1605458I150J-132D01*
G01Y1604838D01*
G02X284520Y1604636I-202J0D01*
G01X281700D01*
G02X281498Y1604838I0J202D01*
G01Y1605458D01*
G03X281448Y1605590I-200J0D01*
G02Y1608506I1661J1458D01*
G03X281498Y1608638I-150J132D01*
G01Y1610576D01*
G03X281448Y1610708I-200J0D01*
G02Y1613624I1661J1458D01*
G03X281498Y1613756I-150J132D01*
G01Y1614376D01*
G02X281700Y1614578I202J0D01*
G37*
G36*
G01X316346D02*
X319166D01*
G02X319368Y1614376I0J-202D01*
G01Y1613756D01*
G03X319418Y1613624I200J0D01*
G02Y1610708I-1661J-1458D01*
G03X319368Y1610576I150J-132D01*
G01Y1608638D01*
G03X319418Y1608506I200J0D01*
G02Y1605590I-1661J-1458D01*
G03X319368Y1605458I150J-132D01*
G01Y1604838D01*
G02X319166Y1604636I-202J0D01*
G01X316346D01*
G02X316144Y1604838I0J202D01*
G01Y1605458D01*
G03X316094Y1605590I-200J0D01*
G02Y1608506I1661J1458D01*
G03X316144Y1608638I-150J132D01*
G01Y1610576D01*
G03X316094Y1610708I-200J0D01*
G02Y1613624I1661J1458D01*
G03X316144Y1613756I-150J132D01*
G01Y1614376D01*
G02X316346Y1614578I202J0D01*
G37*
G36*
G01X333668D02*
X336488D01*
G02X336690Y1614376I0J-202D01*
G01Y1613756D01*
G03X336740Y1613624I200J0D01*
G02Y1610708I-1661J-1458D01*
G03X336690Y1610576I150J-132D01*
G01Y1608638D01*
G03X336740Y1608506I200J0D01*
G02Y1605590I-1661J-1458D01*
G03X336690Y1605458I150J-132D01*
G01Y1604838D01*
G02X336488Y1604636I-202J0D01*
G01X333668D01*
G02X333466Y1604838I0J202D01*
G01Y1605458D01*
G03X333416Y1605590I-200J0D01*
G02Y1608506I1661J1458D01*
G03X333466Y1608638I-150J132D01*
G01Y1610576D01*
G03X333416Y1610708I-200J0D01*
G02Y1613624I1661J1458D01*
G03X333466Y1613756I-150J132D01*
G01Y1614376D01*
G02X333668Y1614578I202J0D01*
G37*
G36*
G01X645480D02*
X648300D01*
G02X648502Y1614376I0J-202D01*
G01Y1613756D01*
G03X648552Y1613624I200J0D01*
G02Y1610708I-1661J-1458D01*
G03X648502Y1610576I150J-132D01*
G01Y1608638D01*
G03X648552Y1608506I200J0D01*
G02Y1605590I-1661J-1458D01*
G03X648502Y1605458I150J-132D01*
G01Y1604838D01*
G02X648300Y1604636I-202J0D01*
G01X645480D01*
G02X645278Y1604838I0J202D01*
G01Y1605458D01*
G03X645228Y1605590I-200J0D01*
G02Y1608506I1661J1458D01*
G03X645278Y1608638I-150J132D01*
G01Y1610576D01*
G03X645228Y1610708I-200J0D01*
G02Y1613624I1661J1458D01*
G03X645278Y1613756I-150J132D01*
G01Y1614376D01*
G02X645480Y1614578I202J0D01*
G37*
G36*
G01X1130440D02*
X1133260D01*
G02X1133462Y1614376I0J-202D01*
G01Y1613756D01*
G03X1133512Y1613624I200J0D01*
G02Y1610708I-1661J-1458D01*
G03X1133462Y1610576I150J-132D01*
G01Y1608638D01*
G03X1133512Y1608506I200J0D01*
G02Y1605590I-1661J-1458D01*
G03X1133462Y1605458I150J-132D01*
G01Y1604838D01*
G02X1133260Y1604636I-202J0D01*
G01X1130440D01*
G02X1130238Y1604838I0J202D01*
G01Y1605458D01*
G03X1130188Y1605590I-200J0D01*
G02Y1608506I1661J1458D01*
G03X1130238Y1608638I-150J132D01*
G01Y1610576D01*
G03X1130188Y1610708I-200J0D01*
G02Y1613624I1661J1458D01*
G03X1130238Y1613756I-150J132D01*
G01Y1614376D01*
G02X1130440Y1614578I202J0D01*
G37*
G36*
G01X1165086D02*
X1167906D01*
G02X1168108Y1614376I0J-202D01*
G01Y1613756D01*
G03X1168158Y1613624I200J0D01*
G02Y1610708I-1661J-1458D01*
G03X1168108Y1610576I150J-132D01*
G01Y1608638D01*
G03X1168158Y1608506I200J0D01*
G02Y1605590I-1661J-1458D01*
G03X1168108Y1605458I150J-132D01*
G01Y1604838D01*
G02X1167906Y1604636I-202J0D01*
G01X1165086D01*
G02X1164884Y1604838I0J202D01*
G01Y1605458D01*
G03X1164834Y1605590I-200J0D01*
G02Y1608506I1661J1458D01*
G03X1164884Y1608638I-150J132D01*
G01Y1610576D01*
G03X1164834Y1610708I-200J0D01*
G02Y1613624I1661J1458D01*
G03X1164884Y1613756I-150J132D01*
G01Y1614376D01*
G02X1165086Y1614578I202J0D01*
G37*
G36*
G01X1182408D02*
X1185228D01*
G02X1185430Y1614376I0J-202D01*
G01Y1613756D01*
G03X1185480Y1613624I200J0D01*
G02Y1610708I-1661J-1458D01*
G03X1185430Y1610576I150J-132D01*
G01Y1608638D01*
G03X1185480Y1608506I200J0D01*
G02Y1605590I-1661J-1458D01*
G03X1185430Y1605458I150J-132D01*
G01Y1604838D01*
G02X1185228Y1604636I-202J0D01*
G01X1182408D01*
G02X1182206Y1604838I0J202D01*
G01Y1605458D01*
G03X1182156Y1605590I-200J0D01*
G02Y1608506I1661J1458D01*
G03X1182206Y1608638I-150J132D01*
G01Y1610576D01*
G03X1182156Y1610708I-200J0D01*
G02Y1613624I1661J1458D01*
G03X1182206Y1613756I-150J132D01*
G01Y1614376D01*
G02X1182408Y1614578I202J0D01*
G37*
G36*
G01X1320992D02*
X1323812D01*
G02X1324014Y1614376I0J-202D01*
G01Y1613756D01*
G03X1324064Y1613624I200J0D01*
G02Y1610708I-1661J-1458D01*
G03X1324014Y1610576I150J-132D01*
G01Y1608638D01*
G03X1324064Y1608506I200J0D01*
G02Y1605590I-1661J-1458D01*
G03X1324014Y1605458I150J-132D01*
G01Y1604838D01*
G02X1323812Y1604636I-202J0D01*
G01X1320992D01*
G02X1320790Y1604838I0J202D01*
G01Y1605458D01*
G03X1320740Y1605590I-200J0D01*
G02Y1608506I1661J1458D01*
G03X1320790Y1608638I-150J132D01*
G01Y1610576D01*
G03X1320740Y1610708I-200J0D01*
G02Y1613624I1661J1458D01*
G03X1320790Y1613756I-150J132D01*
G01Y1614376D01*
G02X1320992Y1614578I202J0D01*
G37*
G36*
G01X1667448D02*
X1670268D01*
G02X1670470Y1614376I0J-202D01*
G01Y1613756D01*
G03X1670520Y1613624I200J0D01*
G02Y1610708I-1661J-1458D01*
G03X1670470Y1610576I150J-132D01*
G01Y1608638D01*
G03X1670520Y1608506I200J0D01*
G02Y1605590I-1661J-1458D01*
G03X1670470Y1605458I150J-132D01*
G01Y1604838D01*
G02X1670268Y1604636I-202J0D01*
G01X1667448D01*
G02X1667246Y1604838I0J202D01*
G01Y1605458D01*
G03X1667196Y1605590I-200J0D01*
G02Y1608506I1661J1458D01*
G03X1667246Y1608638I-150J132D01*
G01Y1610576D01*
G03X1667196Y1610708I-200J0D01*
G02Y1613624I1661J1458D01*
G03X1667246Y1613756I-150J132D01*
G01Y1614376D01*
G02X1667448Y1614578I202J0D01*
G37*
G36*
G01X125795D02*
X128615D01*
G02X128818Y1614376I1J-202D01*
G01Y1613754D01*
G03X128868Y1613622I200J0D01*
G02Y1610710I-1664J-1456D01*
G03X128818Y1610578I150J-132D01*
G01Y1608636D01*
G03X128868Y1608504I200J0D01*
G02Y1605592I-1664J-1456D01*
G03X128818Y1605460I150J-132D01*
G01Y1604838D01*
G02X128615Y1604636I-203J1D01*
G01X125795D01*
G02X125592Y1604838I-1J202D01*
G01Y1605460D01*
G03X125542Y1605592I-200J0D01*
G02Y1608504I1664J1456D01*
G03X125592Y1608636I-150J132D01*
G01Y1610578D01*
G03X125542Y1610710I-200J0D01*
G02Y1613622I1664J1456D01*
G03X125592Y1613754I-150J132D01*
G01Y1614376D01*
G02X125795Y1614578I203J-1D01*
G37*
G36*
G01X299023D02*
X301843D01*
G02X302046Y1614376I1J-202D01*
G01Y1613754D01*
G03X302096Y1613622I200J0D01*
G02Y1610710I-1664J-1456D01*
G03X302046Y1610578I150J-132D01*
G01Y1608636D01*
G03X302096Y1608504I200J0D01*
G02Y1605592I-1664J-1456D01*
G03X302046Y1605460I150J-132D01*
G01Y1604838D01*
G02X301843Y1604636I-203J1D01*
G01X299023D01*
G02X298820Y1604838I-1J202D01*
G01Y1605460D01*
G03X298770Y1605592I-200J0D01*
G02Y1608504I1664J1456D01*
G03X298820Y1608636I-150J132D01*
G01Y1610578D01*
G03X298770Y1610710I-200J0D01*
G02Y1613622I1664J1456D01*
G03X298820Y1613754I-150J132D01*
G01Y1614376D01*
G02X299023Y1614578I203J-1D01*
G37*
G36*
G01X628157D02*
X630977D01*
G02X631180Y1614376I1J-202D01*
G01Y1613754D01*
G03X631230Y1613622I200J0D01*
G02Y1610710I-1664J-1456D01*
G03X631180Y1610578I150J-132D01*
G01Y1608636D01*
G03X631230Y1608504I200J0D01*
G02Y1605592I-1664J-1456D01*
G03X631180Y1605460I150J-132D01*
G01Y1604838D01*
G02X630977Y1604636I-203J1D01*
G01X628157D01*
G02X627954Y1604838I-1J202D01*
G01Y1605460D01*
G03X627904Y1605592I-200J0D01*
G02Y1608504I1664J1456D01*
G03X627954Y1608636I-150J132D01*
G01Y1610578D01*
G03X627904Y1610710I-200J0D01*
G02Y1613622I1664J1456D01*
G03X627954Y1613754I-150J132D01*
G01Y1614376D01*
G02X628157Y1614578I203J-1D01*
G37*
G36*
G01X662803D02*
X665623D01*
G02X665826Y1614376I1J-202D01*
G01Y1613754D01*
G03X665876Y1613622I200J0D01*
G02Y1610710I-1664J-1456D01*
G03X665826Y1610578I150J-132D01*
G01Y1608636D01*
G03X665876Y1608504I200J0D01*
G02Y1605592I-1664J-1456D01*
G03X665826Y1605460I150J-132D01*
G01Y1604838D01*
G02X665623Y1604636I-203J1D01*
G01X662803D01*
G02X662600Y1604838I-1J202D01*
G01Y1605460D01*
G03X662550Y1605592I-200J0D01*
G02Y1608504I1664J1456D01*
G03X662600Y1608636I-150J132D01*
G01Y1610578D01*
G03X662550Y1610710I-200J0D01*
G02Y1613622I1664J1456D01*
G03X662600Y1613754I-150J132D01*
G01Y1614376D01*
G02X662803Y1614578I203J-1D01*
G37*
G36*
G01X680125D02*
X682945D01*
G02X683148Y1614376I1J-202D01*
G01Y1613754D01*
G03X683198Y1613622I200J0D01*
G02Y1610710I-1664J-1456D01*
G03X683148Y1610578I150J-132D01*
G01Y1608636D01*
G03X683198Y1608504I200J0D01*
G02Y1605592I-1664J-1456D01*
G03X683148Y1605460I150J-132D01*
G01Y1604838D01*
G02X682945Y1604636I-203J1D01*
G01X680125D01*
G02X679922Y1604838I-1J202D01*
G01Y1605460D01*
G03X679872Y1605592I-200J0D01*
G02Y1608504I1664J1456D01*
G03X679922Y1608636I-150J132D01*
G01Y1610578D01*
G03X679872Y1610710I-200J0D01*
G02Y1613622I1664J1456D01*
G03X679922Y1613754I-150J132D01*
G01Y1614376D01*
G02X680125Y1614578I203J-1D01*
G37*
G36*
G01X1147763D02*
X1150583D01*
G02X1150786Y1614376I1J-202D01*
G01Y1613754D01*
G03X1150836Y1613622I200J0D01*
G02Y1610710I-1664J-1456D01*
G03X1150786Y1610578I150J-132D01*
G01Y1608636D01*
G03X1150836Y1608504I200J0D01*
G02Y1605592I-1664J-1456D01*
G03X1150786Y1605460I150J-132D01*
G01Y1604838D01*
G02X1150583Y1604636I-203J1D01*
G01X1147763D01*
G02X1147560Y1604838I-1J202D01*
G01Y1605460D01*
G03X1147510Y1605592I-200J0D01*
G02Y1608504I1664J1456D01*
G03X1147560Y1608636I-150J132D01*
G01Y1610578D01*
G03X1147510Y1610710I-200J0D01*
G02Y1613622I1664J1456D01*
G03X1147560Y1613754I-150J132D01*
G01Y1614376D01*
G02X1147763Y1614578I203J-1D01*
G37*
G36*
G01X1303669D02*
X1306489D01*
G02X1306692Y1614376I1J-202D01*
G01Y1613754D01*
G03X1306742Y1613622I200J0D01*
G02Y1610710I-1664J-1456D01*
G03X1306692Y1610578I150J-132D01*
G01Y1608636D01*
G03X1306742Y1608504I200J0D01*
G02Y1605592I-1664J-1456D01*
G03X1306692Y1605460I150J-132D01*
G01Y1604838D01*
G02X1306489Y1604636I-203J1D01*
G01X1303669D01*
G02X1303466Y1604838I-1J202D01*
G01Y1605460D01*
G03X1303416Y1605592I-200J0D01*
G02Y1608504I1664J1456D01*
G03X1303466Y1608636I-150J132D01*
G01Y1610578D01*
G03X1303416Y1610710I-200J0D01*
G02Y1613622I1664J1456D01*
G03X1303466Y1613754I-150J132D01*
G01Y1614376D01*
G02X1303669Y1614578I203J-1D01*
G37*
G36*
G01X1338315D02*
X1341135D01*
G02X1341338Y1614376I1J-202D01*
G01Y1613754D01*
G03X1341388Y1613622I200J0D01*
G02Y1610710I-1664J-1456D01*
G03X1341338Y1610578I150J-132D01*
G01Y1608636D01*
G03X1341388Y1608504I200J0D01*
G02Y1605592I-1664J-1456D01*
G03X1341338Y1605460I150J-132D01*
G01Y1604838D01*
G02X1341135Y1604636I-203J1D01*
G01X1338315D01*
G02X1338112Y1604838I-1J202D01*
G01Y1605460D01*
G03X1338062Y1605592I-200J0D01*
G02Y1608504I1664J1456D01*
G03X1338112Y1608636I-150J132D01*
G01Y1610578D01*
G03X1338062Y1610710I-200J0D01*
G02Y1613622I1664J1456D01*
G03X1338112Y1613754I-150J132D01*
G01Y1614376D01*
G02X1338315Y1614578I203J-1D01*
G37*
G36*
G01X1355637D02*
X1358457D01*
G02X1358660Y1614376I1J-202D01*
G01Y1613754D01*
G03X1358710Y1613622I200J0D01*
G02Y1610710I-1664J-1456D01*
G03X1358660Y1610578I150J-132D01*
G01Y1608636D01*
G03X1358710Y1608504I200J0D01*
G02Y1605592I-1664J-1456D01*
G03X1358660Y1605460I150J-132D01*
G01Y1604838D01*
G02X1358457Y1604636I-203J1D01*
G01X1355637D01*
G02X1355434Y1604838I-1J202D01*
G01Y1605460D01*
G03X1355384Y1605592I-200J0D01*
G02Y1608504I1664J1456D01*
G03X1355434Y1608636I-150J132D01*
G01Y1610578D01*
G03X1355384Y1610710I-200J0D01*
G02Y1613622I1664J1456D01*
G03X1355434Y1613754I-150J132D01*
G01Y1614376D01*
G02X1355637Y1614578I203J-1D01*
G37*
G36*
G01X1476897D02*
X1479717D01*
G02X1479920Y1614376I1J-202D01*
G01Y1613754D01*
G03X1479970Y1613622I200J0D01*
G02Y1610710I-1664J-1456D01*
G03X1479920Y1610578I150J-132D01*
G01Y1608636D01*
G03X1479970Y1608504I200J0D01*
G02Y1605592I-1664J-1456D01*
G03X1479920Y1605460I150J-132D01*
G01Y1604838D01*
G02X1479717Y1604636I-203J1D01*
G01X1476897D01*
G02X1476694Y1604838I-1J202D01*
G01Y1605460D01*
G03X1476644Y1605592I-200J0D01*
G02Y1608504I1664J1456D01*
G03X1476694Y1608636I-150J132D01*
G01Y1610578D01*
G03X1476644Y1610710I-200J0D01*
G02Y1613622I1664J1456D01*
G03X1476694Y1613754I-150J132D01*
G01Y1614376D01*
G02X1476897Y1614578I203J-1D01*
G37*
G36*
G01X1650125D02*
X1652945D01*
G02X1653148Y1614376I1J-202D01*
G01Y1613754D01*
G03X1653198Y1613622I200J0D01*
G02Y1610710I-1664J-1456D01*
G03X1653148Y1610578I150J-132D01*
G01Y1608636D01*
G03X1653198Y1608504I200J0D01*
G02Y1605592I-1664J-1456D01*
G03X1653148Y1605460I150J-132D01*
G01Y1604838D01*
G02X1652945Y1604636I-203J1D01*
G01X1650125D01*
G02X1649922Y1604838I-1J202D01*
G01Y1605460D01*
G03X1649872Y1605592I-200J0D01*
G02Y1608504I1664J1456D01*
G03X1649922Y1608636I-150J132D01*
G01Y1610578D01*
G03X1649872Y1610710I-200J0D01*
G02Y1613622I1664J1456D01*
G03X1649922Y1613754I-150J132D01*
G01Y1614376D01*
G02X1650125Y1614578I203J-1D01*
G37*
G36*
G01X1684771D02*
X1687591D01*
G02X1687794Y1614376I1J-202D01*
G01Y1613754D01*
G03X1687844Y1613622I200J0D01*
G02Y1610710I-1664J-1456D01*
G03X1687794Y1610578I150J-132D01*
G01Y1608636D01*
G03X1687844Y1608504I200J0D01*
G02Y1605592I-1664J-1456D01*
G03X1687794Y1605460I150J-132D01*
G01Y1604838D01*
G02X1687591Y1604636I-203J1D01*
G01X1684771D01*
G02X1684568Y1604838I-1J202D01*
G01Y1605460D01*
G03X1684518Y1605592I-200J0D01*
G02Y1608504I1664J1456D01*
G03X1684568Y1608636I-150J132D01*
G01Y1610578D01*
G03X1684518Y1610710I-200J0D01*
G02Y1613622I1664J1456D01*
G03X1684568Y1613754I-150J132D01*
G01Y1614376D01*
G02X1684771Y1614578I203J-1D01*
G37*
G36*
G01X1702093D02*
X1704913D01*
G02X1705116Y1614376I1J-202D01*
G01Y1613754D01*
G03X1705166Y1613622I200J0D01*
G02Y1610710I-1664J-1456D01*
G03X1705116Y1610578I150J-132D01*
G01Y1608636D01*
G03X1705166Y1608504I200J0D01*
G02Y1605592I-1664J-1456D01*
G03X1705116Y1605460I150J-132D01*
G01Y1604838D01*
G02X1704913Y1604636I-203J1D01*
G01X1702093D01*
G02X1701890Y1604838I-1J202D01*
G01Y1605460D01*
G03X1701840Y1605592I-200J0D01*
G02Y1608504I1664J1456D01*
G03X1701890Y1608636I-150J132D01*
G01Y1610578D01*
G03X1701840Y1610710I-200J0D01*
G02Y1613622I1664J1456D01*
G03X1701890Y1613754I-150J132D01*
G01Y1614376D01*
G02X1702093Y1614578I203J-1D01*
G37*
G36*
G01X134456Y1618908D02*
X137276D01*
G02X137478Y1618706I0J-202D01*
G01Y1618086D01*
G03X137528Y1617954I200J0D01*
G02Y1615038I-1661J-1458D01*
G03X137478Y1614906I150J-132D01*
G01Y1612968D01*
G03X137528Y1612836I200J0D01*
G02Y1609920I-1661J-1458D01*
G03X137478Y1609788I150J-132D01*
G01Y1609168D01*
G02X137276Y1608966I-202J0D01*
G01X134456D01*
G02X134254Y1609168I0J202D01*
G01Y1609788D01*
G03X134204Y1609920I-200J0D01*
G02Y1612836I1661J1458D01*
G03X134254Y1612968I-150J132D01*
G01Y1614906D01*
G03X134204Y1615038I-200J0D01*
G02Y1617954I1661J1458D01*
G03X134254Y1618086I-150J132D01*
G01Y1618706D01*
G02X134456Y1618908I202J0D01*
G37*
G36*
G01X169102D02*
X171922D01*
G02X172124Y1618706I0J-202D01*
G01Y1618086D01*
G03X172174Y1617954I200J0D01*
G02Y1615038I-1661J-1458D01*
G03X172124Y1614906I150J-132D01*
G01Y1612968D01*
G03X172174Y1612836I200J0D01*
G02Y1609920I-1661J-1458D01*
G03X172124Y1609788I150J-132D01*
G01Y1609168D01*
G02X171922Y1608966I-202J0D01*
G01X169102D01*
G02X168900Y1609168I0J202D01*
G01Y1609788D01*
G03X168850Y1609920I-200J0D01*
G02Y1612836I1661J1458D01*
G03X168900Y1612968I-150J132D01*
G01Y1614906D01*
G03X168850Y1615038I-200J0D01*
G02Y1617954I1661J1458D01*
G03X168900Y1618086I-150J132D01*
G01Y1618706D01*
G02X169102Y1618908I202J0D01*
G37*
G36*
G01X307684D02*
X310504D01*
G02X310706Y1618706I0J-202D01*
G01Y1618086D01*
G03X310756Y1617954I200J0D01*
G02Y1615038I-1661J-1458D01*
G03X310706Y1614906I150J-132D01*
G01Y1612968D01*
G03X310756Y1612836I200J0D01*
G02Y1609920I-1661J-1458D01*
G03X310706Y1609788I150J-132D01*
G01Y1609168D01*
G02X310504Y1608966I-202J0D01*
G01X307684D01*
G02X307482Y1609168I0J202D01*
G01Y1609788D01*
G03X307432Y1609920I-200J0D01*
G02Y1612836I1661J1458D01*
G03X307482Y1612968I-150J132D01*
G01Y1614906D01*
G03X307432Y1615038I-200J0D01*
G02Y1617954I1661J1458D01*
G03X307482Y1618086I-150J132D01*
G01Y1618706D01*
G02X307684Y1618908I202J0D01*
G37*
G36*
G01X342330D02*
X345150D01*
G02X345352Y1618706I0J-202D01*
G01Y1618086D01*
G03X345402Y1617954I200J0D01*
G02Y1615038I-1661J-1458D01*
G03X345352Y1614906I150J-132D01*
G01Y1612968D01*
G03X345402Y1612836I200J0D01*
G02Y1609920I-1661J-1458D01*
G03X345352Y1609788I150J-132D01*
G01Y1609168D01*
G02X345150Y1608966I-202J0D01*
G01X342330D01*
G02X342128Y1609168I0J202D01*
G01Y1609788D01*
G03X342078Y1609920I-200J0D01*
G02Y1612836I1661J1458D01*
G03X342128Y1612968I-150J132D01*
G01Y1614906D01*
G03X342078Y1615038I-200J0D01*
G02Y1617954I1661J1458D01*
G03X342128Y1618086I-150J132D01*
G01Y1618706D01*
G02X342330Y1618908I202J0D01*
G37*
G36*
G01X636818D02*
X639638D01*
G02X639840Y1618706I0J-202D01*
G01Y1618086D01*
G03X639890Y1617954I200J0D01*
G02Y1615038I-1661J-1458D01*
G03X639840Y1614906I150J-132D01*
G01Y1612968D01*
G03X639890Y1612836I200J0D01*
G02Y1609920I-1661J-1458D01*
G03X639840Y1609788I150J-132D01*
G01Y1609168D01*
G02X639638Y1608966I-202J0D01*
G01X636818D01*
G02X636616Y1609168I0J202D01*
G01Y1609788D01*
G03X636566Y1609920I-200J0D01*
G02Y1612836I1661J1458D01*
G03X636616Y1612968I-150J132D01*
G01Y1614906D01*
G03X636566Y1615038I-200J0D01*
G02Y1617954I1661J1458D01*
G03X636616Y1618086I-150J132D01*
G01Y1618706D01*
G02X636818Y1618908I202J0D01*
G37*
G36*
G01X671464D02*
X674284D01*
G02X674486Y1618706I0J-202D01*
G01Y1618086D01*
G03X674536Y1617954I200J0D01*
G02Y1615038I-1661J-1458D01*
G03X674486Y1614906I150J-132D01*
G01Y1612968D01*
G03X674536Y1612836I200J0D01*
G02Y1609920I-1661J-1458D01*
G03X674486Y1609788I150J-132D01*
G01Y1609168D01*
G02X674284Y1608966I-202J0D01*
G01X671464D01*
G02X671262Y1609168I0J202D01*
G01Y1609788D01*
G03X671212Y1609920I-200J0D01*
G02Y1612836I1661J1458D01*
G03X671262Y1612968I-150J132D01*
G01Y1614906D01*
G03X671212Y1615038I-200J0D01*
G02Y1617954I1661J1458D01*
G03X671262Y1618086I-150J132D01*
G01Y1618706D01*
G02X671464Y1618908I202J0D01*
G37*
G36*
G01X1156424D02*
X1159244D01*
G02X1159446Y1618706I0J-202D01*
G01Y1618086D01*
G03X1159496Y1617954I200J0D01*
G02Y1615038I-1661J-1458D01*
G03X1159446Y1614906I150J-132D01*
G01Y1612968D01*
G03X1159496Y1612836I200J0D01*
G02Y1609920I-1661J-1458D01*
G03X1159446Y1609788I150J-132D01*
G01Y1609168D01*
G02X1159244Y1608966I-202J0D01*
G01X1156424D01*
G02X1156222Y1609168I0J202D01*
G01Y1609788D01*
G03X1156172Y1609920I-200J0D01*
G02Y1612836I1661J1458D01*
G03X1156222Y1612968I-150J132D01*
G01Y1614906D01*
G03X1156172Y1615038I-200J0D01*
G02Y1617954I1661J1458D01*
G03X1156222Y1618086I-150J132D01*
G01Y1618706D01*
G02X1156424Y1618908I202J0D01*
G37*
G36*
G01X1191070D02*
X1193890D01*
G02X1194092Y1618706I0J-202D01*
G01Y1618086D01*
G03X1194142Y1617954I200J0D01*
G02Y1615038I-1661J-1458D01*
G03X1194092Y1614906I150J-132D01*
G01Y1612968D01*
G03X1194142Y1612836I200J0D01*
G02Y1609920I-1661J-1458D01*
G03X1194092Y1609788I150J-132D01*
G01Y1609168D01*
G02X1193890Y1608966I-202J0D01*
G01X1191070D01*
G02X1190868Y1609168I0J202D01*
G01Y1609788D01*
G03X1190818Y1609920I-200J0D01*
G02Y1612836I1661J1458D01*
G03X1190868Y1612968I-150J132D01*
G01Y1614906D01*
G03X1190818Y1615038I-200J0D01*
G02Y1617954I1661J1458D01*
G03X1190868Y1618086I-150J132D01*
G01Y1618706D01*
G02X1191070Y1618908I202J0D01*
G37*
G36*
G01X1312330D02*
X1315150D01*
G02X1315352Y1618706I0J-202D01*
G01Y1618086D01*
G03X1315402Y1617954I200J0D01*
G02Y1615038I-1661J-1458D01*
G03X1315352Y1614906I150J-132D01*
G01Y1612968D01*
G03X1315402Y1612836I200J0D01*
G02Y1609920I-1661J-1458D01*
G03X1315352Y1609788I150J-132D01*
G01Y1609168D01*
G02X1315150Y1608966I-202J0D01*
G01X1312330D01*
G02X1312128Y1609168I0J202D01*
G01Y1609788D01*
G03X1312078Y1609920I-200J0D01*
G02Y1612836I1661J1458D01*
G03X1312128Y1612968I-150J132D01*
G01Y1614906D01*
G03X1312078Y1615038I-200J0D01*
G02Y1617954I1661J1458D01*
G03X1312128Y1618086I-150J132D01*
G01Y1618706D01*
G02X1312330Y1618908I202J0D01*
G37*
G36*
G01X1346976D02*
X1349796D01*
G02X1349998Y1618706I0J-202D01*
G01Y1618086D01*
G03X1350048Y1617954I200J0D01*
G02Y1615038I-1661J-1458D01*
G03X1349998Y1614906I150J-132D01*
G01Y1612968D01*
G03X1350048Y1612836I200J0D01*
G02Y1609920I-1661J-1458D01*
G03X1349998Y1609788I150J-132D01*
G01Y1609168D01*
G02X1349796Y1608966I-202J0D01*
G01X1346976D01*
G02X1346774Y1609168I0J202D01*
G01Y1609788D01*
G03X1346724Y1609920I-200J0D01*
G02Y1612836I1661J1458D01*
G03X1346774Y1612968I-150J132D01*
G01Y1614906D01*
G03X1346724Y1615038I-200J0D01*
G02Y1617954I1661J1458D01*
G03X1346774Y1618086I-150J132D01*
G01Y1618706D01*
G02X1346976Y1618908I202J0D01*
G37*
G36*
G01X1658786D02*
X1661606D01*
G02X1661808Y1618706I0J-202D01*
G01Y1618086D01*
G03X1661858Y1617954I200J0D01*
G02Y1615038I-1661J-1458D01*
G03X1661808Y1614906I150J-132D01*
G01Y1612968D01*
G03X1661858Y1612836I200J0D01*
G02Y1609920I-1661J-1458D01*
G03X1661808Y1609788I150J-132D01*
G01Y1609168D01*
G02X1661606Y1608966I-202J0D01*
G01X1658786D01*
G02X1658584Y1609168I0J202D01*
G01Y1609788D01*
G03X1658534Y1609920I-200J0D01*
G02Y1612836I1661J1458D01*
G03X1658584Y1612968I-150J132D01*
G01Y1614906D01*
G03X1658534Y1615038I-200J0D01*
G02Y1617954I1661J1458D01*
G03X1658584Y1618086I-150J132D01*
G01Y1618706D01*
G02X1658786Y1618908I202J0D01*
G37*
G36*
G01X1693432D02*
X1696252D01*
G02X1696454Y1618706I0J-202D01*
G01Y1618086D01*
G03X1696504Y1617954I200J0D01*
G02Y1615038I-1661J-1458D01*
G03X1696454Y1614906I150J-132D01*
G01Y1612968D01*
G03X1696504Y1612836I200J0D01*
G02Y1609920I-1661J-1458D01*
G03X1696454Y1609788I150J-132D01*
G01Y1609168D01*
G02X1696252Y1608966I-202J0D01*
G01X1693432D01*
G02X1693230Y1609168I0J202D01*
G01Y1609788D01*
G03X1693180Y1609920I-200J0D01*
G02Y1612836I1661J1458D01*
G03X1693230Y1612968I-150J132D01*
G01Y1614906D01*
G03X1693180Y1615038I-200J0D01*
G02Y1617954I1661J1458D01*
G03X1693230Y1618086I-150J132D01*
G01Y1618706D01*
G02X1693432Y1618908I202J0D01*
G37*
G36*
G01X117133D02*
X119953D01*
G02X120156Y1618706I1J-202D01*
G01Y1618084D01*
G03X120206Y1617952I200J0D01*
G02Y1615040I-1664J-1456D01*
G03X120156Y1614908I150J-132D01*
G01Y1612966D01*
G03X120206Y1612834I200J0D01*
G02Y1609922I-1664J-1456D01*
G03X120156Y1609790I150J-132D01*
G01Y1609168D01*
G02X119953Y1608966I-203J1D01*
G01X117133D01*
G02X116930Y1609168I-1J202D01*
G01Y1609790D01*
G03X116880Y1609922I-200J0D01*
G02Y1612834I1664J1456D01*
G03X116930Y1612966I-150J132D01*
G01Y1614908D01*
G03X116880Y1615040I-200J0D01*
G02Y1617952I1664J1456D01*
G03X116930Y1618084I-150J132D01*
G01Y1618706D01*
G02X117133Y1618908I203J-1D01*
G37*
G36*
G01X151779D02*
X154599D01*
G02X154802Y1618706I1J-202D01*
G01Y1618084D01*
G03X154852Y1617952I200J0D01*
G02Y1615040I-1664J-1456D01*
G03X154802Y1614908I150J-132D01*
G01Y1612966D01*
G03X154852Y1612834I200J0D01*
G02Y1609922I-1664J-1456D01*
G03X154802Y1609790I150J-132D01*
G01Y1609168D01*
G02X154599Y1608966I-203J1D01*
G01X151779D01*
G02X151576Y1609168I-1J202D01*
G01Y1609790D01*
G03X151526Y1609922I-200J0D01*
G02Y1612834I1664J1456D01*
G03X151576Y1612966I-150J132D01*
G01Y1614908D01*
G03X151526Y1615040I-200J0D01*
G02Y1617952I1664J1456D01*
G03X151576Y1618084I-150J132D01*
G01Y1618706D01*
G02X151779Y1618908I203J-1D01*
G37*
G36*
G01X186425D02*
X189245D01*
G02X189448Y1618706I1J-202D01*
G01Y1618084D01*
G03X189498Y1617952I200J0D01*
G02Y1615040I-1664J-1456D01*
G03X189448Y1614908I150J-132D01*
G01Y1612966D01*
G03X189498Y1612834I200J0D01*
G02Y1609922I-1664J-1456D01*
G03X189448Y1609790I150J-132D01*
G01Y1609168D01*
G02X189245Y1608966I-203J1D01*
G01X186425D01*
G02X186222Y1609168I-1J202D01*
G01Y1609790D01*
G03X186172Y1609922I-200J0D01*
G02Y1612834I1664J1456D01*
G03X186222Y1612966I-150J132D01*
G01Y1614908D01*
G03X186172Y1615040I-200J0D01*
G02Y1617952I1664J1456D01*
G03X186222Y1618084I-150J132D01*
G01Y1618706D01*
G02X186425Y1618908I203J-1D01*
G37*
G36*
G01X290361D02*
X293181D01*
G02X293384Y1618706I1J-202D01*
G01Y1618084D01*
G03X293434Y1617952I200J0D01*
G02Y1615040I-1664J-1456D01*
G03X293384Y1614908I150J-132D01*
G01Y1612966D01*
G03X293434Y1612834I200J0D01*
G02Y1609922I-1664J-1456D01*
G03X293384Y1609790I150J-132D01*
G01Y1609168D01*
G02X293181Y1608966I-203J1D01*
G01X290361D01*
G02X290158Y1609168I-1J202D01*
G01Y1609790D01*
G03X290108Y1609922I-200J0D01*
G02Y1612834I1664J1456D01*
G03X290158Y1612966I-150J132D01*
G01Y1614908D01*
G03X290108Y1615040I-200J0D01*
G02Y1617952I1664J1456D01*
G03X290158Y1618084I-150J132D01*
G01Y1618706D01*
G02X290361Y1618908I203J-1D01*
G37*
G36*
G01X325007D02*
X327827D01*
G02X328030Y1618706I1J-202D01*
G01Y1618084D01*
G03X328080Y1617952I200J0D01*
G02Y1615040I-1664J-1456D01*
G03X328030Y1614908I150J-132D01*
G01Y1612966D01*
G03X328080Y1612834I200J0D01*
G02Y1609922I-1664J-1456D01*
G03X328030Y1609790I150J-132D01*
G01Y1609168D01*
G02X327827Y1608966I-203J1D01*
G01X325007D01*
G02X324804Y1609168I-1J202D01*
G01Y1609790D01*
G03X324754Y1609922I-200J0D01*
G02Y1612834I1664J1456D01*
G03X324804Y1612966I-150J132D01*
G01Y1614908D01*
G03X324754Y1615040I-200J0D01*
G02Y1617952I1664J1456D01*
G03X324804Y1618084I-150J132D01*
G01Y1618706D01*
G02X325007Y1618908I203J-1D01*
G37*
G36*
G01X359653D02*
X362473D01*
G02X362676Y1618706I1J-202D01*
G01Y1618084D01*
G03X362726Y1617952I200J0D01*
G02Y1615040I-1664J-1456D01*
G03X362676Y1614908I150J-132D01*
G01Y1612966D01*
G03X362726Y1612834I200J0D01*
G02Y1609922I-1664J-1456D01*
G03X362676Y1609790I150J-132D01*
G01Y1609168D01*
G02X362473Y1608966I-203J1D01*
G01X359653D01*
G02X359450Y1609168I-1J202D01*
G01Y1609790D01*
G03X359400Y1609922I-200J0D01*
G02Y1612834I1664J1456D01*
G03X359450Y1612966I-150J132D01*
G01Y1614908D01*
G03X359400Y1615040I-200J0D01*
G02Y1617952I1664J1456D01*
G03X359450Y1618084I-150J132D01*
G01Y1618706D01*
G02X359653Y1618908I203J-1D01*
G37*
G36*
G01X515559D02*
X518379D01*
G02X518582Y1618706I1J-202D01*
G01Y1618084D01*
G03X518632Y1617952I200J0D01*
G02Y1615040I-1664J-1456D01*
G03X518582Y1614908I150J-132D01*
G01Y1612966D01*
G03X518632Y1612834I200J0D01*
G02Y1609922I-1664J-1456D01*
G03X518582Y1609790I150J-132D01*
G01Y1609168D01*
G02X518379Y1608966I-203J1D01*
G01X515559D01*
G02X515356Y1609168I-1J202D01*
G01Y1609790D01*
G03X515306Y1609922I-200J0D01*
G02Y1612834I1664J1456D01*
G03X515356Y1612966I-150J132D01*
G01Y1614908D01*
G03X515306Y1615040I-200J0D01*
G02Y1617952I1664J1456D01*
G03X515356Y1618084I-150J132D01*
G01Y1618706D01*
G02X515559Y1618908I203J-1D01*
G37*
G36*
G01X654141D02*
X656961D01*
G02X657164Y1618706I1J-202D01*
G01Y1618084D01*
G03X657214Y1617952I200J0D01*
G02Y1615040I-1664J-1456D01*
G03X657164Y1614908I150J-132D01*
G01Y1612966D01*
G03X657214Y1612834I200J0D01*
G02Y1609922I-1664J-1456D01*
G03X657164Y1609790I150J-132D01*
G01Y1609168D01*
G02X656961Y1608966I-203J1D01*
G01X654141D01*
G02X653938Y1609168I-1J202D01*
G01Y1609790D01*
G03X653888Y1609922I-200J0D01*
G02Y1612834I1664J1456D01*
G03X653938Y1612966I-150J132D01*
G01Y1614908D01*
G03X653888Y1615040I-200J0D01*
G02Y1617952I1664J1456D01*
G03X653938Y1618084I-150J132D01*
G01Y1618706D01*
G02X654141Y1618908I203J-1D01*
G37*
G36*
G01X688787D02*
X691607D01*
G02X691810Y1618706I1J-202D01*
G01Y1618084D01*
G03X691860Y1617952I200J0D01*
G02Y1615040I-1664J-1456D01*
G03X691810Y1614908I150J-132D01*
G01Y1612966D01*
G03X691860Y1612834I200J0D01*
G02Y1609922I-1664J-1456D01*
G03X691810Y1609790I150J-132D01*
G01Y1609168D01*
G02X691607Y1608966I-203J1D01*
G01X688787D01*
G02X688584Y1609168I-1J202D01*
G01Y1609790D01*
G03X688534Y1609922I-200J0D01*
G02Y1612834I1664J1456D01*
G03X688584Y1612966I-150J132D01*
G01Y1614908D01*
G03X688534Y1615040I-200J0D01*
G02Y1617952I1664J1456D01*
G03X688584Y1618084I-150J132D01*
G01Y1618706D01*
G02X688787Y1618908I203J-1D01*
G37*
G36*
G01X1139101D02*
X1141921D01*
G02X1142124Y1618706I1J-202D01*
G01Y1618084D01*
G03X1142174Y1617952I200J0D01*
G02Y1615040I-1664J-1456D01*
G03X1142124Y1614908I150J-132D01*
G01Y1612966D01*
G03X1142174Y1612834I200J0D01*
G02Y1609922I-1664J-1456D01*
G03X1142124Y1609790I150J-132D01*
G01Y1609168D01*
G02X1141921Y1608966I-203J1D01*
G01X1139101D01*
G02X1138898Y1609168I-1J202D01*
G01Y1609790D01*
G03X1138848Y1609922I-200J0D01*
G02Y1612834I1664J1456D01*
G03X1138898Y1612966I-150J132D01*
G01Y1614908D01*
G03X1138848Y1615040I-200J0D01*
G02Y1617952I1664J1456D01*
G03X1138898Y1618084I-150J132D01*
G01Y1618706D01*
G02X1139101Y1618908I203J-1D01*
G37*
G36*
G01X1173747D02*
X1176567D01*
G02X1176770Y1618706I1J-202D01*
G01Y1618084D01*
G03X1176820Y1617952I200J0D01*
G02Y1615040I-1664J-1456D01*
G03X1176770Y1614908I150J-132D01*
G01Y1612966D01*
G03X1176820Y1612834I200J0D01*
G02Y1609922I-1664J-1456D01*
G03X1176770Y1609790I150J-132D01*
G01Y1609168D01*
G02X1176567Y1608966I-203J1D01*
G01X1173747D01*
G02X1173544Y1609168I-1J202D01*
G01Y1609790D01*
G03X1173494Y1609922I-200J0D01*
G02Y1612834I1664J1456D01*
G03X1173544Y1612966I-150J132D01*
G01Y1614908D01*
G03X1173494Y1615040I-200J0D01*
G02Y1617952I1664J1456D01*
G03X1173544Y1618084I-150J132D01*
G01Y1618706D01*
G02X1173747Y1618908I203J-1D01*
G37*
G36*
G01X1329653D02*
X1332473D01*
G02X1332676Y1618706I1J-202D01*
G01Y1618084D01*
G03X1332726Y1617952I200J0D01*
G02Y1615040I-1664J-1456D01*
G03X1332676Y1614908I150J-132D01*
G01Y1612966D01*
G03X1332726Y1612834I200J0D01*
G02Y1609922I-1664J-1456D01*
G03X1332676Y1609790I150J-132D01*
G01Y1609168D01*
G02X1332473Y1608966I-203J1D01*
G01X1329653D01*
G02X1329450Y1609168I-1J202D01*
G01Y1609790D01*
G03X1329400Y1609922I-200J0D01*
G02Y1612834I1664J1456D01*
G03X1329450Y1612966I-150J132D01*
G01Y1614908D01*
G03X1329400Y1615040I-200J0D01*
G02Y1617952I1664J1456D01*
G03X1329450Y1618084I-150J132D01*
G01Y1618706D01*
G02X1329653Y1618908I203J-1D01*
G37*
G36*
G01X1364299D02*
X1367119D01*
G02X1367322Y1618706I1J-202D01*
G01Y1618084D01*
G03X1367372Y1617952I200J0D01*
G02Y1615040I-1664J-1456D01*
G03X1367322Y1614908I150J-132D01*
G01Y1612966D01*
G03X1367372Y1612834I200J0D01*
G02Y1609922I-1664J-1456D01*
G03X1367322Y1609790I150J-132D01*
G01Y1609168D01*
G02X1367119Y1608966I-203J1D01*
G01X1364299D01*
G02X1364096Y1609168I-1J202D01*
G01Y1609790D01*
G03X1364046Y1609922I-200J0D01*
G02Y1612834I1664J1456D01*
G03X1364096Y1612966I-150J132D01*
G01Y1614908D01*
G03X1364046Y1615040I-200J0D01*
G02Y1617952I1664J1456D01*
G03X1364096Y1618084I-150J132D01*
G01Y1618706D01*
G02X1364299Y1618908I203J-1D01*
G37*
G36*
G01X1676109D02*
X1678929D01*
G02X1679132Y1618706I1J-202D01*
G01Y1618084D01*
G03X1679182Y1617952I200J0D01*
G02Y1615040I-1664J-1456D01*
G03X1679132Y1614908I150J-132D01*
G01Y1612966D01*
G03X1679182Y1612834I200J0D01*
G02Y1609922I-1664J-1456D01*
G03X1679132Y1609790I150J-132D01*
G01Y1609168D01*
G02X1678929Y1608966I-203J1D01*
G01X1676109D01*
G02X1675906Y1609168I-1J202D01*
G01Y1609790D01*
G03X1675856Y1609922I-200J0D01*
G02Y1612834I1664J1456D01*
G03X1675906Y1612966I-150J132D01*
G01Y1614908D01*
G03X1675856Y1615040I-200J0D01*
G02Y1617952I1664J1456D01*
G03X1675906Y1618084I-150J132D01*
G01Y1618706D01*
G02X1676109Y1618908I203J-1D01*
G37*
G36*
G01X1710755D02*
X1713575D01*
G02X1713778Y1618706I1J-202D01*
G01Y1618084D01*
G03X1713828Y1617952I200J0D01*
G02Y1615040I-1664J-1456D01*
G03X1713778Y1614908I150J-132D01*
G01Y1612966D01*
G03X1713828Y1612834I200J0D01*
G02Y1609922I-1664J-1456D01*
G03X1713778Y1609790I150J-132D01*
G01Y1609168D01*
G02X1713575Y1608966I-203J1D01*
G01X1710755D01*
G02X1710552Y1609168I-1J202D01*
G01Y1609790D01*
G03X1710502Y1609922I-200J0D01*
G02Y1612834I1664J1456D01*
G03X1710552Y1612966I-150J132D01*
G01Y1614908D01*
G03X1710502Y1615040I-200J0D01*
G02Y1617952I1664J1456D01*
G03X1710552Y1618084I-150J132D01*
G01Y1618706D01*
G02X1710755Y1618908I203J-1D01*
G37*
G36*
G01X1522570Y1409998D02*
X1525970D01*
G02Y1406992I0J-1503D01*
G01X1522570D01*
G02Y1409998I0J1503D01*
G37*
G36*
G01X1559290Y1349690D02*
X1562690D01*
G02Y1346684I0J-1503D01*
G01X1559290D01*
G02Y1349690I0J1503D01*
G37*
G36*
G01X1522570Y1385800D02*
X1525970D01*
G02Y1382794I0J-1503D01*
G01X1522570D01*
G02Y1385800I0J1503D01*
G37*
G36*
G01Y1373888D02*
X1525970D01*
G02Y1370882I0J-1503D01*
G01X1522570D01*
G02Y1373888I0J1503D01*
G37*
G36*
G01Y1398086D02*
X1525970D01*
G02Y1395080I0J-1503D01*
G01X1522570D01*
G02Y1398086I0J1503D01*
G37*
G36*
G01X1510330Y1373888D02*
X1513730D01*
G02Y1370882I0J-1503D01*
G01X1510330D01*
G02Y1373888I0J1503D01*
G37*
G36*
G01X1547050Y1361602D02*
X1550450D01*
G02Y1358596I0J-1503D01*
G01X1547050D01*
G02Y1361602I0J1503D01*
G37*
G36*
G01X1534810D02*
X1538210D01*
G02Y1358596I0J-1503D01*
G01X1534810D01*
G02Y1361602I0J1503D01*
G37*
G36*
G01X1547050Y1349690D02*
X1550450D01*
G02Y1346684I0J-1503D01*
G01X1547050D01*
G02Y1349690I0J1503D01*
G37*
G36*
G01X1534810D02*
X1538210D01*
G02Y1346684I0J-1503D01*
G01X1534810D01*
G02Y1349690I0J1503D01*
G37*
G36*
G01X241623Y1373888D02*
X245023D01*
G02Y1370882I0J-1503D01*
G01X241623D01*
G02Y1373888I0J1503D01*
G37*
G36*
G01Y1361602D02*
X245023D01*
G02Y1358596I0J-1503D01*
G01X241623D01*
G02Y1361602I0J1503D01*
G37*
G36*
G01X1485850Y1409998D02*
X1489250D01*
G02Y1406992I0J-1503D01*
G01X1485850D01*
G02Y1409998I0J1503D01*
G37*
G36*
G01X1510330Y1349690D02*
X1513730D01*
G02Y1346684I0J-1503D01*
G01X1510330D01*
G02Y1349690I0J1503D01*
G37*
G36*
G01X364023Y1398086D02*
X367423D01*
G02Y1395080I0J-1503D01*
G01X364023D01*
G02Y1398086I0J1503D01*
G37*
G36*
G01X1485850Y1385800D02*
X1489250D01*
G02Y1382794I0J-1503D01*
G01X1485850D01*
G02Y1385800I0J1503D01*
G37*
G36*
G01X1473610D02*
X1477010D01*
G02Y1382794I0J-1503D01*
G01X1473610D01*
G02Y1385800I0J1503D01*
G37*
G36*
G01Y1361602D02*
X1477010D01*
G02Y1358596I0J-1503D01*
G01X1473610D01*
G02Y1361602I0J1503D01*
G37*
G36*
G01Y1349690D02*
X1477010D01*
G02Y1346684I0J-1503D01*
G01X1473610D01*
G02Y1349690I0J1503D01*
G37*
G36*
G01X1461370Y1385800D02*
X1464770D01*
G02Y1382794I0J-1503D01*
G01X1461370D01*
G02Y1385800I0J1503D01*
G37*
G36*
G01Y1373888D02*
X1464770D01*
G02Y1370882I0J-1503D01*
G01X1461370D01*
G02Y1373888I0J1503D01*
G37*
G36*
G01Y1361602D02*
X1464770D01*
G02Y1358596I0J-1503D01*
G01X1461370D01*
G02Y1361602I0J1503D01*
G37*
G36*
G01Y1349690D02*
X1464770D01*
G02Y1346684I0J-1503D01*
G01X1461370D01*
G02Y1349690I0J1503D01*
G37*
G36*
G01X1485850Y1373888D02*
X1489250D01*
G02Y1370882I0J-1503D01*
G01X1485850D01*
G02Y1373888I0J1503D01*
G37*
G36*
G01X1498090Y1361602D02*
X1501490D01*
G02Y1358596I0J-1503D01*
G01X1498090D01*
G02Y1361602I0J1503D01*
G37*
G36*
G01X1485850D02*
X1489250D01*
G02Y1358596I0J-1503D01*
G01X1485850D01*
G02Y1361602I0J1503D01*
G37*
G36*
G01X253863Y1409998D02*
X257263D01*
G02Y1406992I0J-1503D01*
G01X253863D01*
G02Y1409998I0J1503D01*
G37*
G36*
G01X266103Y1373888D02*
X269503D01*
G02Y1370882I0J-1503D01*
G01X266103D01*
G02Y1373888I0J1503D01*
G37*
G36*
G01X290583Y1361602D02*
X293983D01*
G02Y1358596I0J-1503D01*
G01X290583D01*
G02Y1361602I0J1503D01*
G37*
G36*
G01X327303Y1349690D02*
X330703D01*
G02Y1346684I0J-1503D01*
G01X327303D01*
G02Y1349690I0J1503D01*
G37*
G36*
G01X290583Y1385800D02*
X293983D01*
G02Y1382794I0J-1503D01*
G01X290583D01*
G02Y1385800I0J1503D01*
G37*
G36*
G01Y1409998D02*
X293983D01*
G02Y1406992I0J-1503D01*
G01X290583D01*
G02Y1409998I0J1503D01*
G37*
G36*
G01X253863Y1398086D02*
X257263D01*
G02Y1395080I0J-1503D01*
G01X253863D01*
G02Y1398086I0J1503D01*
G37*
G36*
G01X364023Y1361602D02*
X367423D01*
G02Y1358596I0J-1503D01*
G01X364023D01*
G02Y1361602I0J1503D01*
G37*
G36*
G01X339543Y1349690D02*
X342943D01*
G02Y1346684I0J-1503D01*
G01X339543D01*
G02Y1349690I0J1503D01*
G37*
G36*
G01X241623D02*
X245023D01*
G02Y1346684I0J-1503D01*
G01X241623D01*
G02Y1349690I0J1503D01*
G37*
G36*
G01X339543Y1361602D02*
X342943D01*
G02Y1358596I0J-1503D01*
G01X339543D01*
G02Y1361602I0J1503D01*
G37*
G36*
G01X302823Y1409998D02*
X306223D01*
G02Y1406992I0J-1503D01*
G01X302823D01*
G02Y1409998I0J1503D01*
G37*
G36*
G01X364023Y1385800D02*
X367423D01*
G02Y1382794I0J-1503D01*
G01X364023D01*
G02Y1385800I0J1503D01*
G37*
G36*
G01X290583Y1398086D02*
X293983D01*
G02Y1395080I0J-1503D01*
G01X290583D01*
G02Y1398086I0J1503D01*
G37*
G36*
G01X112832D02*
X116232D01*
G02Y1395080I0J-1503D01*
G01X112832D01*
G02Y1398086I0J1503D01*
G37*
G36*
G01X364023Y1373888D02*
X367423D01*
G02Y1370882I0J-1503D01*
G01X364023D01*
G02Y1373888I0J1503D01*
G37*
G36*
G01X302823Y1361602D02*
X306223D01*
G02Y1358596I0J-1503D01*
G01X302823D01*
G02Y1361602I0J1503D01*
G37*
G36*
G01X1534810Y1409998D02*
X1538210D01*
G02Y1406992I0J-1503D01*
G01X1534810D01*
G02Y1409998I0J1503D01*
G37*
G36*
G01X1510330Y1385800D02*
X1513730D01*
G02Y1382794I0J-1503D01*
G01X1510330D01*
G02Y1385800I0J1503D01*
G37*
G36*
G01X1534810Y1398086D02*
X1538210D01*
G02Y1395080I0J-1503D01*
G01X1534810D01*
G02Y1398086I0J1503D01*
G37*
G36*
G01X302823Y1349690D02*
X306223D01*
G02Y1346684I0J-1503D01*
G01X302823D01*
G02Y1349690I0J1503D01*
G37*
G36*
G01X88352Y1373888D02*
X91752D01*
G02Y1370882I0J-1503D01*
G01X88352D01*
G02Y1373888I0J1503D01*
G37*
G36*
G01X339543Y1385800D02*
X342943D01*
G02Y1382794I0J-1503D01*
G01X339543D01*
G02Y1385800I0J1503D01*
G37*
G36*
G01X327303Y1373888D02*
X330703D01*
G02Y1370882I0J-1503D01*
G01X327303D01*
G02Y1373888I0J1503D01*
G37*
G36*
G01Y1409998D02*
X330703D01*
G02Y1406992I0J-1503D01*
G01X327303D01*
G02Y1409998I0J1503D01*
G37*
G36*
G01X278343Y1398086D02*
X281743D01*
G02Y1395080I0J-1503D01*
G01X278343D01*
G02Y1398086I0J1503D01*
G37*
G36*
G01X351783Y1349690D02*
X355183D01*
G02Y1346684I0J-1503D01*
G01X351783D01*
G02Y1349690I0J1503D01*
G37*
G36*
G01X186272Y1385800D02*
X189672D01*
G02Y1382794I0J-1503D01*
G01X186272D01*
G02Y1385800I0J1503D01*
G37*
G36*
G01Y1373888D02*
X189672D01*
G02Y1370882I0J-1503D01*
G01X186272D01*
G02Y1373888I0J1503D01*
G37*
G36*
G01X315063Y1361602D02*
X318463D01*
G02Y1358596I0J-1503D01*
G01X315063D01*
G02Y1361602I0J1503D01*
G37*
G36*
G01X327303D02*
X330703D01*
G02Y1358596I0J-1503D01*
G01X327303D01*
G02Y1361602I0J1503D01*
G37*
G36*
G01X315063Y1349690D02*
X318463D01*
G02Y1346684I0J-1503D01*
G01X315063D01*
G02Y1349690I0J1503D01*
G37*
G36*
G01X174032Y1398086D02*
X177432D01*
G02Y1395080I0J-1503D01*
G01X174032D01*
G02Y1398086I0J1503D01*
G37*
G36*
G01X266103Y1349690D02*
X269503D01*
G02Y1346684I0J-1503D01*
G01X266103D01*
G02Y1349690I0J1503D01*
G37*
G36*
G01X1054713Y1361602D02*
X1058113D01*
G02Y1358596I0J-1503D01*
G01X1054713D01*
G02Y1361602I0J1503D01*
G37*
G36*
G01Y1349690D02*
X1058113D01*
G02Y1346684I0J-1503D01*
G01X1054713D01*
G02Y1349690I0J1503D01*
G37*
G36*
G01Y1385800D02*
X1058113D01*
G02Y1382794I0J-1503D01*
G01X1054713D01*
G02Y1385800I0J1503D01*
G37*
G36*
G01Y1373888D02*
X1058113D01*
G02Y1370882I0J-1503D01*
G01X1054713D01*
G02Y1373888I0J1503D01*
G37*
G36*
G01X1177113Y1409998D02*
X1180513D01*
G02Y1406992I0J-1503D01*
G01X1177113D01*
G02Y1409998I0J1503D01*
G37*
G36*
G01Y1398086D02*
X1180513D01*
G02Y1395080I0J-1503D01*
G01X1177113D01*
G02Y1398086I0J1503D01*
G37*
G36*
G01Y1373888D02*
X1180513D01*
G02Y1370882I0J-1503D01*
G01X1177113D01*
G02Y1373888I0J1503D01*
G37*
G36*
G01Y1385800D02*
X1180513D01*
G02Y1382794I0J-1503D01*
G01X1177113D01*
G02Y1385800I0J1503D01*
G37*
G36*
G01Y1361602D02*
X1180513D01*
G02Y1358596I0J-1503D01*
G01X1177113D01*
G02Y1361602I0J1503D01*
G37*
G36*
G01Y1349690D02*
X1180513D01*
G02Y1346684I0J-1503D01*
G01X1177113D01*
G02Y1349690I0J1503D01*
G37*
G36*
G01X1164873Y1409998D02*
X1168273D01*
G02Y1406992I0J-1503D01*
G01X1164873D01*
G02Y1409998I0J1503D01*
G37*
G36*
G01Y1398086D02*
X1168273D01*
G02Y1395080I0J-1503D01*
G01X1164873D01*
G02Y1398086I0J1503D01*
G37*
G36*
G01Y1385800D02*
X1168273D01*
G02Y1382794I0J-1503D01*
G01X1164873D01*
G02Y1385800I0J1503D01*
G37*
G36*
G01Y1373888D02*
X1168273D01*
G02Y1370882I0J-1503D01*
G01X1164873D01*
G02Y1373888I0J1503D01*
G37*
G36*
G01Y1361602D02*
X1168273D01*
G02Y1358596I0J-1503D01*
G01X1164873D01*
G02Y1361602I0J1503D01*
G37*
G36*
G01Y1349690D02*
X1168273D01*
G02Y1346684I0J-1503D01*
G01X1164873D01*
G02Y1349690I0J1503D01*
G37*
G36*
G01X1152633Y1409998D02*
X1156033D01*
G02Y1406992I0J-1503D01*
G01X1152633D01*
G02Y1409998I0J1503D01*
G37*
G36*
G01Y1398086D02*
X1156033D01*
G02Y1395080I0J-1503D01*
G01X1152633D01*
G02Y1398086I0J1503D01*
G37*
G36*
G01Y1373888D02*
X1156033D01*
G02Y1370882I0J-1503D01*
G01X1152633D01*
G02Y1373888I0J1503D01*
G37*
G36*
G01Y1385800D02*
X1156033D01*
G02Y1382794I0J-1503D01*
G01X1152633D01*
G02Y1385800I0J1503D01*
G37*
G36*
G01Y1361602D02*
X1156033D01*
G02Y1358596I0J-1503D01*
G01X1152633D01*
G02Y1361602I0J1503D01*
G37*
G36*
G01Y1349690D02*
X1156033D01*
G02Y1346684I0J-1503D01*
G01X1152633D01*
G02Y1349690I0J1503D01*
G37*
G36*
G01X1128153Y1409998D02*
X1131553D01*
G02Y1406992I0J-1503D01*
G01X1128153D01*
G02Y1409998I0J1503D01*
G37*
G36*
G01X1140393D02*
X1143793D01*
G02Y1406992I0J-1503D01*
G01X1140393D01*
G02Y1409998I0J1503D01*
G37*
G36*
G01X1128153Y1398086D02*
X1131553D01*
G02Y1395080I0J-1503D01*
G01X1128153D01*
G02Y1398086I0J1503D01*
G37*
G36*
G01X1140393D02*
X1143793D01*
G02Y1395080I0J-1503D01*
G01X1140393D01*
G02Y1398086I0J1503D01*
G37*
G36*
G01X1128153Y1373888D02*
X1131553D01*
G02Y1370882I0J-1503D01*
G01X1128153D01*
G02Y1373888I0J1503D01*
G37*
G36*
G01Y1385800D02*
X1131553D01*
G02Y1382794I0J-1503D01*
G01X1128153D01*
G02Y1385800I0J1503D01*
G37*
G36*
G01X1140393D02*
X1143793D01*
G02Y1382794I0J-1503D01*
G01X1140393D01*
G02Y1385800I0J1503D01*
G37*
G36*
G01Y1373888D02*
X1143793D01*
G02Y1370882I0J-1503D01*
G01X1140393D01*
G02Y1373888I0J1503D01*
G37*
G36*
G01X1128153Y1361602D02*
X1131553D01*
G02Y1358596I0J-1503D01*
G01X1128153D01*
G02Y1361602I0J1503D01*
G37*
G36*
G01X1140393D02*
X1143793D01*
G02Y1358596I0J-1503D01*
G01X1140393D01*
G02Y1361602I0J1503D01*
G37*
G36*
G01X1128153Y1349690D02*
X1131553D01*
G02Y1346684I0J-1503D01*
G01X1128153D01*
G02Y1349690I0J1503D01*
G37*
G36*
G01X1140393D02*
X1143793D01*
G02Y1346684I0J-1503D01*
G01X1140393D01*
G02Y1349690I0J1503D01*
G37*
G36*
G01X1115913Y1409998D02*
X1119313D01*
G02Y1406992I0J-1503D01*
G01X1115913D01*
G02Y1409998I0J1503D01*
G37*
G36*
G01Y1398086D02*
X1119313D01*
G02Y1395080I0J-1503D01*
G01X1115913D01*
G02Y1398086I0J1503D01*
G37*
G36*
G01Y1373888D02*
X1119313D01*
G02Y1370882I0J-1503D01*
G01X1115913D01*
G02Y1373888I0J1503D01*
G37*
G36*
G01Y1385800D02*
X1119313D01*
G02Y1382794I0J-1503D01*
G01X1115913D01*
G02Y1385800I0J1503D01*
G37*
G36*
G01Y1361602D02*
X1119313D01*
G02Y1358596I0J-1503D01*
G01X1115913D01*
G02Y1361602I0J1503D01*
G37*
G36*
G01Y1349690D02*
X1119313D01*
G02Y1346684I0J-1503D01*
G01X1115913D01*
G02Y1349690I0J1503D01*
G37*
G36*
G01X1103673Y1409998D02*
X1107073D01*
G02Y1406992I0J-1503D01*
G01X1103673D01*
G02Y1409998I0J1503D01*
G37*
G36*
G01Y1398086D02*
X1107073D01*
G02Y1395080I0J-1503D01*
G01X1103673D01*
G02Y1398086I0J1503D01*
G37*
G36*
G01Y1385800D02*
X1107073D01*
G02Y1382794I0J-1503D01*
G01X1103673D01*
G02Y1385800I0J1503D01*
G37*
G36*
G01Y1373888D02*
X1107073D01*
G02Y1370882I0J-1503D01*
G01X1103673D01*
G02Y1373888I0J1503D01*
G37*
G36*
G01Y1361602D02*
X1107073D01*
G02Y1358596I0J-1503D01*
G01X1103673D01*
G02Y1361602I0J1503D01*
G37*
G36*
G01Y1349690D02*
X1107073D01*
G02Y1346684I0J-1503D01*
G01X1103673D01*
G02Y1349690I0J1503D01*
G37*
G36*
G01X1079193Y1409998D02*
X1082593D01*
G02Y1406992I0J-1503D01*
G01X1079193D01*
G02Y1409998I0J1503D01*
G37*
G36*
G01X1091433D02*
X1094833D01*
G02Y1406992I0J-1503D01*
G01X1091433D01*
G02Y1409998I0J1503D01*
G37*
G36*
G01X1079193Y1398086D02*
X1082593D01*
G02Y1395080I0J-1503D01*
G01X1079193D01*
G02Y1398086I0J1503D01*
G37*
G36*
G01X1091433D02*
X1094833D01*
G02Y1395080I0J-1503D01*
G01X1091433D01*
G02Y1398086I0J1503D01*
G37*
G36*
G01X1079193Y1385800D02*
X1082593D01*
G02Y1382794I0J-1503D01*
G01X1079193D01*
G02Y1385800I0J1503D01*
G37*
G36*
G01Y1373888D02*
X1082593D01*
G02Y1370882I0J-1503D01*
G01X1079193D01*
G02Y1373888I0J1503D01*
G37*
G36*
G01X1091433Y1385800D02*
X1094833D01*
G02Y1382794I0J-1503D01*
G01X1091433D01*
G02Y1385800I0J1503D01*
G37*
G36*
G01Y1373888D02*
X1094833D01*
G02Y1370882I0J-1503D01*
G01X1091433D01*
G02Y1373888I0J1503D01*
G37*
G36*
G01X1079193Y1361602D02*
X1082593D01*
G02Y1358596I0J-1503D01*
G01X1079193D01*
G02Y1361602I0J1503D01*
G37*
G36*
G01X1091433D02*
X1094833D01*
G02Y1358596I0J-1503D01*
G01X1091433D01*
G02Y1361602I0J1503D01*
G37*
G36*
G01X1079193Y1349690D02*
X1082593D01*
G02Y1346684I0J-1503D01*
G01X1079193D01*
G02Y1349690I0J1503D01*
G37*
G36*
G01X1091433D02*
X1094833D01*
G02Y1346684I0J-1503D01*
G01X1091433D01*
G02Y1349690I0J1503D01*
G37*
G36*
G01X1066953Y1409998D02*
X1070353D01*
G02Y1406992I0J-1503D01*
G01X1066953D01*
G02Y1409998I0J1503D01*
G37*
G36*
G01Y1398086D02*
X1070353D01*
G02Y1395080I0J-1503D01*
G01X1066953D01*
G02Y1398086I0J1503D01*
G37*
G36*
G01X290583Y1349690D02*
X293983D01*
G02Y1346684I0J-1503D01*
G01X290583D01*
G02Y1349690I0J1503D01*
G37*
G36*
G01X241623Y1385800D02*
X245023D01*
G02Y1382794I0J-1503D01*
G01X241623D01*
G02Y1385800I0J1503D01*
G37*
G36*
G01X253863Y1361602D02*
X257263D01*
G02Y1358596I0J-1503D01*
G01X253863D01*
G02Y1361602I0J1503D01*
G37*
G36*
G01Y1349690D02*
X257263D01*
G02Y1346684I0J-1503D01*
G01X253863D01*
G02Y1349690I0J1503D01*
G37*
G36*
G01X1547050Y1409998D02*
X1550450D01*
G02Y1406992I0J-1503D01*
G01X1547050D01*
G02Y1409998I0J1503D01*
G37*
G36*
G01X1559290Y1385800D02*
X1562690D01*
G02Y1382794I0J-1503D01*
G01X1559290D01*
G02Y1385800I0J1503D01*
G37*
G36*
G01X1230326Y1349690D02*
X1233726D01*
G02Y1346684I0J-1503D01*
G01X1230326D01*
G02Y1349690I0J1503D01*
G37*
G36*
G01Y1361602D02*
X1233726D01*
G02Y1358596I0J-1503D01*
G01X1230326D01*
G02Y1361602I0J1503D01*
G37*
G36*
G01Y1373888D02*
X1233726D01*
G02Y1370882I0J-1503D01*
G01X1230326D01*
G02Y1373888I0J1503D01*
G37*
G36*
G01Y1385800D02*
X1233726D01*
G02Y1382794I0J-1503D01*
G01X1230326D01*
G02Y1385800I0J1503D01*
G37*
G36*
G01X1242566Y1349690D02*
X1245966D01*
G02Y1346684I0J-1503D01*
G01X1242566D01*
G02Y1349690I0J1503D01*
G37*
G36*
G01Y1361602D02*
X1245966D01*
G02Y1358596I0J-1503D01*
G01X1242566D01*
G02Y1361602I0J1503D01*
G37*
G36*
G01Y1385800D02*
X1245966D01*
G02Y1382794I0J-1503D01*
G01X1242566D01*
G02Y1385800I0J1503D01*
G37*
G36*
G01Y1373888D02*
X1245966D01*
G02Y1370882I0J-1503D01*
G01X1242566D01*
G02Y1373888I0J1503D01*
G37*
G36*
G01Y1398086D02*
X1245966D01*
G02Y1395080I0J-1503D01*
G01X1242566D01*
G02Y1398086I0J1503D01*
G37*
G36*
G01Y1409998D02*
X1245966D01*
G02Y1406992I0J-1503D01*
G01X1242566D01*
G02Y1409998I0J1503D01*
G37*
G36*
G01X1267046Y1349690D02*
X1270446D01*
G02Y1346684I0J-1503D01*
G01X1267046D01*
G02Y1349690I0J1503D01*
G37*
G36*
G01X1254806D02*
X1258206D01*
G02Y1346684I0J-1503D01*
G01X1254806D01*
G02Y1349690I0J1503D01*
G37*
G36*
G01X1267046Y1361602D02*
X1270446D01*
G02Y1358596I0J-1503D01*
G01X1267046D01*
G02Y1361602I0J1503D01*
G37*
G36*
G01X1254806D02*
X1258206D01*
G02Y1358596I0J-1503D01*
G01X1254806D01*
G02Y1361602I0J1503D01*
G37*
G36*
G01X1267046Y1385800D02*
X1270446D01*
G02Y1382794I0J-1503D01*
G01X1267046D01*
G02Y1385800I0J1503D01*
G37*
G36*
G01Y1373888D02*
X1270446D01*
G02Y1370882I0J-1503D01*
G01X1267046D01*
G02Y1373888I0J1503D01*
G37*
G36*
G01X1254806D02*
X1258206D01*
G02Y1370882I0J-1503D01*
G01X1254806D01*
G02Y1373888I0J1503D01*
G37*
G36*
G01Y1385800D02*
X1258206D01*
G02Y1382794I0J-1503D01*
G01X1254806D01*
G02Y1385800I0J1503D01*
G37*
G36*
G01X1267046Y1398086D02*
X1270446D01*
G02Y1395080I0J-1503D01*
G01X1267046D01*
G02Y1398086I0J1503D01*
G37*
G36*
G01X1254806D02*
X1258206D01*
G02Y1395080I0J-1503D01*
G01X1254806D01*
G02Y1398086I0J1503D01*
G37*
G36*
G01X1267046Y1409998D02*
X1270446D01*
G02Y1406992I0J-1503D01*
G01X1267046D01*
G02Y1409998I0J1503D01*
G37*
G36*
G01X1254806D02*
X1258206D01*
G02Y1406992I0J-1503D01*
G01X1254806D01*
G02Y1409998I0J1503D01*
G37*
G36*
G01X1279286Y1349690D02*
X1282686D01*
G02Y1346684I0J-1503D01*
G01X1279286D01*
G02Y1349690I0J1503D01*
G37*
G36*
G01Y1361602D02*
X1282686D01*
G02Y1358596I0J-1503D01*
G01X1279286D01*
G02Y1361602I0J1503D01*
G37*
G36*
G01X1510330D02*
X1513730D01*
G02Y1358596I0J-1503D01*
G01X1510330D01*
G02Y1361602I0J1503D01*
G37*
G36*
G01X1279286Y1373888D02*
X1282686D01*
G02Y1370882I0J-1503D01*
G01X1279286D01*
G02Y1373888I0J1503D01*
G37*
G36*
G01Y1385800D02*
X1282686D01*
G02Y1382794I0J-1503D01*
G01X1279286D01*
G02Y1385800I0J1503D01*
G37*
G36*
G01X1648118Y1409998D02*
X1651518D01*
G02Y1406992I0J-1503D01*
G01X1648118D01*
G02Y1409998I0J1503D01*
G37*
G36*
G01X1279286Y1398086D02*
X1282686D01*
G02Y1395080I0J-1503D01*
G01X1279286D01*
G02Y1398086I0J1503D01*
G37*
G36*
G01Y1409998D02*
X1282686D01*
G02Y1406992I0J-1503D01*
G01X1279286D01*
G02Y1409998I0J1503D01*
G37*
G36*
G01X1291526Y1349690D02*
X1294926D01*
G02Y1346684I0J-1503D01*
G01X1291526D01*
G02Y1349690I0J1503D01*
G37*
G36*
G01X1559290Y1398086D02*
X1562690D01*
G02Y1395080I0J-1503D01*
G01X1559290D01*
G02Y1398086I0J1503D01*
G37*
G36*
G01X161792Y1409998D02*
X165192D01*
G02Y1406992I0J-1503D01*
G01X161792D01*
G02Y1409998I0J1503D01*
G37*
G36*
G01X186272Y1349690D02*
X189672D01*
G02Y1346684I0J-1503D01*
G01X186272D01*
G02Y1349690I0J1503D01*
G37*
G36*
G01X315063Y1409998D02*
X318463D01*
G02Y1406992I0J-1503D01*
G01X315063D01*
G02Y1409998I0J1503D01*
G37*
G36*
G01X1534810Y1373888D02*
X1538210D01*
G02Y1370882I0J-1503D01*
G01X1534810D01*
G02Y1373888I0J1503D01*
G37*
G36*
G01X1559290Y1409998D02*
X1562690D01*
G02Y1406992I0J-1503D01*
G01X1559290D01*
G02Y1409998I0J1503D01*
G37*
G36*
G01X351783Y1361602D02*
X355183D01*
G02Y1358596I0J-1503D01*
G01X351783D01*
G02Y1361602I0J1503D01*
G37*
G36*
G01X198512Y1385800D02*
X201912D01*
G02Y1382794I0J-1503D01*
G01X198512D01*
G02Y1385800I0J1503D01*
G37*
G36*
G01X1291526Y1361602D02*
X1294926D01*
G02Y1358596I0J-1503D01*
G01X1291526D01*
G02Y1361602I0J1503D01*
G37*
G36*
G01X1635878Y1349690D02*
X1639278D01*
G02Y1346684I0J-1503D01*
G01X1635878D01*
G02Y1349690I0J1503D01*
G37*
G36*
G01Y1361602D02*
X1639278D01*
G02Y1358596I0J-1503D01*
G01X1635878D01*
G02Y1361602I0J1503D01*
G37*
G36*
G01X1291526Y1385800D02*
X1294926D01*
G02Y1382794I0J-1503D01*
G01X1291526D01*
G02Y1385800I0J1503D01*
G37*
G36*
G01Y1373888D02*
X1294926D01*
G02Y1370882I0J-1503D01*
G01X1291526D01*
G02Y1373888I0J1503D01*
G37*
G36*
G01X1635878Y1385800D02*
X1639278D01*
G02Y1382794I0J-1503D01*
G01X1635878D01*
G02Y1385800I0J1503D01*
G37*
G36*
G01Y1373888D02*
X1639278D01*
G02Y1370882I0J-1503D01*
G01X1635878D01*
G02Y1373888I0J1503D01*
G37*
G36*
G01Y1398086D02*
X1639278D01*
G02Y1395080I0J-1503D01*
G01X1635878D01*
G02Y1398086I0J1503D01*
G37*
G36*
G01X1623638Y1349690D02*
X1627038D01*
G02Y1346684I0J-1503D01*
G01X1623638D01*
G02Y1349690I0J1503D01*
G37*
G36*
G01X1611398D02*
X1614798D01*
G02Y1346684I0J-1503D01*
G01X1611398D01*
G02Y1349690I0J1503D01*
G37*
G36*
G01X1623638Y1361602D02*
X1627038D01*
G02Y1358596I0J-1503D01*
G01X1623638D01*
G02Y1361602I0J1503D01*
G37*
G36*
G01X1291526Y1398086D02*
X1294926D01*
G02Y1395080I0J-1503D01*
G01X1291526D01*
G02Y1398086I0J1503D01*
G37*
G36*
G01Y1409998D02*
X1294926D01*
G02Y1406992I0J-1503D01*
G01X1291526D01*
G02Y1409998I0J1503D01*
G37*
G36*
G01X1316006Y1349690D02*
X1319406D01*
G02Y1346684I0J-1503D01*
G01X1316006D01*
G02Y1349690I0J1503D01*
G37*
G36*
G01X1303766D02*
X1307166D01*
G02Y1346684I0J-1503D01*
G01X1303766D01*
G02Y1349690I0J1503D01*
G37*
G36*
G01X1316006Y1361602D02*
X1319406D01*
G02Y1358596I0J-1503D01*
G01X1316006D01*
G02Y1361602I0J1503D01*
G37*
G36*
G01X1303766D02*
X1307166D01*
G02Y1358596I0J-1503D01*
G01X1303766D01*
G02Y1361602I0J1503D01*
G37*
G36*
G01X1316006Y1385800D02*
X1319406D01*
G02Y1382794I0J-1503D01*
G01X1316006D01*
G02Y1385800I0J1503D01*
G37*
G36*
G01X1611398Y1373888D02*
X1614798D01*
G02Y1370882I0J-1503D01*
G01X1611398D01*
G02Y1373888I0J1503D01*
G37*
G36*
G01Y1385800D02*
X1614798D01*
G02Y1382794I0J-1503D01*
G01X1611398D01*
G02Y1385800I0J1503D01*
G37*
G36*
G01X1623638Y1398086D02*
X1627038D01*
G02Y1395080I0J-1503D01*
G01X1623638D01*
G02Y1398086I0J1503D01*
G37*
G36*
G01X1316006Y1373888D02*
X1319406D01*
G02Y1370882I0J-1503D01*
G01X1316006D01*
G02Y1373888I0J1503D01*
G37*
G36*
G01X1303766D02*
X1307166D01*
G02Y1370882I0J-1503D01*
G01X1303766D01*
G02Y1373888I0J1503D01*
G37*
G36*
G01Y1385800D02*
X1307166D01*
G02Y1382794I0J-1503D01*
G01X1303766D01*
G02Y1385800I0J1503D01*
G37*
G36*
G01X1316006Y1398086D02*
X1319406D01*
G02Y1395080I0J-1503D01*
G01X1316006D01*
G02Y1398086I0J1503D01*
G37*
G36*
G01X1303766D02*
X1307166D01*
G02Y1395080I0J-1503D01*
G01X1303766D01*
G02Y1398086I0J1503D01*
G37*
G36*
G01X1316006Y1409998D02*
X1319406D01*
G02Y1406992I0J-1503D01*
G01X1316006D01*
G02Y1409998I0J1503D01*
G37*
G36*
G01X1303766D02*
X1307166D01*
G02Y1406992I0J-1503D01*
G01X1303766D01*
G02Y1409998I0J1503D01*
G37*
G36*
G01X1623638D02*
X1627038D01*
G02Y1406992I0J-1503D01*
G01X1623638D01*
G02Y1409998I0J1503D01*
G37*
G36*
G01X1328246Y1349690D02*
X1331646D01*
G02Y1346684I0J-1503D01*
G01X1328246D01*
G02Y1349690I0J1503D01*
G37*
G36*
G01Y1361602D02*
X1331646D01*
G02Y1358596I0J-1503D01*
G01X1328246D01*
G02Y1361602I0J1503D01*
G37*
G36*
G01X1648118Y1398086D02*
X1651518D01*
G02Y1395080I0J-1503D01*
G01X1648118D01*
G02Y1398086I0J1503D01*
G37*
G36*
G01Y1373888D02*
X1651518D01*
G02Y1370882I0J-1503D01*
G01X1648118D01*
G02Y1373888I0J1503D01*
G37*
G36*
G01Y1385800D02*
X1651518D01*
G02Y1382794I0J-1503D01*
G01X1648118D01*
G02Y1385800I0J1503D01*
G37*
G36*
G01X1328246Y1373888D02*
X1331646D01*
G02Y1370882I0J-1503D01*
G01X1328246D01*
G02Y1373888I0J1503D01*
G37*
G36*
G01X1648118Y1361602D02*
X1651518D01*
G02Y1358596I0J-1503D01*
G01X1648118D01*
G02Y1361602I0J1503D01*
G37*
G36*
G01Y1349690D02*
X1651518D01*
G02Y1346684I0J-1503D01*
G01X1648118D01*
G02Y1349690I0J1503D01*
G37*
G36*
G01X1635878Y1409998D02*
X1639278D01*
G02Y1406992I0J-1503D01*
G01X1635878D01*
G02Y1409998I0J1503D01*
G37*
G36*
G01X1660358D02*
X1663758D01*
G02Y1406992I0J-1503D01*
G01X1660358D01*
G02Y1409998I0J1503D01*
G37*
G36*
G01X1672598D02*
X1675998D01*
G02Y1406992I0J-1503D01*
G01X1672598D01*
G02Y1409998I0J1503D01*
G37*
G36*
G01X1660358Y1398086D02*
X1663758D01*
G02Y1395080I0J-1503D01*
G01X1660358D01*
G02Y1398086I0J1503D01*
G37*
G36*
G01X1672598D02*
X1675998D01*
G02Y1395080I0J-1503D01*
G01X1672598D01*
G02Y1398086I0J1503D01*
G37*
G36*
G01X1660358Y1373888D02*
X1663758D01*
G02Y1370882I0J-1503D01*
G01X1660358D01*
G02Y1373888I0J1503D01*
G37*
G36*
G01Y1385800D02*
X1663758D01*
G02Y1382794I0J-1503D01*
G01X1660358D01*
G02Y1385800I0J1503D01*
G37*
G36*
G01X1672598Y1373888D02*
X1675998D01*
G02Y1370882I0J-1503D01*
G01X1672598D01*
G02Y1373888I0J1503D01*
G37*
G36*
G01X1328246Y1385800D02*
X1331646D01*
G02Y1382794I0J-1503D01*
G01X1328246D01*
G02Y1385800I0J1503D01*
G37*
G36*
G01X1672598D02*
X1675998D01*
G02Y1382794I0J-1503D01*
G01X1672598D01*
G02Y1385800I0J1503D01*
G37*
G36*
G01X174032Y1409998D02*
X177432D01*
G02Y1406992I0J-1503D01*
G01X174032D01*
G02Y1409998I0J1503D01*
G37*
G36*
G01X266103Y1385800D02*
X269503D01*
G02Y1382794I0J-1503D01*
G01X266103D01*
G02Y1385800I0J1503D01*
G37*
G36*
G01X315063D02*
X318463D01*
G02Y1382794I0J-1503D01*
G01X315063D01*
G02Y1385800I0J1503D01*
G37*
G36*
G01X278343Y1409998D02*
X281743D01*
G02Y1406992I0J-1503D01*
G01X278343D01*
G02Y1409998I0J1503D01*
G37*
G36*
G01X1328246Y1398086D02*
X1331646D01*
G02Y1395080I0J-1503D01*
G01X1328246D01*
G02Y1398086I0J1503D01*
G37*
G36*
G01X364023Y1409998D02*
X367423D01*
G02Y1406992I0J-1503D01*
G01X364023D01*
G02Y1409998I0J1503D01*
G37*
G36*
G01X266103D02*
X269503D01*
G02Y1406992I0J-1503D01*
G01X266103D01*
G02Y1409998I0J1503D01*
G37*
G36*
G01X1733798Y1385800D02*
X1737198D01*
G02Y1382794I0J-1503D01*
G01X1733798D01*
G02Y1385800I0J1503D01*
G37*
G36*
G01Y1373888D02*
X1737198D01*
G02Y1370882I0J-1503D01*
G01X1733798D01*
G02Y1373888I0J1503D01*
G37*
G36*
G01Y1398086D02*
X1737198D01*
G02Y1395080I0J-1503D01*
G01X1733798D01*
G02Y1398086I0J1503D01*
G37*
G36*
G01X1721558Y1373888D02*
X1724958D01*
G02Y1370882I0J-1503D01*
G01X1721558D01*
G02Y1373888I0J1503D01*
G37*
G36*
G01X290583D02*
X293983D01*
G02Y1370882I0J-1503D01*
G01X290583D01*
G02Y1373888I0J1503D01*
G37*
G36*
G01X1328246Y1409998D02*
X1331646D01*
G02Y1406992I0J-1503D01*
G01X1328246D01*
G02Y1409998I0J1503D01*
G37*
G36*
G01X1340486Y1349690D02*
X1343886D01*
G02Y1346684I0J-1503D01*
G01X1340486D01*
G02Y1349690I0J1503D01*
G37*
G36*
G01X1583770Y1373888D02*
X1587170D01*
G02Y1370882I0J-1503D01*
G01X1583770D01*
G02Y1373888I0J1503D01*
G37*
G36*
G01X1485850Y1349690D02*
X1489250D01*
G02Y1346684I0J-1503D01*
G01X1485850D01*
G02Y1349690I0J1503D01*
G37*
G36*
G01X1340486Y1361602D02*
X1343886D01*
G02Y1358596I0J-1503D01*
G01X1340486D01*
G02Y1361602I0J1503D01*
G37*
G36*
G01X1733798Y1409998D02*
X1737198D01*
G02Y1406992I0J-1503D01*
G01X1733798D01*
G02Y1409998I0J1503D01*
G37*
G36*
G01X278343Y1373888D02*
X281743D01*
G02Y1370882I0J-1503D01*
G01X278343D01*
G02Y1373888I0J1503D01*
G37*
G36*
G01X266103Y1398086D02*
X269503D01*
G02Y1395080I0J-1503D01*
G01X266103D01*
G02Y1398086I0J1503D01*
G37*
G36*
G01X1733798Y1349690D02*
X1737198D01*
G02Y1346684I0J-1503D01*
G01X1733798D01*
G02Y1349690I0J1503D01*
G37*
G36*
G01X137312Y1385800D02*
X140712D01*
G02Y1382794I0J-1503D01*
G01X137312D01*
G02Y1385800I0J1503D01*
G37*
G36*
G01X1721558Y1398086D02*
X1724958D01*
G02Y1395080I0J-1503D01*
G01X1721558D01*
G02Y1398086I0J1503D01*
G37*
G36*
G01X1340486Y1385800D02*
X1343886D01*
G02Y1382794I0J-1503D01*
G01X1340486D01*
G02Y1385800I0J1503D01*
G37*
G36*
G01Y1373888D02*
X1343886D01*
G02Y1370882I0J-1503D01*
G01X1340486D01*
G02Y1373888I0J1503D01*
G37*
G36*
G01X1721558Y1385800D02*
X1724958D01*
G02Y1382794I0J-1503D01*
G01X1721558D01*
G02Y1385800I0J1503D01*
G37*
G36*
G01X339543Y1398086D02*
X342943D01*
G02Y1395080I0J-1503D01*
G01X339543D01*
G02Y1398086I0J1503D01*
G37*
G36*
G01X327303Y1385800D02*
X330703D01*
G02Y1382794I0J-1503D01*
G01X327303D01*
G02Y1385800I0J1503D01*
G37*
G36*
G01X315063Y1373888D02*
X318463D01*
G02Y1370882I0J-1503D01*
G01X315063D01*
G02Y1373888I0J1503D01*
G37*
G36*
G01X339543D02*
X342943D01*
G02Y1370882I0J-1503D01*
G01X339543D01*
G02Y1373888I0J1503D01*
G37*
G36*
G01X351783Y1385800D02*
X355183D01*
G02Y1382794I0J-1503D01*
G01X351783D01*
G02Y1385800I0J1503D01*
G37*
G36*
G01Y1373888D02*
X355183D01*
G02Y1370882I0J-1503D01*
G01X351783D01*
G02Y1373888I0J1503D01*
G37*
G36*
G01Y1398086D02*
X355183D01*
G02Y1395080I0J-1503D01*
G01X351783D01*
G02Y1398086I0J1503D01*
G37*
G36*
G01Y1409998D02*
X355183D01*
G02Y1406992I0J-1503D01*
G01X351783D01*
G02Y1409998I0J1503D01*
G37*
G36*
G01X315063Y1398086D02*
X318463D01*
G02Y1395080I0J-1503D01*
G01X315063D01*
G02Y1398086I0J1503D01*
G37*
G36*
G01X278343Y1361602D02*
X281743D01*
G02Y1358596I0J-1503D01*
G01X278343D01*
G02Y1361602I0J1503D01*
G37*
G36*
G01X1498090Y1349690D02*
X1501490D01*
G02Y1346684I0J-1503D01*
G01X1498090D01*
G02Y1349690I0J1503D01*
G37*
G36*
G01X266103Y1361602D02*
X269503D01*
G02Y1358596I0J-1503D01*
G01X266103D01*
G02Y1361602I0J1503D01*
G37*
G36*
G01X35825Y1466648D02*
X39225D01*
G02Y1463044I0J-1802D01*
G01X35825D01*
G02Y1466648I0J1802D01*
G37*
G36*
G01X942699Y344560D02*
X939299D01*
G02Y348166I0J1803D01*
G01X942699D01*
G02Y344560I0J-1803D01*
G37*
G36*
G01X942730Y322242D02*
X939330D01*
G02Y325846I0J1802D01*
G01X942730D01*
G02Y322242I0J-1802D01*
G37*
G36*
G01X927963Y342238D02*
X924563D01*
G02Y345844I0J1803D01*
G01X927963D01*
G02Y342238I0J-1803D01*
G37*
G36*
G01X919353Y342348D02*
X915953D01*
G02Y345952I0J1802D01*
G01X919353D01*
G02Y342348I0J-1802D01*
G37*
G36*
G01X302823Y1398086D02*
X306223D01*
G02Y1395080I0J-1503D01*
G01X302823D01*
G02Y1398086I0J1503D01*
G37*
G36*
G01X389015Y794228D02*
X392415D01*
G02Y791222I0J-1503D01*
G01X389015D01*
G02Y794228I0J1503D01*
G37*
G36*
G01X302823Y1373888D02*
X306223D01*
G02Y1370882I0J-1503D01*
G01X302823D01*
G02Y1373888I0J1503D01*
G37*
G36*
G01X1534810Y1385800D02*
X1538210D01*
G02Y1382794I0J-1503D01*
G01X1534810D01*
G02Y1385800I0J1503D01*
G37*
G36*
G01X327303Y1398086D02*
X330703D01*
G02Y1395080I0J-1503D01*
G01X327303D01*
G02Y1398086I0J1503D01*
G37*
G36*
G01X339543Y1409998D02*
X342943D01*
G02Y1406992I0J-1503D01*
G01X339543D01*
G02Y1409998I0J1503D01*
G37*
G36*
G01X302823Y1385800D02*
X306223D01*
G02Y1382794I0J-1503D01*
G01X302823D01*
G02Y1385800I0J1503D01*
G37*
G36*
G01X278343D02*
X281743D01*
G02Y1382794I0J-1503D01*
G01X278343D01*
G02Y1385800I0J1503D01*
G37*
G36*
G01X1340486Y1398086D02*
X1343886D01*
G02Y1395080I0J-1503D01*
G01X1340486D01*
G02Y1398086I0J1503D01*
G37*
G36*
G01Y1409998D02*
X1343886D01*
G02Y1406992I0J-1503D01*
G01X1340486D01*
G02Y1409998I0J1503D01*
G37*
G36*
G01X1583770Y1385800D02*
X1587170D01*
G02Y1382794I0J-1503D01*
G01X1583770D01*
G02Y1385800I0J1503D01*
G37*
G36*
G01X1571530Y1349690D02*
X1574930D01*
G02Y1346684I0J-1503D01*
G01X1571530D01*
G02Y1349690I0J1503D01*
G37*
G36*
G01Y1373888D02*
X1574930D01*
G02Y1370882I0J-1503D01*
G01X1571530D01*
G02Y1373888I0J1503D01*
G37*
G36*
G01Y1385800D02*
X1574930D01*
G02Y1382794I0J-1503D01*
G01X1571530D01*
G02Y1385800I0J1503D01*
G37*
G36*
G01X1473610Y1398086D02*
X1477010D01*
G02Y1395080I0J-1503D01*
G01X1473610D01*
G02Y1398086I0J1503D01*
G37*
G36*
G01Y1409998D02*
X1477010D01*
G02Y1406992I0J-1503D01*
G01X1473610D01*
G02Y1409998I0J1503D01*
G37*
G36*
G01X1583770Y1398086D02*
X1587170D01*
G02Y1395080I0J-1503D01*
G01X1583770D01*
G02Y1398086I0J1503D01*
G37*
G36*
G01Y1409998D02*
X1587170D01*
G02Y1406992I0J-1503D01*
G01X1583770D01*
G02Y1409998I0J1503D01*
G37*
G36*
G01X1485850Y1398086D02*
X1489250D01*
G02Y1395080I0J-1503D01*
G01X1485850D01*
G02Y1398086I0J1503D01*
G37*
G36*
G01X1498090Y1373888D02*
X1501490D01*
G02Y1370882I0J-1503D01*
G01X1498090D01*
G02Y1373888I0J1503D01*
G37*
G36*
G01X1522570Y1361602D02*
X1525970D01*
G02Y1358596I0J-1503D01*
G01X1522570D01*
G02Y1361602I0J1503D01*
G37*
G36*
G01X1498090Y1409998D02*
X1501490D01*
G02Y1406992I0J-1503D01*
G01X1498090D01*
G02Y1409998I0J1503D01*
G37*
G36*
G01X1352726Y1349690D02*
X1356126D01*
G02Y1346684I0J-1503D01*
G01X1352726D01*
G02Y1349690I0J1503D01*
G37*
G36*
G01X1510330Y1398086D02*
X1513730D01*
G02Y1395080I0J-1503D01*
G01X1510330D01*
G02Y1398086I0J1503D01*
G37*
G36*
G01X1611398Y1361602D02*
X1614798D01*
G02Y1358596I0J-1503D01*
G01X1611398D01*
G02Y1361602I0J1503D01*
G37*
G36*
G01X1623638Y1373888D02*
X1627038D01*
G02Y1370882I0J-1503D01*
G01X1623638D01*
G02Y1373888I0J1503D01*
G37*
G36*
G01X1547050D02*
X1550450D01*
G02Y1370882I0J-1503D01*
G01X1547050D01*
G02Y1373888I0J1503D01*
G37*
G36*
G01X1352726Y1361602D02*
X1356126D01*
G02Y1358596I0J-1503D01*
G01X1352726D01*
G02Y1361602I0J1503D01*
G37*
G36*
G01Y1385800D02*
X1356126D01*
G02Y1382794I0J-1503D01*
G01X1352726D01*
G02Y1385800I0J1503D01*
G37*
G36*
G01Y1373888D02*
X1356126D01*
G02Y1370882I0J-1503D01*
G01X1352726D01*
G02Y1373888I0J1503D01*
G37*
G36*
G01X1684838Y1409998D02*
X1688238D01*
G02Y1406992I0J-1503D01*
G01X1684838D01*
G02Y1409998I0J1503D01*
G37*
G36*
G01X1709318Y1373888D02*
X1712718D01*
G02Y1370882I0J-1503D01*
G01X1709318D01*
G02Y1373888I0J1503D01*
G37*
G36*
G01Y1385800D02*
X1712718D01*
G02Y1382794I0J-1503D01*
G01X1709318D01*
G02Y1385800I0J1503D01*
G37*
G36*
G01X1733798Y1361602D02*
X1737198D01*
G02Y1358596I0J-1503D01*
G01X1733798D01*
G02Y1361602I0J1503D01*
G37*
G36*
G01X1697078Y1373888D02*
X1700478D01*
G02Y1370882I0J-1503D01*
G01X1697078D01*
G02Y1373888I0J1503D01*
G37*
G36*
G01X1709318Y1409998D02*
X1712718D01*
G02Y1406992I0J-1503D01*
G01X1709318D01*
G02Y1409998I0J1503D01*
G37*
G36*
G01X1697078Y1398086D02*
X1700478D01*
G02Y1395080I0J-1503D01*
G01X1697078D01*
G02Y1398086I0J1503D01*
G37*
G36*
G01X1709318D02*
X1712718D01*
G02Y1395080I0J-1503D01*
G01X1709318D01*
G02Y1398086I0J1503D01*
G37*
G36*
G01X1721558Y1349690D02*
X1724958D01*
G02Y1346684I0J-1503D01*
G01X1721558D01*
G02Y1349690I0J1503D01*
G37*
G36*
G01Y1361602D02*
X1724958D01*
G02Y1358596I0J-1503D01*
G01X1721558D01*
G02Y1361602I0J1503D01*
G37*
G36*
G01Y1409998D02*
X1724958D01*
G02Y1406992I0J-1503D01*
G01X1721558D01*
G02Y1409998I0J1503D01*
G37*
G36*
G01X1352726Y1398086D02*
X1356126D01*
G02Y1395080I0J-1503D01*
G01X1352726D01*
G02Y1398086I0J1503D01*
G37*
G36*
G01X174032Y1361602D02*
X177432D01*
G02Y1358596I0J-1503D01*
G01X174032D01*
G02Y1361602I0J1503D01*
G37*
G36*
G01X198512Y1349690D02*
X201912D01*
G02Y1346684I0J-1503D01*
G01X198512D01*
G02Y1349690I0J1503D01*
G37*
G36*
G01Y1398086D02*
X201912D01*
G02Y1395080I0J-1503D01*
G01X198512D01*
G02Y1398086I0J1503D01*
G37*
G36*
G01X186272D02*
X189672D01*
G02Y1395080I0J-1503D01*
G01X186272D01*
G02Y1398086I0J1503D01*
G37*
G36*
G01X161792Y1349690D02*
X165192D01*
G02Y1346684I0J-1503D01*
G01X161792D01*
G02Y1349690I0J1503D01*
G37*
G36*
G01X186272Y1361602D02*
X189672D01*
G02Y1358596I0J-1503D01*
G01X186272D01*
G02Y1361602I0J1503D01*
G37*
G36*
G01X100592Y1349690D02*
X103992D01*
G02Y1346684I0J-1503D01*
G01X100592D01*
G02Y1349690I0J1503D01*
G37*
G36*
G01X112832D02*
X116232D01*
G02Y1346684I0J-1503D01*
G01X112832D01*
G02Y1349690I0J1503D01*
G37*
G36*
G01X149552Y1398086D02*
X152952D01*
G02Y1395080I0J-1503D01*
G01X149552D01*
G02Y1398086I0J1503D01*
G37*
G36*
G01X161792D02*
X165192D01*
G02Y1395080I0J-1503D01*
G01X161792D01*
G02Y1398086I0J1503D01*
G37*
G36*
G01Y1373888D02*
X165192D01*
G02Y1370882I0J-1503D01*
G01X161792D01*
G02Y1373888I0J1503D01*
G37*
G36*
G01Y1385800D02*
X165192D01*
G02Y1382794I0J-1503D01*
G01X161792D01*
G02Y1385800I0J1503D01*
G37*
G36*
G01X198512Y1361602D02*
X201912D01*
G02Y1358596I0J-1503D01*
G01X198512D01*
G02Y1361602I0J1503D01*
G37*
G36*
G01X137312D02*
X140712D01*
G02Y1358596I0J-1503D01*
G01X137312D01*
G02Y1361602I0J1503D01*
G37*
G36*
G01X161792D02*
X165192D01*
G02Y1358596I0J-1503D01*
G01X161792D01*
G02Y1361602I0J1503D01*
G37*
G36*
G01X149552Y1349690D02*
X152952D01*
G02Y1346684I0J-1503D01*
G01X149552D01*
G02Y1349690I0J1503D01*
G37*
G36*
G01X137312D02*
X140712D01*
G02Y1346684I0J-1503D01*
G01X137312D01*
G02Y1349690I0J1503D01*
G37*
G36*
G01X76112Y1361602D02*
X79512D01*
G02Y1358596I0J-1503D01*
G01X76112D01*
G02Y1361602I0J1503D01*
G37*
G36*
G01X174032Y1385800D02*
X177432D01*
G02Y1382794I0J-1503D01*
G01X174032D01*
G02Y1385800I0J1503D01*
G37*
G36*
G01X125072Y1409998D02*
X128472D01*
G02Y1406992I0J-1503D01*
G01X125072D01*
G02Y1409998I0J1503D01*
G37*
G36*
G01Y1398086D02*
X128472D01*
G02Y1395080I0J-1503D01*
G01X125072D01*
G02Y1398086I0J1503D01*
G37*
G36*
G01Y1373888D02*
X128472D01*
G02Y1370882I0J-1503D01*
G01X125072D01*
G02Y1373888I0J1503D01*
G37*
G36*
G01Y1385800D02*
X128472D01*
G02Y1382794I0J-1503D01*
G01X125072D01*
G02Y1385800I0J1503D01*
G37*
G36*
G01X1571530Y1361602D02*
X1574930D01*
G02Y1358596I0J-1503D01*
G01X1571530D01*
G02Y1361602I0J1503D01*
G37*
G36*
G01X100592Y1385800D02*
X103992D01*
G02Y1382794I0J-1503D01*
G01X100592D01*
G02Y1385800I0J1503D01*
G37*
G36*
G01X76112Y1373888D02*
X79512D01*
G02Y1370882I0J-1503D01*
G01X76112D01*
G02Y1373888I0J1503D01*
G37*
G36*
G01X88352Y1409998D02*
X91752D01*
G02Y1406992I0J-1503D01*
G01X88352D01*
G02Y1409998I0J1503D01*
G37*
G36*
G01X149552D02*
X152952D01*
G02Y1406992I0J-1503D01*
G01X149552D01*
G02Y1409998I0J1503D01*
G37*
G36*
G01X137312Y1373888D02*
X140712D01*
G02Y1370882I0J-1503D01*
G01X137312D01*
G02Y1373888I0J1503D01*
G37*
G36*
G01X253863Y1385800D02*
X257263D01*
G02Y1382794I0J-1503D01*
G01X253863D01*
G02Y1385800I0J1503D01*
G37*
G36*
G01X186272Y1409998D02*
X189672D01*
G02Y1406992I0J-1503D01*
G01X186272D01*
G02Y1409998I0J1503D01*
G37*
G36*
G01X125072Y1361602D02*
X128472D01*
G02Y1358596I0J-1503D01*
G01X125072D01*
G02Y1361602I0J1503D01*
G37*
G36*
G01Y1349690D02*
X128472D01*
G02Y1346684I0J-1503D01*
G01X125072D01*
G02Y1349690I0J1503D01*
G37*
G36*
G01X149552Y1373888D02*
X152952D01*
G02Y1370882I0J-1503D01*
G01X149552D01*
G02Y1373888I0J1503D01*
G37*
G36*
G01X174032Y1349690D02*
X177432D01*
G02Y1346684I0J-1503D01*
G01X174032D01*
G02Y1349690I0J1503D01*
G37*
G36*
G01Y1373888D02*
X177432D01*
G02Y1370882I0J-1503D01*
G01X174032D01*
G02Y1373888I0J1503D01*
G37*
G36*
G01X76112Y1385800D02*
X79512D01*
G02Y1382794I0J-1503D01*
G01X76112D01*
G02Y1385800I0J1503D01*
G37*
G36*
G01X1583770Y1349690D02*
X1587170D01*
G02Y1346684I0J-1503D01*
G01X1583770D01*
G02Y1349690I0J1503D01*
G37*
G36*
G01X1697078Y1385800D02*
X1700478D01*
G02Y1382794I0J-1503D01*
G01X1697078D01*
G02Y1385800I0J1503D01*
G37*
G36*
G01X88352Y1361602D02*
X91752D01*
G02Y1358596I0J-1503D01*
G01X88352D01*
G02Y1361602I0J1503D01*
G37*
G36*
G01Y1349690D02*
X91752D01*
G02Y1346684I0J-1503D01*
G01X88352D01*
G02Y1349690I0J1503D01*
G37*
G36*
G01X1697078Y1409998D02*
X1700478D01*
G02Y1406992I0J-1503D01*
G01X1697078D01*
G02Y1409998I0J1503D01*
G37*
G36*
G01X112832Y1373888D02*
X116232D01*
G02Y1370882I0J-1503D01*
G01X112832D01*
G02Y1373888I0J1503D01*
G37*
G36*
G01Y1409998D02*
X116232D01*
G02Y1406992I0J-1503D01*
G01X112832D01*
G02Y1409998I0J1503D01*
G37*
G36*
G01X100592D02*
X103992D01*
G02Y1406992I0J-1503D01*
G01X100592D01*
G02Y1409998I0J1503D01*
G37*
G36*
G01X724208Y1385800D02*
X727608D01*
G02Y1382794I0J-1503D01*
G01X724208D01*
G02Y1385800I0J1503D01*
G37*
G36*
G01X88352D02*
X91752D01*
G02Y1382794I0J-1503D01*
G01X88352D01*
G02Y1385800I0J1503D01*
G37*
G36*
G01X760928Y1361602D02*
X764328D01*
G02Y1358596I0J-1503D01*
G01X760928D01*
G02Y1361602I0J1503D01*
G37*
G36*
G01X100592Y1373888D02*
X103992D01*
G02Y1370882I0J-1503D01*
G01X100592D01*
G02Y1373888I0J1503D01*
G37*
G36*
G01X137312Y1398086D02*
X140712D01*
G02Y1395080I0J-1503D01*
G01X137312D01*
G02Y1398086I0J1503D01*
G37*
G36*
G01Y1409998D02*
X140712D01*
G02Y1406992I0J-1503D01*
G01X137312D01*
G02Y1409998I0J1503D01*
G37*
G36*
G01X112832Y1385800D02*
X116232D01*
G02Y1382794I0J-1503D01*
G01X112832D01*
G02Y1385800I0J1503D01*
G37*
G36*
G01X663008Y1361602D02*
X666408D01*
G02Y1358596I0J-1503D01*
G01X663008D01*
G02Y1361602I0J1503D01*
G37*
G36*
G01X100592Y1398086D02*
X103992D01*
G02Y1395080I0J-1503D01*
G01X100592D01*
G02Y1398086I0J1503D01*
G37*
G36*
G01X748688Y1385800D02*
X752088D01*
G02Y1382794I0J-1503D01*
G01X748688D01*
G02Y1385800I0J1503D01*
G37*
G36*
G01X1352726Y1409998D02*
X1356126D01*
G02Y1406992I0J-1503D01*
G01X1352726D01*
G02Y1409998I0J1503D01*
G37*
G36*
G01X100592Y1361602D02*
X103992D01*
G02Y1358596I0J-1503D01*
G01X100592D01*
G02Y1361602I0J1503D01*
G37*
G36*
G01X112832D02*
X116232D01*
G02Y1358596I0J-1503D01*
G01X112832D01*
G02Y1361602I0J1503D01*
G37*
G36*
G01X88352Y1398086D02*
X91752D01*
G02Y1395080I0J-1503D01*
G01X88352D01*
G02Y1398086I0J1503D01*
G37*
G36*
G01X1660358Y1361602D02*
X1663758D01*
G02Y1358596I0J-1503D01*
G01X1660358D01*
G02Y1361602I0J1503D01*
G37*
G36*
G01X1066953Y1349690D02*
X1070353D01*
G02Y1346684I0J-1503D01*
G01X1066953D01*
G02Y1349690I0J1503D01*
G37*
G36*
G01X663008D02*
X666408D01*
G02Y1346684I0J-1503D01*
G01X663008D01*
G02Y1349690I0J1503D01*
G37*
G36*
G01X1583770Y1361602D02*
X1587170D01*
G02Y1358596I0J-1503D01*
G01X1583770D01*
G02Y1361602I0J1503D01*
G37*
G36*
G01X1571530Y1398086D02*
X1574930D01*
G02Y1395080I0J-1503D01*
G01X1571530D01*
G02Y1398086I0J1503D01*
G37*
G36*
G01X1559290Y1361602D02*
X1562690D01*
G02Y1358596I0J-1503D01*
G01X1559290D01*
G02Y1361602I0J1503D01*
G37*
G36*
G01Y1373888D02*
X1562690D01*
G02Y1370882I0J-1503D01*
G01X1559290D01*
G02Y1373888I0J1503D01*
G37*
G36*
G01X1623638Y1385800D02*
X1627038D01*
G02Y1382794I0J-1503D01*
G01X1623638D01*
G02Y1385800I0J1503D01*
G37*
G36*
G01X76112Y1349690D02*
X79512D01*
G02Y1346684I0J-1503D01*
G01X76112D01*
G02Y1349690I0J1503D01*
G37*
G36*
G01X1066953Y1361602D02*
X1070353D01*
G02Y1358596I0J-1503D01*
G01X1066953D01*
G02Y1361602I0J1503D01*
G37*
G36*
G01X1547050Y1385800D02*
X1550450D01*
G02Y1382794I0J-1503D01*
G01X1547050D01*
G02Y1385800I0J1503D01*
G37*
G36*
G01X1672598Y1349690D02*
X1675998D01*
G02Y1346684I0J-1503D01*
G01X1672598D01*
G02Y1349690I0J1503D01*
G37*
G36*
G01X1660358D02*
X1663758D01*
G02Y1346684I0J-1503D01*
G01X1660358D01*
G02Y1349690I0J1503D01*
G37*
G36*
G01X1672598Y1361602D02*
X1675998D01*
G02Y1358596I0J-1503D01*
G01X1672598D01*
G02Y1361602I0J1503D01*
G37*
G36*
G01X1709318Y1349690D02*
X1712718D01*
G02Y1346684I0J-1503D01*
G01X1709318D01*
G02Y1349690I0J1503D01*
G37*
G36*
G01X1697078D02*
X1700478D01*
G02Y1346684I0J-1503D01*
G01X1697078D01*
G02Y1349690I0J1503D01*
G37*
G36*
G01X1684838Y1385800D02*
X1688238D01*
G02Y1382794I0J-1503D01*
G01X1684838D01*
G02Y1385800I0J1503D01*
G37*
G36*
G01X1709318Y1361602D02*
X1712718D01*
G02Y1358596I0J-1503D01*
G01X1709318D01*
G02Y1361602I0J1503D01*
G37*
G36*
G01X1697078D02*
X1700478D01*
G02Y1358596I0J-1503D01*
G01X1697078D01*
G02Y1361602I0J1503D01*
G37*
G36*
G01X1684838D02*
X1688238D01*
G02Y1358596I0J-1503D01*
G01X1684838D01*
G02Y1361602I0J1503D01*
G37*
G36*
G01Y1373888D02*
X1688238D01*
G02Y1370882I0J-1503D01*
G01X1684838D01*
G02Y1373888I0J1503D01*
G37*
G36*
G01Y1398086D02*
X1688238D01*
G02Y1395080I0J-1503D01*
G01X1684838D01*
G02Y1398086I0J1503D01*
G37*
G36*
G01X1066953Y1373888D02*
X1070353D01*
G02Y1370882I0J-1503D01*
G01X1066953D01*
G02Y1373888I0J1503D01*
G37*
G36*
G01Y1385800D02*
X1070353D01*
G02Y1382794I0J-1503D01*
G01X1066953D01*
G02Y1385800I0J1503D01*
G37*
G36*
G01X1547050Y1398086D02*
X1550450D01*
G02Y1395080I0J-1503D01*
G01X1547050D01*
G02Y1398086I0J1503D01*
G37*
G36*
G01X549168Y783102D02*
G02Y780098I0J-1502D01*
G01X545813D01*
X545808D01*
G02X545944Y783092I-38J1502D01*
G01X545956Y783090D01*
X548978D01*
X548990Y783092D01*
G02X549168Y783102I173J-1492D01*
G37*
G36*
G01X278343Y1349690D02*
X281743D01*
G02Y1346684I0J-1503D01*
G01X278343D01*
G02Y1349690I0J1503D01*
G37*
G36*
G01X945982Y888540D02*
X949382D01*
G02Y884936I0J-1802D01*
G01X945982D01*
G02Y888540I0J1802D01*
G37*
G36*
G01X1684838Y1349690D02*
X1688238D01*
G02Y1346684I0J-1503D01*
G01X1684838D01*
G02Y1349690I0J1503D01*
G37*
G36*
G01X1571530Y1409998D02*
X1574930D01*
G02Y1406992I0J-1503D01*
G01X1571530D01*
G02Y1409998I0J1503D01*
G37*
G36*
G01X1473610Y1373888D02*
X1477010D01*
G02Y1370882I0J-1503D01*
G01X1473610D01*
G02Y1373888I0J1503D01*
G37*
G36*
G01X1498090Y1398086D02*
X1501490D01*
G02Y1395080I0J-1503D01*
G01X1498090D01*
G02Y1398086I0J1503D01*
G37*
G36*
G01Y1385800D02*
X1501490D01*
G02Y1382794I0J-1503D01*
G01X1498090D01*
G02Y1385800I0J1503D01*
G37*
G36*
G01X1510330Y1409998D02*
X1513730D01*
G02Y1406992I0J-1503D01*
G01X1510330D01*
G02Y1409998I0J1503D01*
G37*
G36*
G01X1522570Y1349690D02*
X1525970D01*
G02Y1346684I0J-1503D01*
G01X1522570D01*
G02Y1349690I0J1503D01*
G37*
G36*
G01X146948Y1135604D02*
X143208D01*
G02Y1138210I0J1303D01*
G01X146948D01*
G02Y1135604I0J-1303D01*
G37*
G36*
G01X165649Y1131864D02*
X161909D01*
G02Y1134470I0J1303D01*
G01X165649D01*
G02Y1131864I0J-1303D01*
G37*
G36*
G01X154429D02*
X150689D01*
G02Y1134470I0J1303D01*
G01X154429D01*
G02Y1131864I0J-1303D01*
G37*
G36*
G01X173129Y1135604D02*
X169389D01*
G02Y1138210I0J1303D01*
G01X173129D01*
G02Y1135604I0J-1303D01*
G37*
G36*
G01X440402Y1361602D02*
X443802D01*
G02Y1358596I0J-1503D01*
G01X440402D01*
G02Y1361602I0J1503D01*
G37*
G36*
G01Y1349690D02*
X443802D01*
G02Y1346684I0J-1503D01*
G01X440402D01*
G02Y1349690I0J1503D01*
G37*
G36*
G01X452642Y1361602D02*
X456042D01*
G02Y1358596I0J-1503D01*
G01X452642D01*
G02Y1361602I0J1503D01*
G37*
G36*
G01Y1349690D02*
X456042D01*
G02Y1346684I0J-1503D01*
G01X452642D01*
G02Y1349690I0J1503D01*
G37*
G36*
G01X501602Y1385800D02*
X505002D01*
G02Y1382794I0J-1503D01*
G01X501602D01*
G02Y1385800I0J1503D01*
G37*
G36*
G01X513842D02*
X517242D01*
G02Y1382794I0J-1503D01*
G01X513842D01*
G02Y1385800I0J1503D01*
G37*
G36*
G01Y1373888D02*
X517242D01*
G02Y1370882I0J-1503D01*
G01X513842D01*
G02Y1373888I0J1503D01*
G37*
G36*
G01X501602D02*
X505002D01*
G02Y1370882I0J-1503D01*
G01X501602D01*
G02Y1373888I0J1503D01*
G37*
G36*
G01X464882Y1349690D02*
X468282D01*
G02Y1346684I0J-1503D01*
G01X464882D01*
G02Y1349690I0J1503D01*
G37*
G36*
G01X477122D02*
X480522D01*
G02Y1346684I0J-1503D01*
G01X477122D01*
G02Y1349690I0J1503D01*
G37*
G36*
G01X526082Y1385800D02*
X529482D01*
G02Y1382794I0J-1503D01*
G01X526082D01*
G02Y1385800I0J1503D01*
G37*
G36*
G01X538322D02*
X541722D01*
G02Y1382794I0J-1503D01*
G01X538322D01*
G02Y1385800I0J1503D01*
G37*
G36*
G01X526082Y1373888D02*
X529482D01*
G02Y1370882I0J-1503D01*
G01X526082D01*
G02Y1373888I0J1503D01*
G37*
G36*
G01X538322D02*
X541722D01*
G02Y1370882I0J-1503D01*
G01X538322D01*
G02Y1373888I0J1503D01*
G37*
G36*
G01X464882Y1361602D02*
X468282D01*
G02Y1358596I0J-1503D01*
G01X464882D01*
G02Y1361602I0J1503D01*
G37*
G36*
G01X477122D02*
X480522D01*
G02Y1358596I0J-1503D01*
G01X477122D01*
G02Y1361602I0J1503D01*
G37*
G36*
G01X489362Y1349690D02*
X492762D01*
G02Y1346684I0J-1503D01*
G01X489362D01*
G02Y1349690I0J1503D01*
G37*
G36*
G01X440402Y1373888D02*
X443802D01*
G02Y1370882I0J-1503D01*
G01X440402D01*
G02Y1373888I0J1503D01*
G37*
G36*
G01X550562Y1385800D02*
X553962D01*
G02Y1382794I0J-1503D01*
G01X550562D01*
G02Y1385800I0J1503D01*
G37*
G36*
G01Y1373888D02*
X553962D01*
G02Y1370882I0J-1503D01*
G01X550562D01*
G02Y1373888I0J1503D01*
G37*
G36*
G01X489362Y1361602D02*
X492762D01*
G02Y1358596I0J-1503D01*
G01X489362D01*
G02Y1361602I0J1503D01*
G37*
G36*
G01X440402Y1385800D02*
X443802D01*
G02Y1382794I0J-1503D01*
G01X440402D01*
G02Y1385800I0J1503D01*
G37*
G36*
G01X452642Y1373888D02*
X456042D01*
G02Y1370882I0J-1503D01*
G01X452642D01*
G02Y1373888I0J1503D01*
G37*
G36*
G01X562802Y1385800D02*
X566202D01*
G02Y1382794I0J-1503D01*
G01X562802D01*
G02Y1385800I0J1503D01*
G37*
G36*
G01X452642Y1409998D02*
X456042D01*
G02Y1406992I0J-1503D01*
G01X452642D01*
G02Y1409998I0J1503D01*
G37*
G36*
G01Y1398086D02*
X456042D01*
G02Y1395080I0J-1503D01*
G01X452642D01*
G02Y1398086I0J1503D01*
G37*
G36*
G01X562802Y1373888D02*
X566202D01*
G02Y1370882I0J-1503D01*
G01X562802D01*
G02Y1373888I0J1503D01*
G37*
G36*
G01X452642Y1385800D02*
X456042D01*
G02Y1382794I0J-1503D01*
G01X452642D01*
G02Y1385800I0J1503D01*
G37*
G36*
G01X464882Y1409998D02*
X468282D01*
G02Y1406992I0J-1503D01*
G01X464882D01*
G02Y1409998I0J1503D01*
G37*
G36*
G01Y1398086D02*
X468282D01*
G02Y1395080I0J-1503D01*
G01X464882D01*
G02Y1398086I0J1503D01*
G37*
G36*
G01Y1385800D02*
X468282D01*
G02Y1382794I0J-1503D01*
G01X464882D01*
G02Y1385800I0J1503D01*
G37*
G36*
G01X477122D02*
X480522D01*
G02Y1382794I0J-1503D01*
G01X477122D01*
G02Y1385800I0J1503D01*
G37*
G36*
G01Y1373888D02*
X480522D01*
G02Y1370882I0J-1503D01*
G01X477122D01*
G02Y1373888I0J1503D01*
G37*
G36*
G01X464882D02*
X468282D01*
G02Y1370882I0J-1503D01*
G01X464882D01*
G02Y1373888I0J1503D01*
G37*
G36*
G01X489362D02*
X492762D01*
G02Y1370882I0J-1503D01*
G01X489362D01*
G02Y1373888I0J1503D01*
G37*
G36*
G01Y1409998D02*
X492762D01*
G02Y1406992I0J-1503D01*
G01X489362D01*
G02Y1409998I0J1503D01*
G37*
G36*
G01Y1398086D02*
X492762D01*
G02Y1395080I0J-1503D01*
G01X489362D01*
G02Y1398086I0J1503D01*
G37*
G36*
G01X477122Y1409998D02*
X480522D01*
G02Y1406992I0J-1503D01*
G01X477122D01*
G02Y1409998I0J1503D01*
G37*
G36*
G01Y1398086D02*
X480522D01*
G02Y1395080I0J-1503D01*
G01X477122D01*
G02Y1398086I0J1503D01*
G37*
G36*
G01X489362Y1385800D02*
X492762D01*
G02Y1382794I0J-1503D01*
G01X489362D01*
G02Y1385800I0J1503D01*
G37*
G36*
G01X501602Y1361602D02*
X505002D01*
G02Y1358596I0J-1503D01*
G01X501602D01*
G02Y1361602I0J1503D01*
G37*
G36*
G01X513842D02*
X517242D01*
G02Y1358596I0J-1503D01*
G01X513842D01*
G02Y1361602I0J1503D01*
G37*
G36*
G01X501602Y1349690D02*
X505002D01*
G02Y1346684I0J-1503D01*
G01X501602D01*
G02Y1349690I0J1503D01*
G37*
G36*
G01X513842D02*
X517242D01*
G02Y1346684I0J-1503D01*
G01X513842D01*
G02Y1349690I0J1503D01*
G37*
G36*
G01X501602Y1398086D02*
X505002D01*
G02Y1395080I0J-1503D01*
G01X501602D01*
G02Y1398086I0J1503D01*
G37*
G36*
G01Y1409998D02*
X505002D01*
G02Y1406992I0J-1503D01*
G01X501602D01*
G02Y1409998I0J1503D01*
G37*
G36*
G01X526082Y1361602D02*
X529482D01*
G02Y1358596I0J-1503D01*
G01X526082D01*
G02Y1361602I0J1503D01*
G37*
G36*
G01Y1349690D02*
X529482D01*
G02Y1346684I0J-1503D01*
G01X526082D01*
G02Y1349690I0J1503D01*
G37*
G36*
G01X513842Y1398086D02*
X517242D01*
G02Y1395080I0J-1503D01*
G01X513842D01*
G02Y1398086I0J1503D01*
G37*
G36*
G01X526082Y1409998D02*
X529482D01*
G02Y1406992I0J-1503D01*
G01X526082D01*
G02Y1409998I0J1503D01*
G37*
G36*
G01X513842D02*
X517242D01*
G02Y1406992I0J-1503D01*
G01X513842D01*
G02Y1409998I0J1503D01*
G37*
G36*
G01X526082Y1398086D02*
X529482D01*
G02Y1395080I0J-1503D01*
G01X526082D01*
G02Y1398086I0J1503D01*
G37*
G36*
G01X538322Y1361602D02*
X541722D01*
G02Y1358596I0J-1503D01*
G01X538322D01*
G02Y1361602I0J1503D01*
G37*
G36*
G01X550562D02*
X553962D01*
G02Y1358596I0J-1503D01*
G01X550562D01*
G02Y1361602I0J1503D01*
G37*
G36*
G01X538322Y1349690D02*
X541722D01*
G02Y1346684I0J-1503D01*
G01X538322D01*
G02Y1349690I0J1503D01*
G37*
G36*
G01X550562D02*
X553962D01*
G02Y1346684I0J-1503D01*
G01X550562D01*
G02Y1349690I0J1503D01*
G37*
G36*
G01X538322Y1398086D02*
X541722D01*
G02Y1395080I0J-1503D01*
G01X538322D01*
G02Y1398086I0J1503D01*
G37*
G36*
G01Y1409998D02*
X541722D01*
G02Y1406992I0J-1503D01*
G01X538322D01*
G02Y1409998I0J1503D01*
G37*
G36*
G01X562802Y1361602D02*
X566202D01*
G02Y1358596I0J-1503D01*
G01X562802D01*
G02Y1361602I0J1503D01*
G37*
G36*
G01Y1349690D02*
X566202D01*
G02Y1346684I0J-1503D01*
G01X562802D01*
G02Y1349690I0J1503D01*
G37*
G36*
G01X550562Y1398086D02*
X553962D01*
G02Y1395080I0J-1503D01*
G01X550562D01*
G02Y1398086I0J1503D01*
G37*
G36*
G01X562802D02*
X566202D01*
G02Y1395080I0J-1503D01*
G01X562802D01*
G02Y1398086I0J1503D01*
G37*
G36*
G01X550562Y1409998D02*
X553962D01*
G02Y1406992I0J-1503D01*
G01X550562D01*
G02Y1409998I0J1503D01*
G37*
G36*
G01X562802D02*
X566202D01*
G02Y1406992I0J-1503D01*
G01X562802D01*
G02Y1409998I0J1503D01*
G37*
G36*
G01X650768Y1361602D02*
X654168D01*
G02Y1358596I0J-1503D01*
G01X650768D01*
G02Y1361602I0J1503D01*
G37*
G36*
G01Y1349690D02*
X654168D01*
G02Y1346684I0J-1503D01*
G01X650768D01*
G02Y1349690I0J1503D01*
G37*
G36*
G01X626288Y1409998D02*
X629688D01*
G02Y1406992I0J-1503D01*
G01X626288D01*
G02Y1409998I0J1503D01*
G37*
G36*
G01X638528Y1385800D02*
X641928D01*
G02Y1382794I0J-1503D01*
G01X638528D01*
G02Y1385800I0J1503D01*
G37*
G36*
G01Y1373888D02*
X641928D01*
G02Y1370882I0J-1503D01*
G01X638528D01*
G02Y1373888I0J1503D01*
G37*
G36*
G01X626288Y1398086D02*
X629688D01*
G02Y1395080I0J-1503D01*
G01X626288D01*
G02Y1398086I0J1503D01*
G37*
G36*
G01X675248Y1361602D02*
X678648D01*
G02Y1358596I0J-1503D01*
G01X675248D01*
G02Y1361602I0J1503D01*
G37*
G36*
G01X650768Y1385800D02*
X654168D01*
G02Y1382794I0J-1503D01*
G01X650768D01*
G02Y1385800I0J1503D01*
G37*
G36*
G01X675248Y1349690D02*
X678648D01*
G02Y1346684I0J-1503D01*
G01X675248D01*
G02Y1349690I0J1503D01*
G37*
G36*
G01X650768Y1373888D02*
X654168D01*
G02Y1370882I0J-1503D01*
G01X650768D01*
G02Y1373888I0J1503D01*
G37*
G36*
G01X638528Y1409998D02*
X641928D01*
G02Y1406992I0J-1503D01*
G01X638528D01*
G02Y1409998I0J1503D01*
G37*
G36*
G01Y1398086D02*
X641928D01*
G02Y1395080I0J-1503D01*
G01X638528D01*
G02Y1398086I0J1503D01*
G37*
G36*
G01X687488Y1361602D02*
X690888D01*
G02Y1358596I0J-1503D01*
G01X687488D01*
G02Y1361602I0J1503D01*
G37*
G36*
G01Y1349690D02*
X690888D01*
G02Y1346684I0J-1503D01*
G01X687488D01*
G02Y1349690I0J1503D01*
G37*
G36*
G01X663008Y1385800D02*
X666408D01*
G02Y1382794I0J-1503D01*
G01X663008D01*
G02Y1385800I0J1503D01*
G37*
G36*
G01X650768Y1409998D02*
X654168D01*
G02Y1406992I0J-1503D01*
G01X650768D01*
G02Y1409998I0J1503D01*
G37*
G36*
G01X663008Y1373888D02*
X666408D01*
G02Y1370882I0J-1503D01*
G01X663008D01*
G02Y1373888I0J1503D01*
G37*
G36*
G01X650768Y1398086D02*
X654168D01*
G02Y1395080I0J-1503D01*
G01X650768D01*
G02Y1398086I0J1503D01*
G37*
G36*
G01X699728Y1361602D02*
X703128D01*
G02Y1358596I0J-1503D01*
G01X699728D01*
G02Y1361602I0J1503D01*
G37*
G36*
G01X687488Y1385800D02*
X690888D01*
G02Y1382794I0J-1503D01*
G01X687488D01*
G02Y1385800I0J1503D01*
G37*
G36*
G01X699728Y1349690D02*
X703128D01*
G02Y1346684I0J-1503D01*
G01X699728D01*
G02Y1349690I0J1503D01*
G37*
G36*
G01X687488Y1373888D02*
X690888D01*
G02Y1370882I0J-1503D01*
G01X687488D01*
G02Y1373888I0J1503D01*
G37*
G36*
G01X675248Y1385800D02*
X678648D01*
G02Y1382794I0J-1503D01*
G01X675248D01*
G02Y1385800I0J1503D01*
G37*
G36*
G01Y1373888D02*
X678648D01*
G02Y1370882I0J-1503D01*
G01X675248D01*
G02Y1373888I0J1503D01*
G37*
G36*
G01X711968Y1349690D02*
X715368D01*
G02Y1346684I0J-1503D01*
G01X711968D01*
G02Y1349690I0J1503D01*
G37*
G36*
G01Y1361602D02*
X715368D01*
G02Y1358596I0J-1503D01*
G01X711968D01*
G02Y1361602I0J1503D01*
G37*
G36*
G01X663008Y1409998D02*
X666408D01*
G02Y1406992I0J-1503D01*
G01X663008D01*
G02Y1409998I0J1503D01*
G37*
G36*
G01X699728Y1385800D02*
X703128D01*
G02Y1382794I0J-1503D01*
G01X699728D01*
G02Y1385800I0J1503D01*
G37*
G36*
G01Y1373888D02*
X703128D01*
G02Y1370882I0J-1503D01*
G01X699728D01*
G02Y1373888I0J1503D01*
G37*
G36*
G01X663008Y1398086D02*
X666408D01*
G02Y1395080I0J-1503D01*
G01X663008D01*
G02Y1398086I0J1503D01*
G37*
G36*
G01X724208Y1397992D02*
X727608D01*
G02Y1394986I0J-1503D01*
G01X724208D01*
G02Y1397992I0J1503D01*
G37*
G36*
G01Y1349690D02*
X727608D01*
G02Y1346684I0J-1503D01*
G01X724208D01*
G02Y1349690I0J1503D01*
G37*
G36*
G01X675248Y1409998D02*
X678648D01*
G02Y1406992I0J-1503D01*
G01X675248D01*
G02Y1409998I0J1503D01*
G37*
G36*
G01Y1398086D02*
X678648D01*
G02Y1395080I0J-1503D01*
G01X675248D01*
G02Y1398086I0J1503D01*
G37*
G36*
G01X724208Y1361602D02*
X727608D01*
G02Y1358596I0J-1503D01*
G01X724208D01*
G02Y1361602I0J1503D01*
G37*
G36*
G01Y1409904D02*
X727608D01*
G02Y1406898I0J-1503D01*
G01X724208D01*
G02Y1409904I0J1503D01*
G37*
G36*
G01X736448Y1349690D02*
X739848D01*
G02Y1346684I0J-1503D01*
G01X736448D01*
G02Y1349690I0J1503D01*
G37*
G36*
G01X711968Y1373888D02*
X715368D01*
G02Y1370882I0J-1503D01*
G01X711968D01*
G02Y1373888I0J1503D01*
G37*
G36*
G01X736448Y1361602D02*
X739848D01*
G02Y1358596I0J-1503D01*
G01X736448D01*
G02Y1361602I0J1503D01*
G37*
G36*
G01X711968Y1385800D02*
X715368D01*
G02Y1382794I0J-1503D01*
G01X711968D01*
G02Y1385800I0J1503D01*
G37*
G36*
G01X687488Y1409998D02*
X690888D01*
G02Y1406992I0J-1503D01*
G01X687488D01*
G02Y1409998I0J1503D01*
G37*
G36*
G01Y1398086D02*
X690888D01*
G02Y1395080I0J-1503D01*
G01X687488D01*
G02Y1398086I0J1503D01*
G37*
G36*
G01X736448Y1373888D02*
X739848D01*
G02Y1370882I0J-1503D01*
G01X736448D01*
G02Y1373888I0J1503D01*
G37*
G36*
G01X748688Y1349690D02*
X752088D01*
G02Y1346684I0J-1503D01*
G01X748688D01*
G02Y1349690I0J1503D01*
G37*
G36*
G01X724208Y1373888D02*
X727608D01*
G02Y1370882I0J-1503D01*
G01X724208D01*
G02Y1373888I0J1503D01*
G37*
G36*
G01X736448Y1385800D02*
X739848D01*
G02Y1382794I0J-1503D01*
G01X736448D01*
G02Y1385800I0J1503D01*
G37*
G36*
G01X748688Y1361602D02*
X752088D01*
G02Y1358596I0J-1503D01*
G01X748688D01*
G02Y1361602I0J1503D01*
G37*
G36*
G01X736448Y1409904D02*
X739848D01*
G02Y1406898I0J-1503D01*
G01X736448D01*
G02Y1409904I0J1503D01*
G37*
G36*
G01Y1397992D02*
X739848D01*
G02Y1394986I0J-1503D01*
G01X736448D01*
G02Y1397992I0J1503D01*
G37*
G36*
G01X699728Y1409998D02*
X703128D01*
G02Y1406992I0J-1503D01*
G01X699728D01*
G02Y1409998I0J1503D01*
G37*
G36*
G01Y1398086D02*
X703128D01*
G02Y1395080I0J-1503D01*
G01X699728D01*
G02Y1398086I0J1503D01*
G37*
G36*
G01X748688Y1373888D02*
X752088D01*
G02Y1370882I0J-1503D01*
G01X748688D01*
G02Y1373888I0J1503D01*
G37*
G36*
G01X773168Y1349690D02*
X776568D01*
G02Y1346684I0J-1503D01*
G01X773168D01*
G02Y1349690I0J1503D01*
G37*
G36*
G01X760928D02*
X764328D01*
G02Y1346684I0J-1503D01*
G01X760928D01*
G02Y1349690I0J1503D01*
G37*
G36*
G01X711968Y1409998D02*
X715368D01*
G02Y1406992I0J-1503D01*
G01X711968D01*
G02Y1409998I0J1503D01*
G37*
G36*
G01Y1398086D02*
X715368D01*
G02Y1395080I0J-1503D01*
G01X711968D01*
G02Y1398086I0J1503D01*
G37*
G36*
G01X773168Y1361602D02*
X776568D01*
G02Y1358596I0J-1503D01*
G01X773168D01*
G02Y1361602I0J1503D01*
G37*
G36*
G01X760928Y1373888D02*
X764328D01*
G02Y1370882I0J-1503D01*
G01X760928D01*
G02Y1373888I0J1503D01*
G37*
G36*
G01Y1385800D02*
X764328D01*
G02Y1382794I0J-1503D01*
G01X760928D01*
G02Y1385800I0J1503D01*
G37*
G36*
G01X149552D02*
X152952D01*
G02Y1382794I0J-1503D01*
G01X149552D01*
G02Y1385800I0J1503D01*
G37*
G36*
G01Y1361602D02*
X152952D01*
G02Y1358596I0J-1503D01*
G01X149552D01*
G02Y1361602I0J1503D01*
G37*
G36*
G01X253863Y1373888D02*
X257263D01*
G02Y1370882I0J-1503D01*
G01X253863D01*
G02Y1373888I0J1503D01*
G37*
G36*
G01X198512D02*
X201912D01*
G02Y1370882I0J-1503D01*
G01X198512D01*
G02Y1373888I0J1503D01*
G37*
G36*
G01Y1409998D02*
X201912D01*
G02Y1406992I0J-1503D01*
G01X198512D01*
G02Y1409998I0J1503D01*
G37*
G36*
G01X364023Y1349690D02*
X367423D01*
G02Y1346684I0J-1503D01*
G01X364023D01*
G02Y1349690I0J1503D01*
G37*
G54D76*
X978614Y1210568D03*
Y1214838D03*
X914637Y1210568D03*
Y1214838D03*
X70947Y1201565D03*
Y1205835D03*
X1822594Y1211054D03*
Y1215324D03*
G54D82*
X665748Y1101376D03*
X658268D03*
X744290Y1097637D03*
X748031Y1105117D03*
X744290Y1093897D03*
X740551Y1101376D03*
X751771Y1097637D03*
Y1093897D03*
X748031Y1101376D03*
X740551Y1105117D03*
X320866Y1221062D03*
X313385Y1209842D03*
X320866Y1213582D03*
X324606Y1221062D03*
X313385Y1217322D03*
X317125Y1236023D03*
X313385Y1224803D03*
X324606Y1228543D03*
X317125Y1232283D03*
X313385Y1228543D03*
X320866D03*
X324606Y1239763D03*
X313385Y1247243D03*
X320866D03*
X317125Y1250984D03*
X320866Y1239763D03*
X313385Y1243503D03*
X324606Y1247243D03*
X317125Y1254724D03*
X320866Y1198621D03*
X313385Y1202362D03*
X324606Y1198621D03*
X317125Y1202362D03*
X320866Y1206102D03*
X324606D03*
X317125Y1217322D03*
Y1209842D03*
X324606Y1213582D03*
X320866Y1090157D03*
X317125Y1093897D03*
X324606Y1090157D03*
X313385Y1101377D03*
X320866D03*
X324606D03*
X317125Y1097637D03*
X305905Y1224803D03*
X302165Y1236023D03*
X294685Y1250984D03*
X298425Y1247243D03*
X309645Y1250984D03*
X298425Y1243503D03*
X305905D03*
Y1247243D03*
X302165Y1250984D03*
X294685Y1254724D03*
X309645D03*
X302165D03*
X298425Y1213582D03*
X305905Y1209842D03*
Y1217322D03*
X302165Y1209842D03*
X298425Y1206102D03*
X302165Y1217322D03*
Y1232283D03*
X309645D03*
X294685Y1236023D03*
X298425Y1224803D03*
X294685Y1232283D03*
X298425Y1228543D03*
X309645Y1236023D03*
X305905Y1228543D03*
Y1127559D03*
Y1135039D03*
X302165D03*
Y1127559D03*
X298425Y1123818D03*
Y1131299D03*
Y1198621D03*
X305905Y1202362D03*
X302165D03*
X298425Y1105117D03*
Y1101376D03*
X309644Y1097637D03*
X302164D03*
X305905Y1105117D03*
X294684Y1097637D03*
X313385Y1105117D03*
X305905Y1101376D03*
X302165Y1120078D03*
X305905Y1112598D03*
X298425Y1116338D03*
X305905Y1120078D03*
X302165Y1112598D03*
X294684Y1093897D03*
X309644D03*
X302164D03*
X290944Y1247243D03*
Y1243503D03*
X294685Y1213582D03*
Y1206102D03*
X290944Y1224803D03*
Y1228543D03*
X294684Y1123818D03*
Y1131299D03*
X294685Y1198621D03*
X287203Y1093897D03*
X279723D03*
X283464Y1101376D03*
Y1105117D03*
X290944Y1101376D03*
X279723Y1097637D03*
X290944Y1105117D03*
X287203Y1097637D03*
X294684Y1116338D03*
X264762Y1097637D03*
X268503Y1105117D03*
X272243Y1097637D03*
X275984Y1105117D03*
X268503Y1101376D03*
X275984D03*
X272243Y1093897D03*
X264762D03*
X246062Y1243503D03*
X249803Y1250984D03*
X246062Y1247243D03*
X257283Y1250984D03*
X253543Y1247243D03*
Y1243503D03*
X257283Y1254724D03*
X249803D03*
X249802Y1097637D03*
X257282D03*
X253543Y1105117D03*
Y1101376D03*
X261023Y1105117D03*
Y1101376D03*
X249802Y1093897D03*
X257282D03*
X234842Y1254724D03*
X242322D03*
X238582Y1247243D03*
X242322Y1250984D03*
X234842D03*
X238582Y1243503D03*
X246062Y1105117D03*
X242321Y1097637D03*
X234841D03*
X238582Y1101376D03*
X246062D03*
X238582Y1105117D03*
X234841Y1093897D03*
X242321D03*
X219881Y1254724D03*
X227362D03*
X219881Y1232283D03*
Y1236023D03*
X223622Y1224803D03*
X227362Y1232283D03*
X223622Y1228543D03*
X227362Y1236023D03*
X231102Y1243503D03*
Y1247243D03*
X223622Y1243503D03*
Y1247243D03*
X219881Y1250984D03*
X227362D03*
Y1093897D03*
X219881D03*
X231102Y1101376D03*
X219881Y1097637D03*
X223621Y1101376D03*
Y1105117D03*
X227362Y1097637D03*
X231102Y1105117D03*
X216141Y1247243D03*
X208661Y1243503D03*
X216141D03*
X204921Y1250984D03*
X208661Y1247243D03*
X201181Y1243503D03*
X212401Y1250984D03*
X201181Y1247243D03*
X212401Y1254724D03*
X204921D03*
Y1232283D03*
X201181Y1224803D03*
X212401Y1232283D03*
X208661Y1228543D03*
X212401Y1236023D03*
X216141Y1224803D03*
X208661D03*
X201181Y1228543D03*
X216141D03*
X204921Y1236023D03*
Y1097637D03*
X216141Y1101376D03*
X208661D03*
X212401Y1097637D03*
X208661Y1105117D03*
X216141D03*
X201181Y1101376D03*
Y1105117D03*
X212401Y1093897D03*
X204921D03*
X197440Y1236023D03*
X186220Y1224803D03*
X193700Y1228543D03*
X197440Y1232283D03*
X189960Y1236023D03*
X186220Y1228543D03*
X193700Y1224803D03*
X189960Y1232283D03*
X197440Y1093897D03*
X189960D03*
X193700Y1105117D03*
X189960Y1097637D03*
X186220Y1105117D03*
X197440Y1097637D03*
X193700Y1101376D03*
X186220D03*
X178740Y1228543D03*
X171259Y1224803D03*
X182480Y1236023D03*
Y1232283D03*
X174999D03*
X171259Y1228543D03*
X178740Y1224803D03*
X174999Y1236023D03*
Y1093897D03*
X182480D03*
Y1097637D03*
X174999D03*
X178740Y1101376D03*
Y1105117D03*
X1658463Y1097637D03*
X1617322Y1101376D03*
X1639763D03*
X1636022Y1097637D03*
Y1093897D03*
X1662204Y1101376D03*
X1621062Y1093897D03*
X1658463D03*
X1628542Y1097637D03*
X1643503D03*
Y1093897D03*
X1647244Y1101376D03*
X1621062Y1097637D03*
X1632283Y1101376D03*
X1624803D03*
X1654724D03*
X699408Y1093897D03*
X736810D03*
Y1097637D03*
X669488Y1093897D03*
X639567D03*
X635827Y1101376D03*
Y1105117D03*
X639567Y1097637D03*
X632086D03*
X774212Y1093897D03*
X729330Y1097637D03*
X721849Y1093897D03*
X781693Y1101377D03*
X669488Y1097637D03*
X1628542Y1093897D03*
X650787Y1101376D03*
X647047Y1097637D03*
X762992Y1120078D03*
X777953Y1101377D03*
X770472D03*
Y1105117D03*
X774212Y1097637D03*
X643307Y1101376D03*
Y1105117D03*
X781693Y1090157D03*
X777953D03*
X650787Y1105117D03*
X762992Y1112598D03*
Y1135039D03*
Y1127559D03*
X1647244Y1105116D03*
X662008Y1093897D03*
Y1097637D03*
X658268Y1105117D03*
X632086Y1093897D03*
X1624803Y1105116D03*
X1650983Y1097637D03*
Y1093897D03*
X1677165Y1101376D03*
X1669685D03*
X1680904Y1093897D03*
Y1097637D03*
X1673424Y1093897D03*
Y1097637D03*
X1665944D03*
Y1093897D03*
X1695866Y1090157D03*
X1692126D03*
X1688385Y1097637D03*
Y1093897D03*
X1684645Y1101377D03*
X1695866D03*
X1692126D03*
X1550000Y1105116D03*
X1564960D03*
X1557480D03*
X1572441D03*
X1579921D03*
X1594881D03*
X1587401D03*
X1609842D03*
X1602362D03*
X1516338Y1191141D03*
Y1198621D03*
Y1206102D03*
Y1213582D03*
X1535039Y1187401D03*
X1527559D03*
X1523819D03*
X1535039Y1194881D03*
Y1202362D03*
X1523819Y1194881D03*
X1527559D03*
X1523819Y1202362D03*
X1527559D03*
X1520078Y1191141D03*
Y1198621D03*
Y1206102D03*
X1535039Y1217322D03*
Y1209842D03*
X1527559D03*
X1523819D03*
Y1217322D03*
X1527559D03*
X1520078Y1213582D03*
X1538779Y1187401D03*
Y1194881D03*
Y1202362D03*
Y1217322D03*
Y1209842D03*
X1546259Y1191141D03*
X1542519D03*
Y1198621D03*
X1546259D03*
X1542519Y1206102D03*
X1546259D03*
X602165Y1228543D03*
X613386Y1243503D03*
Y1247243D03*
X609646Y1250984D03*
Y1254724D03*
X617126D03*
Y1250984D03*
X620866Y1247243D03*
Y1243503D03*
X665748Y1105117D03*
X613386Y1202362D03*
X609646D03*
X613386Y1194881D03*
X609646D03*
X613386Y1217322D03*
X609646D03*
Y1209842D03*
X613386D03*
X620866Y1187401D03*
Y1202362D03*
Y1194881D03*
Y1209842D03*
X624606Y1187401D03*
X632086Y1206102D03*
X628346D03*
X632086Y1198621D03*
X628346D03*
X624606Y1202362D03*
Y1194881D03*
X628346Y1191141D03*
X632086D03*
Y1213582D03*
X628346D03*
X624606Y1209842D03*
X620866Y1217322D03*
X624606D03*
X762992Y1105117D03*
X755512Y1101376D03*
X766731Y1097637D03*
X755512Y1105117D03*
X766731Y1093897D03*
X759251Y1097637D03*
X762992Y1101376D03*
X759251Y1093897D03*
X1516338Y1221062D03*
Y1228543D03*
X647047Y1093897D03*
X654527Y1097637D03*
Y1093897D03*
X602165Y1239763D03*
X718110Y1101376D03*
X714369Y1093897D03*
Y1097637D03*
X706889Y1093897D03*
Y1097637D03*
X703149Y1105117D03*
X699408Y1097637D03*
X691928Y1093897D03*
Y1097637D03*
X695669Y1101376D03*
Y1105117D03*
X703149Y1101376D03*
X710630Y1105117D03*
Y1101376D03*
X718110Y1105117D03*
X684449Y1097637D03*
Y1093897D03*
X1527559Y1224803D03*
X676968Y1097637D03*
Y1093897D03*
X688189Y1105117D03*
Y1101376D03*
X1520078Y1221062D03*
X680708Y1105117D03*
Y1101376D03*
X673228Y1105117D03*
Y1101376D03*
X725590Y1105117D03*
X733071Y1101376D03*
Y1105117D03*
X725590Y1101376D03*
X721849Y1097637D03*
X729330Y1093897D03*
X1516338Y1239763D03*
X759252Y1127559D03*
Y1135039D03*
X755512Y1131299D03*
X759252Y1112598D03*
Y1120078D03*
X755512Y1116338D03*
Y1123818D03*
X751771Y1131299D03*
Y1116338D03*
Y1123818D03*
X1632283Y1105116D03*
X1617322D03*
X1639763D03*
X1662204D03*
X1654724D03*
X1677165D03*
X1669685D03*
X1684645Y1105117D03*
X1673425Y1112598D03*
Y1120078D03*
X1669685Y1116338D03*
Y1123818D03*
X1665945Y1116338D03*
Y1123818D03*
X1677165Y1112598D03*
Y1120078D03*
X1673425Y1127559D03*
X1669685Y1131299D03*
X1665945D03*
X1677165Y1127559D03*
X1673425Y1135039D03*
X1677165D03*
X1085432Y1224803D03*
Y1228543D03*
X1089172Y1232283D03*
Y1236023D03*
X1092913Y1224803D03*
Y1228543D03*
X1100393Y1224803D03*
Y1228543D03*
X1104133Y1236023D03*
Y1232283D03*
X1107873Y1228543D03*
Y1224803D03*
X1096653Y1232283D03*
Y1236023D03*
X1115354Y1224803D03*
Y1228543D03*
X1119094Y1236023D03*
Y1232283D03*
X1122834Y1228543D03*
Y1224803D03*
X1126574Y1232283D03*
Y1236023D03*
X1111613Y1232283D03*
Y1236023D03*
X1115354Y1243503D03*
Y1247243D03*
X1119094Y1254724D03*
Y1250984D03*
X1122834Y1247243D03*
Y1243503D03*
X1126574Y1250984D03*
Y1254724D03*
X1130314Y1224803D03*
Y1228543D03*
X1141535Y1236023D03*
Y1232283D03*
X1134054Y1236023D03*
Y1232283D03*
X1137795Y1228543D03*
Y1224803D03*
X1130314Y1243503D03*
Y1247243D03*
X1134054Y1254724D03*
Y1250984D03*
X1137795Y1247243D03*
Y1243503D03*
X1141535Y1250984D03*
Y1254724D03*
X1149015D03*
Y1250984D03*
X1152755Y1247243D03*
Y1243503D03*
X1156495Y1250984D03*
Y1254724D03*
X1145275Y1243503D03*
Y1247243D03*
X1163976Y1254724D03*
Y1250984D03*
X1167716Y1243503D03*
Y1247243D03*
X1171456Y1250984D03*
Y1254724D03*
X1160235Y1247243D03*
Y1243503D03*
X1205117Y1228543D03*
Y1224803D03*
Y1243503D03*
Y1247243D03*
X1212598Y1224803D03*
Y1228543D03*
X1220078Y1224803D03*
Y1228543D03*
X1216338Y1232283D03*
Y1236023D03*
X1223818D03*
Y1232283D03*
X1208858Y1236023D03*
Y1232283D03*
X1220078Y1243503D03*
Y1247243D03*
X1223818Y1250984D03*
Y1254724D03*
X1216338D03*
Y1250984D03*
X1212598Y1247243D03*
Y1243503D03*
X1208858Y1250984D03*
Y1254724D03*
X1227558Y1224803D03*
Y1228543D03*
X1235039D03*
X1238779D03*
X1231298Y1232283D03*
Y1236023D03*
X1238779Y1239763D03*
X1235039D03*
X1238779Y1247243D03*
X1235039D03*
X1231298Y1250984D03*
Y1254724D03*
X1227558Y1247243D03*
Y1243503D03*
X1220078Y1202362D03*
X1216338D03*
X1212598Y1206102D03*
Y1198621D03*
X1208858Y1206102D03*
Y1198621D03*
X1220078Y1217322D03*
X1216338D03*
X1212598Y1213582D03*
X1216338Y1209842D03*
X1220078D03*
X1208858Y1213582D03*
X1238779Y1198621D03*
X1235039D03*
X1231298Y1202362D03*
X1227558D03*
X1235039Y1206102D03*
X1238779D03*
Y1213582D03*
X1235039D03*
X1238779Y1221062D03*
X1235039D03*
X1231298Y1217322D03*
X1227558D03*
Y1209842D03*
X1231298D03*
X1089172Y1097637D03*
Y1093897D03*
X1092913Y1101376D03*
X1104133Y1093897D03*
Y1097637D03*
X1107873Y1101376D03*
X1100393D03*
X1096653Y1097637D03*
Y1093897D03*
X1126574D03*
Y1097637D03*
X1119094Y1093897D03*
Y1097637D03*
X1115354Y1101376D03*
X1122834D03*
X1111613Y1097637D03*
Y1093897D03*
X1141535Y1097637D03*
Y1093897D03*
X1134054Y1097637D03*
Y1093897D03*
X1137794Y1101376D03*
X1130314D03*
X1152755D03*
X1156494Y1093897D03*
Y1097637D03*
X1149014D03*
Y1093897D03*
X1145275Y1101376D03*
X1175196D03*
X1167716D03*
X1171455Y1093897D03*
Y1097637D03*
X1163975Y1093897D03*
Y1097637D03*
X1160235Y1101376D03*
X1190157D03*
X1182676D03*
X1186416Y1093897D03*
Y1097637D03*
X1178935Y1093897D03*
Y1097637D03*
X1205117Y1101376D03*
X1197637D03*
X1201376Y1097637D03*
Y1093897D03*
X1193896Y1097637D03*
Y1093897D03*
X1220078Y1101376D03*
X1212598D03*
X1223817Y1093897D03*
Y1097637D03*
X1216337Y1093897D03*
Y1097637D03*
X1208857D03*
Y1093897D03*
X1238779Y1090157D03*
X1235039D03*
X1231298Y1097637D03*
Y1093897D03*
X1227558Y1101377D03*
X1238779D03*
X1235039D03*
X1092913Y1105116D03*
X1107873D03*
X1100393D03*
X1115354D03*
X1122834D03*
X1137794D03*
X1130314D03*
X1152755D03*
X1145275D03*
X1175196D03*
X1167716D03*
X1160235D03*
X1190157D03*
X1182676D03*
X1205117D03*
X1197637D03*
X1220078D03*
X1212598D03*
X1227558Y1105117D03*
X1216338Y1112598D03*
Y1120078D03*
X1212598Y1116338D03*
Y1123818D03*
X1208858Y1116338D03*
Y1123818D03*
X1220078Y1112598D03*
Y1120078D03*
X1216338Y1127559D03*
X1212598Y1131299D03*
X1208858D03*
X1220078Y1127559D03*
X1216338Y1135039D03*
X1220078D03*
X1561220Y1093897D03*
Y1097637D03*
X1564960Y1101376D03*
X1557480D03*
X1553740Y1097637D03*
Y1093897D03*
X1583661D03*
Y1097637D03*
X1576181Y1093897D03*
Y1097637D03*
X1572441Y1101376D03*
X1579921D03*
X1568700Y1097637D03*
Y1093897D03*
X1598622Y1097637D03*
Y1093897D03*
X1591141Y1097637D03*
Y1093897D03*
X1594881Y1101376D03*
X1587401D03*
X1609842D03*
X1613581Y1093897D03*
Y1097637D03*
X1606101D03*
Y1093897D03*
X1602362Y1101376D03*
X1546259Y1097637D03*
Y1093897D03*
X1550000Y1101376D03*
X609646Y1187401D03*
X613386D03*
X1527559Y1228543D03*
X1535039Y1224803D03*
Y1228543D03*
X1523819Y1232283D03*
Y1236023D03*
X1531299D03*
Y1232283D03*
X1520078Y1228543D03*
X1535039Y1243503D03*
Y1247243D03*
X1531299Y1250984D03*
Y1254724D03*
X1523819D03*
Y1250984D03*
X1527559Y1247243D03*
Y1243503D03*
X1520078Y1247243D03*
Y1239763D03*
X1542519Y1213582D03*
X1546259D03*
X1538779Y1232283D03*
Y1236023D03*
X1542519Y1224803D03*
Y1228543D03*
X1546259Y1232283D03*
Y1236023D03*
Y1250984D03*
Y1254724D03*
X1538779D03*
Y1250984D03*
X1542519Y1247243D03*
Y1243503D03*
X1550000Y1224803D03*
Y1228543D03*
Y1243503D03*
Y1247243D03*
X1557480Y1224803D03*
Y1228543D03*
X1561220Y1236023D03*
Y1232283D03*
X1564960Y1228543D03*
Y1224803D03*
X1553740Y1232283D03*
Y1236023D03*
X1557480Y1243503D03*
Y1247243D03*
X1561220Y1254724D03*
Y1250984D03*
X1564960Y1247243D03*
Y1243503D03*
X1553740Y1250984D03*
Y1254724D03*
X1568700Y1232283D03*
Y1236023D03*
Y1250984D03*
Y1254724D03*
X1632283Y1224803D03*
Y1228543D03*
Y1247243D03*
Y1243503D03*
X1636023Y1236023D03*
Y1232283D03*
X1639763Y1224803D03*
Y1228543D03*
X1643504Y1236023D03*
Y1232283D03*
X1647244Y1228543D03*
Y1224803D03*
X1636023Y1254724D03*
Y1250984D03*
X1639763Y1243503D03*
Y1247243D03*
X1643504Y1250984D03*
Y1254724D03*
X1647244Y1247243D03*
Y1243503D03*
X1654724Y1224803D03*
Y1228543D03*
X1658464Y1232283D03*
Y1236023D03*
X1650984D03*
Y1232283D03*
X1654724Y1247243D03*
X1658464Y1254724D03*
Y1250984D03*
X1654724Y1243503D03*
X1650984Y1254724D03*
Y1250984D03*
X605905Y1228543D03*
Y1239763D03*
Y1247243D03*
X617126Y1232283D03*
Y1236023D03*
X609646D03*
Y1232283D03*
X620866Y1228543D03*
Y1224803D03*
X613386Y1228543D03*
Y1224803D03*
X639567Y1236023D03*
Y1232283D03*
X632086Y1236023D03*
Y1232283D03*
X635827Y1228543D03*
Y1224803D03*
X628346Y1228543D03*
Y1224803D03*
X624606Y1236023D03*
Y1232283D03*
X639567Y1254724D03*
Y1250984D03*
X628346Y1243503D03*
Y1247243D03*
X624606Y1250984D03*
Y1254724D03*
X632086D03*
Y1250984D03*
X635827Y1247243D03*
Y1243503D03*
X654527Y1236023D03*
Y1232283D03*
X650787Y1224803D03*
Y1228543D03*
X647047Y1232283D03*
Y1236023D03*
X643307Y1228543D03*
Y1224803D03*
X654527Y1254724D03*
Y1250984D03*
X650787Y1243503D03*
Y1247243D03*
X647047Y1250984D03*
Y1254724D03*
X643307Y1247243D03*
Y1243503D03*
X718110Y1228543D03*
Y1224803D03*
Y1243503D03*
Y1247243D03*
X733071Y1224803D03*
Y1228543D03*
X736811Y1232283D03*
Y1236023D03*
X729331Y1232283D03*
Y1236023D03*
X725590Y1228543D03*
Y1224803D03*
X721850Y1232283D03*
Y1236023D03*
X733071Y1243503D03*
Y1247243D03*
X736811Y1250984D03*
Y1254724D03*
X729331D03*
Y1250984D03*
X725590Y1247243D03*
Y1243503D03*
X721850Y1250984D03*
Y1254724D03*
X744291Y1236023D03*
Y1232283D03*
X740551Y1228543D03*
Y1224803D03*
Y1243503D03*
X744291Y1250984D03*
Y1254724D03*
X740551Y1247243D03*
X602165Y1206102D03*
X605905D03*
X602165Y1198621D03*
X605905D03*
X602165Y1191141D03*
X605905D03*
X602165Y1221062D03*
X605905D03*
Y1213582D03*
X602165D03*
X1516338Y1247243D03*
X602165D03*
G54D80*
X970071Y1409152D03*
Y1365652D03*
G54D73*
X743337Y374862D03*
G54D66*
X1819042Y-27188D03*
Y-37188D03*
Y-47188D03*
X1753686Y-85978D03*
Y-75978D03*
Y-65978D03*
X1564906Y-27086D03*
Y-47086D03*
Y-37086D03*
X1574906Y-66006D03*
Y-86006D03*
Y-76006D03*
X1534542Y-27058D03*
Y-37058D03*
Y-47058D03*
X1499186Y-65978D03*
Y-75978D03*
Y-85978D03*
X1280406Y-26956D03*
Y-46956D03*
Y-36956D03*
X1320406Y-86006D03*
Y-66006D03*
Y-76006D03*
X1248042Y-26928D03*
X1242686Y-65978D03*
Y-75978D03*
Y-85978D03*
X993906Y-26826D03*
Y-46826D03*
Y-36826D03*
X1063906Y-66006D03*
Y-86006D03*
Y-76006D03*
X964542Y-26798D03*
Y-36798D03*
X939542D03*
Y-26798D03*
X989386Y-65978D03*
Y-75978D03*
X964386D03*
Y-65978D03*
X710406Y-26826D03*
Y-36826D03*
X735406D03*
Y-26826D03*
X830406Y-66006D03*
Y-76006D03*
X855406D03*
Y-66006D03*
X1248042Y-36928D03*
Y-46928D03*
X1018906Y-36826D03*
Y-46826D03*
X1217686Y-65978D03*
Y-75978D03*
X1305406Y-36956D03*
Y-46956D03*
Y-26956D03*
X1018906Y-26826D03*
X1217686Y-85978D03*
X1223042Y-26928D03*
Y-36928D03*
X1088906Y-76006D03*
Y-86006D03*
X1345406D03*
Y-76006D03*
Y-66006D03*
X1088906D03*
X1223042Y-46928D03*
X1474186Y-65978D03*
Y-75978D03*
Y-85978D03*
X1509542Y-27058D03*
Y-37058D03*
Y-47058D03*
X1794042Y-27188D03*
Y-37188D03*
Y-47188D03*
X1728686Y-65978D03*
Y-75978D03*
Y-85978D03*
X1589906Y-37086D03*
Y-47086D03*
Y-27086D03*
X1599906Y-76006D03*
Y-86006D03*
Y-66006D03*
G54D79*
X909360Y230906D03*
Y274606D03*
G54D74*
X1729390Y144095D03*
X1627028D03*
X1169941D03*
X1067579D03*
X965217D03*
X815217D03*
G54D72*
X640522Y630650D03*
X1657510Y374862D03*
X1554695Y630650D03*
X1200423Y374862D03*
X1097608Y630650D03*
X286250Y374862D03*
X183435Y630650D03*
G54D78*
X51043Y144095D03*
X57933Y66811D03*
X153405Y144095D03*
X160295Y66811D03*
X255767Y144095D03*
X262657Y66811D03*
X358129Y144095D03*
X365019Y66811D03*
X508130Y144095D03*
X515020Y66811D03*
X610492Y144095D03*
X617382Y66811D03*
X712854Y144095D03*
X719744Y66811D03*
X822106D03*
X972106D03*
X1074468D03*
X1176830D03*
X1272302Y144095D03*
X1279192Y66811D03*
X1422303Y144095D03*
X1429193Y66811D03*
X1524665Y144095D03*
X1531555Y66811D03*
X1633917D03*
X1736279D03*
G54D71*
X736447Y630650D03*
X1650620D03*
X1561585Y374862D03*
X1193533Y630650D03*
X1104498Y374862D03*
X279360Y630650D03*
X190325Y374862D03*
G54D70*
X1817323Y56693D03*
G54D69*
X924650Y1326119D03*
X370202Y1313064D03*
X559070Y686509D03*
X561570Y694509D03*
X559070Y702509D03*
X561570Y710509D03*
X559070Y718509D03*
X460950Y326485D03*
X463950Y334359D03*
X460950Y342233D03*
X463950Y350107D03*
X937000Y313983D03*
X66856Y105949D03*
X169218D03*
X271580D03*
X373942D03*
X893284Y235040D03*
X899352Y310261D03*
X1079748Y321042D03*
X1209184Y461917D03*
X1302896Y342096D03*
X1438116Y105949D03*
X1540478D03*
X1642840D03*
X1745202D03*
X1089096Y543562D03*
X1754906Y822634D03*
X917882Y326517D03*
X212980Y485254D03*
X205680Y478168D03*
X138290Y485260D03*
X148692Y478199D03*
X788482Y476118D03*
X778080Y483179D03*
X721092Y483210D03*
X713792Y476124D03*
X1245568Y476118D03*
X1235166Y483179D03*
X1178178Y483210D03*
X1170878Y476124D03*
X1584240Y485254D03*
X1576940Y478168D03*
X1519952Y478199D03*
X1509550Y485260D03*
X35688Y127128D03*
X28388Y120042D03*
Y134215D03*
X35688Y112955D03*
X130750Y120042D03*
Y134215D03*
X148692Y421047D03*
X138290Y413987D03*
X140690Y399813D03*
X148692Y406874D03*
Y392701D03*
X138050Y127128D03*
Y112955D03*
X138290Y471087D03*
Y442333D03*
Y428160D03*
X148692Y435221D03*
X205680Y399782D03*
X212980Y406868D03*
Y392695D03*
Y471081D03*
Y435215D03*
X205680Y442302D03*
Y428128D03*
Y413955D03*
X212980Y421041D03*
X233112Y134215D03*
Y120042D03*
X240412Y127128D03*
Y112955D03*
X342774Y127128D03*
X335474Y134215D03*
Y120042D03*
X342774Y112955D03*
X533092Y127096D03*
Y112923D03*
X543494Y134209D03*
Y120035D03*
X635454Y127096D03*
Y112923D03*
X645856Y134209D03*
Y120035D03*
X748218Y134209D03*
X737816Y127096D03*
X748218Y120035D03*
X737816Y112923D03*
X721092Y469037D03*
X778080Y469006D03*
X840178Y127096D03*
Y112923D03*
X850580Y134209D03*
Y120035D03*
X990178Y127096D03*
Y112923D03*
X1000580Y134209D03*
Y120035D03*
X1092540Y127096D03*
Y112923D03*
X1102942Y134209D03*
Y120035D03*
X1178178Y469037D03*
X1205304Y134209D03*
X1194902Y127096D03*
X1205304Y120035D03*
X1194902Y112923D03*
X1235166Y469006D03*
X1297264Y127096D03*
Y112923D03*
X1307666Y134209D03*
Y120035D03*
X1399648Y120042D03*
Y134215D03*
X1406948Y127128D03*
Y112955D03*
X1509310D03*
X1509550Y428160D03*
Y413987D03*
X1511950Y399813D03*
X1502010Y134215D03*
X1509310Y127128D03*
X1502010Y120042D03*
X1519952Y421047D03*
Y406874D03*
Y392701D03*
X1509550Y471087D03*
Y442333D03*
X1519952Y435221D03*
X1576940Y442302D03*
Y428128D03*
Y413955D03*
Y399782D03*
X1584240Y421041D03*
Y406868D03*
Y392695D03*
X1604372Y134215D03*
X1611672Y127128D03*
X1604372Y120042D03*
X1611672Y112955D03*
X1584240Y471081D03*
Y435215D03*
X1706734Y134215D03*
Y120042D03*
X1714034Y127128D03*
Y112955D03*
X148692Y536506D03*
Y522333D03*
X138290Y515221D03*
X148692Y492373D03*
X138290Y529394D03*
X205680Y492341D03*
Y536475D03*
X212980Y529388D03*
Y515215D03*
X205680Y522302D03*
X713792Y612817D03*
Y598644D03*
Y584471D03*
Y570297D03*
Y534431D03*
Y520258D03*
Y490297D03*
X721092Y591557D03*
Y577384D03*
Y563210D03*
Y527344D03*
Y513171D03*
Y605730D03*
X778080Y563179D03*
Y527313D03*
Y513139D03*
Y591525D03*
Y605699D03*
Y577352D03*
X788482Y570291D03*
Y534425D03*
Y520252D03*
Y490291D03*
Y612811D03*
Y598638D03*
Y584465D03*
X1170878Y612817D03*
Y598644D03*
Y584471D03*
Y570297D03*
Y534431D03*
Y520258D03*
Y490297D03*
X1178178Y563210D03*
Y527344D03*
Y513171D03*
Y605730D03*
Y591557D03*
Y577384D03*
X1235166Y527313D03*
Y513139D03*
Y605699D03*
Y591525D03*
Y577352D03*
Y563179D03*
X1245568Y570291D03*
Y534425D03*
Y520252D03*
Y490291D03*
Y612811D03*
Y598638D03*
Y584465D03*
X1509550Y529394D03*
Y515221D03*
X1519952Y536506D03*
Y522333D03*
Y492373D03*
X1576940Y536475D03*
Y522302D03*
Y492341D03*
X1584240Y529388D03*
Y515215D03*
X7982Y1527335D03*
G54D67*
X1592187Y-71006D03*
Y-81006D03*
X1582187Y-32086D03*
Y-42086D03*
X1736405Y-80978D03*
Y-70978D03*
X1801761Y-42188D03*
Y-32188D03*
X1517261Y-42058D03*
Y-32058D03*
X1481905Y-80978D03*
Y-70978D03*
X1230761Y-41928D03*
X1081187Y-71006D03*
X1337687D03*
Y-81006D03*
X1081187D03*
X1230761Y-31928D03*
X1225405Y-80978D03*
X1011187Y-31826D03*
X1297687Y-31956D03*
Y-41956D03*
X1225405Y-70978D03*
X1011187Y-41826D03*
X213969Y1460153D03*
Y1449153D03*
X227249Y1460153D03*
Y1449153D03*
G54D81*
X1817323Y1567323D03*
G54D68*
X1009333Y1344993D03*
X1015659Y681354D03*
X933725Y587636D03*
X933741Y596387D03*
X486837Y703006D03*
X394883Y340077D03*
X217907Y1428752D03*
X415203Y1497818D03*
X397267Y1516347D03*
X295011Y461917D03*
X523943Y105949D03*
X626305D03*
X728667D03*
X752097Y461917D03*
X831029Y105949D03*
X981029D03*
X1083391D03*
X1080351Y329955D03*
X1185753Y105949D03*
X1288115D03*
X1366535Y353200D03*
Y337452D03*
X1363535Y345326D03*
Y329578D03*
X1666271Y461919D03*
X174923Y543562D03*
X632009D03*
X1546183Y543564D03*
X385091Y1299153D03*
X454385Y1303545D03*
X940997Y333613D03*
X256705Y476124D03*
X264005Y483210D03*
X605779Y478199D03*
X595377Y485260D03*
X331395Y476118D03*
X320993Y483179D03*
X670067Y485254D03*
X662767Y478168D03*
X1127153Y485254D03*
X1119853Y478168D03*
X1062865Y478199D03*
X1052463Y485260D03*
X1702655Y476118D03*
X1692253Y483179D03*
X1635265Y483210D03*
X1627965Y476124D03*
X76005Y127096D03*
Y112923D03*
X86407Y120035D03*
Y134209D03*
X178367Y127096D03*
Y112923D03*
X188769Y134209D03*
Y120035D03*
X264005Y469037D03*
X291131Y134209D03*
Y120035D03*
X280729Y127096D03*
Y112923D03*
X320993Y469005D03*
X393493Y134209D03*
X383091Y127096D03*
X393493Y120035D03*
X383091Y112923D03*
X485475Y134215D03*
Y120042D03*
X492775Y127128D03*
Y112955D03*
X587837Y134215D03*
Y120042D03*
X597777Y399813D03*
X595137Y127128D03*
Y112955D03*
X595377Y471087D03*
Y442333D03*
Y428160D03*
Y413987D03*
X605779Y435221D03*
Y421047D03*
Y406874D03*
Y392701D03*
X670067Y435215D03*
X662767Y442302D03*
Y428128D03*
Y413955D03*
X670067Y421041D03*
X662767Y399782D03*
X670067Y406868D03*
Y392695D03*
Y471081D03*
X690199Y120042D03*
X697499Y127128D03*
X690199Y134215D03*
X697499Y112955D03*
X799861D03*
Y127128D03*
X792561Y120042D03*
Y134215D03*
X949861Y112955D03*
X942561Y120042D03*
Y134215D03*
X949861Y127128D03*
X1044923Y134215D03*
X1052223Y127128D03*
X1044923Y120042D03*
X1052223Y112955D03*
X1052463Y471087D03*
Y442333D03*
Y428160D03*
Y413987D03*
X1054863Y399813D03*
X1062865Y435221D03*
Y421047D03*
Y406874D03*
Y392701D03*
X1119853Y399782D03*
Y442302D03*
Y428128D03*
Y413955D03*
X1154585Y112955D03*
X1127153Y471081D03*
Y435215D03*
Y421041D03*
Y406868D03*
Y392695D03*
X1154585Y127128D03*
X1147285Y134215D03*
Y120042D03*
X1249647Y134215D03*
Y120042D03*
X1256947Y127128D03*
Y112955D03*
X1447265Y127096D03*
Y112923D03*
X1457667Y134209D03*
Y120035D03*
X1560029Y134209D03*
X1549627Y127096D03*
X1560029Y120035D03*
X1549627Y112923D03*
X1651989Y127096D03*
Y112923D03*
X1635265Y469037D03*
X1662391Y134209D03*
Y120035D03*
X1692253Y469006D03*
X1754351Y127096D03*
Y112923D03*
X1764753Y134209D03*
Y120035D03*
X264005Y513171D03*
X256705Y520258D03*
Y490297D03*
Y612817D03*
X264005Y591557D03*
Y605730D03*
X256705Y598644D03*
X264005Y577384D03*
X256705Y584471D03*
Y570297D03*
X264005Y563210D03*
X256705Y534431D03*
X264005Y527344D03*
X320993Y513139D03*
Y591525D03*
Y605699D03*
Y577352D03*
Y563179D03*
Y527313D03*
X331395Y490291D03*
Y612811D03*
Y598638D03*
Y584465D03*
Y570291D03*
Y534425D03*
Y520252D03*
X595377Y529394D03*
Y515221D03*
X605779Y536506D03*
Y522333D03*
Y492373D03*
X670067Y529388D03*
X662767Y536475D03*
Y522302D03*
X670067Y515215D03*
X662767Y492341D03*
X1052463Y529394D03*
Y515221D03*
X1062865Y536506D03*
Y522333D03*
Y492373D03*
X1119853Y536475D03*
Y522302D03*
Y492341D03*
X1127153Y529388D03*
Y515215D03*
X1627965Y584471D03*
Y570297D03*
Y534431D03*
Y520258D03*
Y490297D03*
Y612817D03*
Y598644D03*
X1635265Y527344D03*
Y513171D03*
Y605730D03*
Y591557D03*
Y577384D03*
Y563210D03*
X1692253Y605699D03*
Y591525D03*
Y577352D03*
Y563179D03*
Y527313D03*
Y513139D03*
X1702655Y534425D03*
Y520252D03*
Y490291D03*
Y612811D03*
Y598638D03*
Y584465D03*
Y570291D03*
G54D77*
X770472Y1490945D03*
X820079Y388583D03*
X1020866D03*
X1070472Y1490945D03*
G54D65*
X19685Y-83298D03*
X1821260D03*
X26789Y1373669D03*
X1796847Y1517889D03*
X1809883Y120792D03*
X184851Y334492D03*
X19685Y1801195D03*
X1821260D03*
G54D75*
X1030905Y1066535D03*
Y1263386D03*
X810038Y1066535D03*
Y1263386D03*
X573818Y1066535D03*
Y1263386D03*
X352952Y1066535D03*
Y1263386D03*
X116731Y1066535D03*
Y1263386D03*
X1724212Y1066535D03*
Y1263386D03*
X1487991Y1066535D03*
Y1263386D03*
X1267125Y1066535D03*
Y1263386D03*
%LPC*%
G75*
G36*
G01X175799Y1093897D02*
G02I-800J0D01*
G37*
G36*
G01Y1097637D02*
G02I-800J0D01*
G37*
G36*
G01X179540Y1101376D02*
G02I-800J0D01*
G37*
G36*
G01Y1105117D02*
G02I-800J0D01*
G37*
G36*
G01Y1228543D02*
G02I-800J0D01*
G37*
G36*
G01X172059Y1224803D02*
G02I-800J0D01*
G37*
G36*
G01X175799Y1232283D02*
G02I-800J0D01*
G37*
G36*
G01X172059Y1228543D02*
G02I-800J0D01*
G37*
G36*
G01X179540Y1224803D02*
G02I-800J0D01*
G37*
G36*
G01X175799Y1236023D02*
G02I-800J0D01*
G37*
G36*
G01X194500Y1105117D02*
G02I-800J0D01*
G37*
G36*
G01X198240Y1093897D02*
G02I-800J0D01*
G37*
G36*
G01X190760Y1097637D02*
G02I-800J0D01*
G37*
G36*
G01X187020Y1105117D02*
G02I-800J0D01*
G37*
G36*
G01X198240Y1097637D02*
G02I-800J0D01*
G37*
G36*
G01X183280Y1093897D02*
G02I-800J0D01*
G37*
G36*
G01Y1097637D02*
G02I-800J0D01*
G37*
G36*
G01X194500Y1101376D02*
G02I-800J0D01*
G37*
G36*
G01X187020D02*
G02I-800J0D01*
G37*
G36*
G01X190760Y1093897D02*
G02I-800J0D01*
G37*
G36*
G01X183280Y1236023D02*
G02I-800J0D01*
G37*
G36*
G01X198240D02*
G02I-800J0D01*
G37*
G36*
G01X187020Y1224803D02*
G02I-800J0D01*
G37*
G36*
G01X183280Y1232283D02*
G02I-800J0D01*
G37*
G36*
G01X194500Y1228543D02*
G02I-800J0D01*
G37*
G36*
G01X198240Y1232283D02*
G02I-800J0D01*
G37*
G36*
G01X190760Y1236023D02*
G02I-800J0D01*
G37*
G36*
G01X187020Y1228543D02*
G02I-800J0D01*
G37*
G36*
G01X194500Y1224803D02*
G02I-800J0D01*
G37*
G36*
G01X190760Y1232283D02*
G02I-800J0D01*
G37*
G36*
G01X205721Y1097637D02*
G02I-800J0D01*
G37*
G36*
G01X209461Y1101376D02*
G02I-800J0D01*
G37*
G36*
G01X213201Y1097637D02*
G02I-800J0D01*
G37*
G36*
G01X209461Y1105117D02*
G02I-800J0D01*
G37*
G36*
G01X213201Y1093897D02*
G02I-800J0D01*
G37*
G36*
G01X201981Y1101376D02*
G02I-800J0D01*
G37*
G36*
G01X205721Y1093897D02*
G02I-800J0D01*
G37*
G36*
G01X201981Y1105117D02*
G02I-800J0D01*
G37*
G36*
G01X205721Y1232283D02*
G02I-800J0D01*
G37*
G36*
G01X201981Y1224803D02*
G02I-800J0D01*
G37*
G36*
G01X213201Y1232283D02*
G02I-800J0D01*
G37*
G36*
G01X209461Y1228543D02*
G02I-800J0D01*
G37*
G36*
G01X213201Y1236023D02*
G02I-800J0D01*
G37*
G36*
G01X209461Y1224803D02*
G02I-800J0D01*
G37*
G36*
G01X201981Y1228543D02*
G02I-800J0D01*
G37*
G36*
G01X205721Y1236023D02*
G02I-800J0D01*
G37*
G36*
G01X209461Y1243503D02*
G02I-800J0D01*
G37*
G36*
G01X205721Y1250984D02*
G02I-800J0D01*
G37*
G36*
G01X209461Y1247243D02*
G02I-800J0D01*
G37*
G36*
G01X201981Y1243503D02*
G02I-800J0D01*
G37*
G36*
G01X213201Y1250984D02*
G02I-800J0D01*
G37*
G36*
G01X201981Y1247243D02*
G02I-800J0D01*
G37*
G36*
G01X213201Y1254724D02*
G02I-800J0D01*
G37*
G36*
G01X205721D02*
G02I-800J0D01*
G37*
G36*
G01X216941Y1101376D02*
G02I-800J0D01*
G37*
G36*
G01X228162Y1093897D02*
G02I-800J0D01*
G37*
G36*
G01X220681Y1097637D02*
G02I-800J0D01*
G37*
G36*
G01X224421Y1101376D02*
G02I-800J0D01*
G37*
G36*
G01Y1105117D02*
G02I-800J0D01*
G37*
G36*
G01X216941D02*
G02I-800J0D01*
G37*
G36*
G01X220681Y1093897D02*
G02I-800J0D01*
G37*
G36*
G01X228162Y1097637D02*
G02I-800J0D01*
G37*
G36*
G01X220681Y1232283D02*
G02I-800J0D01*
G37*
G36*
G01Y1236023D02*
G02I-800J0D01*
G37*
G36*
G01X216941Y1224803D02*
G02I-800J0D01*
G37*
G36*
G01X224422D02*
G02I-800J0D01*
G37*
G36*
G01X228162Y1232283D02*
G02I-800J0D01*
G37*
G36*
G01X224422Y1228543D02*
G02I-800J0D01*
G37*
G36*
G01X216941D02*
G02I-800J0D01*
G37*
G36*
G01X228162Y1236023D02*
G02I-800J0D01*
G37*
G36*
G01X224422Y1243503D02*
G02I-800J0D01*
G37*
G36*
G01X216941Y1247243D02*
G02I-800J0D01*
G37*
G36*
G01X224422D02*
G02I-800J0D01*
G37*
G36*
G01X216941Y1243503D02*
G02I-800J0D01*
G37*
G36*
G01X220681Y1250984D02*
G02I-800J0D01*
G37*
G36*
G01X228162D02*
G02I-800J0D01*
G37*
G36*
G01X220681Y1254724D02*
G02I-800J0D01*
G37*
G36*
G01X228162D02*
G02I-800J0D01*
G37*
G36*
G01X231902Y1101376D02*
G02I-800J0D01*
G37*
G36*
G01X235641Y1093897D02*
G02I-800J0D01*
G37*
G36*
G01X246862Y1105117D02*
G02I-800J0D01*
G37*
G36*
G01X243121Y1097637D02*
G02I-800J0D01*
G37*
G36*
G01X235641D02*
G02I-800J0D01*
G37*
G36*
G01X239382Y1101376D02*
G02I-800J0D01*
G37*
G36*
G01X246862D02*
G02I-800J0D01*
G37*
G36*
G01X239382Y1105117D02*
G02I-800J0D01*
G37*
G36*
G01X243121Y1093897D02*
G02I-800J0D01*
G37*
G36*
G01X231902Y1105117D02*
G02I-800J0D01*
G37*
G36*
G01X239382Y1247243D02*
G02I-800J0D01*
G37*
G36*
G01X246862Y1243503D02*
G02I-800J0D01*
G37*
G36*
G01X231902D02*
G02I-800J0D01*
G37*
G36*
G01X243122Y1250984D02*
G02I-800J0D01*
G37*
G36*
G01X235642D02*
G02I-800J0D01*
G37*
G36*
G01X246862Y1247243D02*
G02I-800J0D01*
G37*
G36*
G01X239382Y1243503D02*
G02I-800J0D01*
G37*
G36*
G01X231902Y1247243D02*
G02I-800J0D01*
G37*
G36*
G01X235642Y1254724D02*
G02I-800J0D01*
G37*
G36*
G01X243122D02*
G02I-800J0D01*
G37*
G36*
G01X250602Y1097637D02*
G02I-800J0D01*
G37*
G36*
G01X258082D02*
G02I-800J0D01*
G37*
G36*
G01X250602Y1093897D02*
G02I-800J0D01*
G37*
G36*
G01X254343Y1105117D02*
G02I-800J0D01*
G37*
G36*
G01Y1101376D02*
G02I-800J0D01*
G37*
G36*
G01X258082Y1093897D02*
G02I-800J0D01*
G37*
G36*
G01X261823Y1105117D02*
G02I-800J0D01*
G37*
G36*
G01Y1101376D02*
G02I-800J0D01*
G37*
G36*
G01X250603Y1250984D02*
G02I-800J0D01*
G37*
G36*
G01X258083D02*
G02I-800J0D01*
G37*
G36*
G01X254343Y1247243D02*
G02I-800J0D01*
G37*
G36*
G01Y1243503D02*
G02I-800J0D01*
G37*
G36*
G01X258083Y1254724D02*
G02I-800J0D01*
G37*
G36*
G01X250603D02*
G02I-800J0D01*
G37*
G36*
G01X265562Y1097637D02*
G02I-800J0D01*
G37*
G36*
G01X269303Y1105117D02*
G02I-800J0D01*
G37*
G36*
G01X273043Y1097637D02*
G02I-800J0D01*
G37*
G36*
G01X276784Y1105117D02*
G02I-800J0D01*
G37*
G36*
G01X280523Y1093897D02*
G02I-800J0D01*
G37*
G36*
G01X273043D02*
G02I-800J0D01*
G37*
G36*
G01X280523Y1097637D02*
G02I-800J0D01*
G37*
G36*
G01X269303Y1101376D02*
G02I-800J0D01*
G37*
G36*
G01X276784D02*
G02I-800J0D01*
G37*
G36*
G01X265562Y1093897D02*
G02I-800J0D01*
G37*
G36*
G01X284264Y1101376D02*
G02I-800J0D01*
G37*
G36*
G01X295484Y1093897D02*
G02I-800J0D01*
G37*
G36*
G01X288003D02*
G02I-800J0D01*
G37*
G36*
G01X295484Y1097637D02*
G02I-800J0D01*
G37*
G36*
G01X284264Y1105117D02*
G02I-800J0D01*
G37*
G36*
G01X291744Y1101376D02*
G02I-800J0D01*
G37*
G36*
G01Y1105117D02*
G02I-800J0D01*
G37*
G36*
G01X288003Y1097637D02*
G02I-800J0D01*
G37*
G36*
G01X295484Y1123818D02*
G02I-800J0D01*
G37*
G36*
G01Y1116338D02*
G02I-800J0D01*
G37*
G36*
G01Y1131299D02*
G02I-800J0D01*
G37*
G36*
G01X295485Y1198621D02*
G02I-800J0D01*
G37*
G36*
G01Y1213582D02*
G02I-800J0D01*
G37*
G36*
G01Y1206102D02*
G02I-800J0D01*
G37*
G36*
G01Y1236023D02*
G02I-800J0D01*
G37*
G36*
G01X291744Y1224803D02*
G02I-800J0D01*
G37*
G36*
G01X295485Y1232283D02*
G02I-800J0D01*
G37*
G36*
G01X291744Y1228543D02*
G02I-800J0D01*
G37*
G36*
G01X295485Y1250984D02*
G02I-800J0D01*
G37*
G36*
G01X291744Y1247243D02*
G02I-800J0D01*
G37*
G36*
G01Y1243503D02*
G02I-800J0D01*
G37*
G36*
G01X295485Y1254724D02*
G02I-800J0D01*
G37*
G36*
G01X299225Y1105117D02*
G02I-800J0D01*
G37*
G36*
G01Y1101376D02*
G02I-800J0D01*
G37*
G36*
G01X310444Y1097637D02*
G02I-800J0D01*
G37*
G36*
G01X302964D02*
G02I-800J0D01*
G37*
G36*
G01X306705Y1105117D02*
G02I-800J0D01*
G37*
G36*
G01X310444Y1093897D02*
G02I-800J0D01*
G37*
G36*
G01X306705Y1101376D02*
G02I-800J0D01*
G37*
G36*
G01X302964Y1093897D02*
G02I-800J0D01*
G37*
G36*
G01X302965Y1120078D02*
G02I-800J0D01*
G37*
G36*
G01X306705Y1112598D02*
G02I-800J0D01*
G37*
G36*
G01X299225Y1116338D02*
G02I-800J0D01*
G37*
G36*
G01X306705Y1120078D02*
G02I-800J0D01*
G37*
G36*
G01X302965Y1112598D02*
G02I-800J0D01*
G37*
G36*
G01X299225Y1123818D02*
G02I-800J0D01*
G37*
G36*
G01X306705Y1127559D02*
G02I-800J0D01*
G37*
G36*
G01Y1135039D02*
G02I-800J0D01*
G37*
G36*
G01X302965D02*
G02I-800J0D01*
G37*
G36*
G01Y1127559D02*
G02I-800J0D01*
G37*
G36*
G01X299225Y1131299D02*
G02I-800J0D01*
G37*
G36*
G01Y1198621D02*
G02I-800J0D01*
G37*
G36*
G01X306705Y1202362D02*
G02I-800J0D01*
G37*
G36*
G01X302965D02*
G02I-800J0D01*
G37*
G36*
G01X299225Y1213582D02*
G02I-800J0D01*
G37*
G36*
G01X306705Y1209842D02*
G02I-800J0D01*
G37*
G36*
G01Y1217322D02*
G02I-800J0D01*
G37*
G36*
G01X302965Y1209842D02*
G02I-800J0D01*
G37*
G36*
G01X299225Y1206102D02*
G02I-800J0D01*
G37*
G36*
G01X302965Y1217322D02*
G02I-800J0D01*
G37*
G36*
G01Y1232283D02*
G02I-800J0D01*
G37*
G36*
G01X310445D02*
G02I-800J0D01*
G37*
G36*
G01X299225Y1224803D02*
G02I-800J0D01*
G37*
G36*
G01Y1228543D02*
G02I-800J0D01*
G37*
G36*
G01X310445Y1236023D02*
G02I-800J0D01*
G37*
G36*
G01X306705Y1228543D02*
G02I-800J0D01*
G37*
G36*
G01Y1224803D02*
G02I-800J0D01*
G37*
G36*
G01X302965Y1236023D02*
G02I-800J0D01*
G37*
G36*
G01X299225Y1247243D02*
G02I-800J0D01*
G37*
G36*
G01X310445Y1250984D02*
G02I-800J0D01*
G37*
G36*
G01X299225Y1243503D02*
G02I-800J0D01*
G37*
G36*
G01X306705D02*
G02I-800J0D01*
G37*
G36*
G01Y1247243D02*
G02I-800J0D01*
G37*
G36*
G01X302965Y1250984D02*
G02I-800J0D01*
G37*
G36*
G01X310445Y1254724D02*
G02I-800J0D01*
G37*
G36*
G01X302965D02*
G02I-800J0D01*
G37*
G36*
G01X321666Y1090157D02*
G02I-800J0D01*
G37*
G36*
G01X325406D02*
G02I-800J0D01*
G37*
G36*
G01X314185Y1101377D02*
G02I-800J0D01*
G37*
G36*
G01X317925Y1093897D02*
G02I-800J0D01*
G37*
G36*
G01X321666Y1101377D02*
G02I-800J0D01*
G37*
G36*
G01X314185Y1105117D02*
G02I-800J0D01*
G37*
G36*
G01X325406Y1101377D02*
G02I-800J0D01*
G37*
G36*
G01X317925Y1097637D02*
G02I-800J0D01*
G37*
G36*
G01X321666Y1198621D02*
G02I-800J0D01*
G37*
G36*
G01X314185Y1202362D02*
G02I-800J0D01*
G37*
G36*
G01X325406Y1198621D02*
G02I-800J0D01*
G37*
G36*
G01X317925Y1202362D02*
G02I-800J0D01*
G37*
G36*
G01Y1217322D02*
G02I-800J0D01*
G37*
G36*
G01Y1209842D02*
G02I-800J0D01*
G37*
G36*
G01X325406Y1213582D02*
G02I-800J0D01*
G37*
G36*
G01X321666Y1221062D02*
G02I-800J0D01*
G37*
G36*
G01X314185Y1209842D02*
G02I-800J0D01*
G37*
G36*
G01X321666Y1206102D02*
G02I-800J0D01*
G37*
G36*
G01Y1213582D02*
G02I-800J0D01*
G37*
G36*
G01X325406Y1221062D02*
G02I-800J0D01*
G37*
G36*
G01Y1206102D02*
G02I-800J0D01*
G37*
G36*
G01X314185Y1217322D02*
G02I-800J0D01*
G37*
G36*
G01X317925Y1236023D02*
G02I-800J0D01*
G37*
G36*
G01X314185Y1224803D02*
G02I-800J0D01*
G37*
G36*
G01X325406Y1228543D02*
G02I-800J0D01*
G37*
G36*
G01X317925Y1232283D02*
G02I-800J0D01*
G37*
G36*
G01X314185Y1228543D02*
G02I-800J0D01*
G37*
G36*
G01X321666D02*
G02I-800J0D01*
G37*
G36*
G01X325406Y1239763D02*
G02I-800J0D01*
G37*
G36*
G01X314185Y1247243D02*
G02I-800J0D01*
G37*
G36*
G01X321666D02*
G02I-800J0D01*
G37*
G36*
G01X317925Y1250984D02*
G02I-800J0D01*
G37*
G36*
G01X321666Y1239763D02*
G02I-800J0D01*
G37*
G36*
G01X314185Y1243503D02*
G02I-800J0D01*
G37*
G36*
G01X325406Y1247243D02*
G02I-800J0D01*
G37*
G36*
G01X317925Y1254724D02*
G02I-800J0D01*
G37*
G36*
G01X602965Y1191141D02*
G02I-800J0D01*
G37*
G36*
G01Y1198621D02*
G02I-800J0D01*
G37*
G36*
G01Y1221062D02*
G02I-800J0D01*
G37*
G36*
G01Y1206102D02*
G02I-800J0D01*
G37*
G36*
G01Y1213582D02*
G02I-800J0D01*
G37*
G36*
G01Y1228543D02*
G02I-800J0D01*
G37*
G36*
G01Y1247243D02*
G02I-800J0D01*
G37*
G36*
G01Y1239763D02*
G02I-800J0D01*
G37*
G36*
G01X614186Y1187401D02*
G02I-800J0D01*
G37*
G36*
G01X610446D02*
G02I-800J0D01*
G37*
G36*
G01X621666D02*
G02I-800J0D01*
G37*
G36*
G01X606705Y1191141D02*
G02I-800J0D01*
G37*
G36*
G01X614186Y1194881D02*
G02I-800J0D01*
G37*
G36*
G01X606705Y1198621D02*
G02I-800J0D01*
G37*
G36*
G01X610446Y1194881D02*
G02I-800J0D01*
G37*
G36*
G01Y1202362D02*
G02I-800J0D01*
G37*
G36*
G01X614186D02*
G02I-800J0D01*
G37*
G36*
G01X621666D02*
G02I-800J0D01*
G37*
G36*
G01Y1194881D02*
G02I-800J0D01*
G37*
G36*
G01X614186Y1217322D02*
G02I-800J0D01*
G37*
G36*
G01X606705Y1221062D02*
G02I-800J0D01*
G37*
G36*
G01X610446Y1217322D02*
G02I-800J0D01*
G37*
G36*
G01Y1209842D02*
G02I-800J0D01*
G37*
G36*
G01X606705Y1206102D02*
G02I-800J0D01*
G37*
G36*
G01Y1213582D02*
G02I-800J0D01*
G37*
G36*
G01X621666Y1209842D02*
G02I-800J0D01*
G37*
G36*
G01X614186D02*
G02I-800J0D01*
G37*
G36*
G01X621666Y1217322D02*
G02I-800J0D01*
G37*
G36*
G01X606705Y1228543D02*
G02I-800J0D01*
G37*
G36*
G01X621666D02*
G02I-800J0D01*
G37*
G36*
G01Y1224803D02*
G02I-800J0D01*
G37*
G36*
G01X610446Y1232283D02*
G02I-800J0D01*
G37*
G36*
G01X617926Y1236023D02*
G02I-800J0D01*
G37*
G36*
G01X614186Y1228543D02*
G02I-800J0D01*
G37*
G36*
G01X617926Y1232283D02*
G02I-800J0D01*
G37*
G36*
G01X610446Y1236023D02*
G02I-800J0D01*
G37*
G36*
G01X614186Y1224803D02*
G02I-800J0D01*
G37*
G36*
G01X606705Y1247243D02*
G02I-800J0D01*
G37*
G36*
G01X617926Y1250984D02*
G02I-800J0D01*
G37*
G36*
G01X621666Y1243503D02*
G02I-800J0D01*
G37*
G36*
G01Y1247243D02*
G02I-800J0D01*
G37*
G36*
G01X614186D02*
G02I-800J0D01*
G37*
G36*
G01Y1243503D02*
G02I-800J0D01*
G37*
G36*
G01X610446Y1250984D02*
G02I-800J0D01*
G37*
G36*
G01X606705Y1239763D02*
G02I-800J0D01*
G37*
G36*
G01X610446Y1254724D02*
G02I-800J0D01*
G37*
G36*
G01X617926D02*
G02I-800J0D01*
G37*
G36*
G01X632886Y1097637D02*
G02I-800J0D01*
G37*
G36*
G01X636627Y1105117D02*
G02I-800J0D01*
G37*
G36*
G01X632886Y1093897D02*
G02I-800J0D01*
G37*
G36*
G01X636627Y1101376D02*
G02I-800J0D01*
G37*
G36*
G01X625406Y1187401D02*
G02I-800J0D01*
G37*
G36*
G01X629146Y1191141D02*
G02I-800J0D01*
G37*
G36*
G01X625406Y1194881D02*
G02I-800J0D01*
G37*
G36*
G01X632886Y1191141D02*
G02I-800J0D01*
G37*
G36*
G01X629146Y1198621D02*
G02I-800J0D01*
G37*
G36*
G01X625406Y1202362D02*
G02I-800J0D01*
G37*
G36*
G01X632886Y1198621D02*
G02I-800J0D01*
G37*
G36*
G01X629146Y1206102D02*
G02I-800J0D01*
G37*
G36*
G01X632886D02*
G02I-800J0D01*
G37*
G36*
G01X625406Y1217322D02*
G02I-800J0D01*
G37*
G36*
G01X629146Y1213582D02*
G02I-800J0D01*
G37*
G36*
G01X632886D02*
G02I-800J0D01*
G37*
G36*
G01X625406Y1209842D02*
G02I-800J0D01*
G37*
G36*
G01X629146Y1224803D02*
G02I-800J0D01*
G37*
G36*
G01Y1228543D02*
G02I-800J0D01*
G37*
G36*
G01X636627D02*
G02I-800J0D01*
G37*
G36*
G01X632886Y1232283D02*
G02I-800J0D01*
G37*
G36*
G01Y1236023D02*
G02I-800J0D01*
G37*
G36*
G01X625406Y1232283D02*
G02I-800J0D01*
G37*
G36*
G01Y1236023D02*
G02I-800J0D01*
G37*
G36*
G01X636627Y1224803D02*
G02I-800J0D01*
G37*
G36*
G01X625406Y1250984D02*
G02I-800J0D01*
G37*
G36*
G01X636627Y1243503D02*
G02I-800J0D01*
G37*
G36*
G01X632886Y1250984D02*
G02I-800J0D01*
G37*
G36*
G01X636627Y1247243D02*
G02I-800J0D01*
G37*
G36*
G01X629146Y1243503D02*
G02I-800J0D01*
G37*
G36*
G01Y1247243D02*
G02I-800J0D01*
G37*
G36*
G01X625406Y1254724D02*
G02I-800J0D01*
G37*
G36*
G01X632886D02*
G02I-800J0D01*
G37*
G36*
G01X651587Y1105117D02*
G02I-800J0D01*
G37*
G36*
G01X647847Y1093897D02*
G02I-800J0D01*
G37*
G36*
G01X640367Y1097637D02*
G02I-800J0D01*
G37*
G36*
G01X644107Y1105117D02*
G02I-800J0D01*
G37*
G36*
G01X647847Y1097637D02*
G02I-800J0D01*
G37*
G36*
G01X640367Y1093897D02*
G02I-800J0D01*
G37*
G36*
G01X644107Y1101376D02*
G02I-800J0D01*
G37*
G36*
G01X651587D02*
G02I-800J0D01*
G37*
G36*
G01X640367Y1236023D02*
G02I-800J0D01*
G37*
G36*
G01X647847D02*
G02I-800J0D01*
G37*
G36*
G01X640367Y1232283D02*
G02I-800J0D01*
G37*
G36*
G01X644107Y1224803D02*
G02I-800J0D01*
G37*
G36*
G01X647847Y1232283D02*
G02I-800J0D01*
G37*
G36*
G01X644107Y1228543D02*
G02I-800J0D01*
G37*
G36*
G01X651587D02*
G02I-800J0D01*
G37*
G36*
G01Y1224803D02*
G02I-800J0D01*
G37*
G36*
G01X640367Y1250984D02*
G02I-800J0D01*
G37*
G36*
G01X651587Y1247243D02*
G02I-800J0D01*
G37*
G36*
G01Y1243503D02*
G02I-800J0D01*
G37*
G36*
G01X647847Y1250984D02*
G02I-800J0D01*
G37*
G36*
G01X644107Y1247243D02*
G02I-800J0D01*
G37*
G36*
G01Y1243503D02*
G02I-800J0D01*
G37*
G36*
G01X640367Y1254724D02*
G02I-800J0D01*
G37*
G36*
G01X647847D02*
G02I-800J0D01*
G37*
G36*
G01X662808Y1097637D02*
G02I-800J0D01*
G37*
G36*
G01X655327Y1093897D02*
G02I-800J0D01*
G37*
G36*
G01X670288D02*
G02I-800J0D01*
G37*
G36*
G01X666548Y1105117D02*
G02I-800J0D01*
G37*
G36*
G01X655327Y1097637D02*
G02I-800J0D01*
G37*
G36*
G01X662808Y1093897D02*
G02I-800J0D01*
G37*
G36*
G01X670288Y1097637D02*
G02I-800J0D01*
G37*
G36*
G01X666548Y1101376D02*
G02I-800J0D01*
G37*
G36*
G01X659068Y1105117D02*
G02I-800J0D01*
G37*
G36*
G01Y1101376D02*
G02I-800J0D01*
G37*
G36*
G01X655327Y1236023D02*
G02I-800J0D01*
G37*
G36*
G01Y1232283D02*
G02I-800J0D01*
G37*
G36*
G01Y1250984D02*
G02I-800J0D01*
G37*
G36*
G01Y1254724D02*
G02I-800J0D01*
G37*
G36*
G01X674028Y1105117D02*
G02I-800J0D01*
G37*
G36*
G01X685249Y1093897D02*
G02I-800J0D01*
G37*
G36*
G01X677768D02*
G02I-800J0D01*
G37*
G36*
G01X685249Y1097637D02*
G02I-800J0D01*
G37*
G36*
G01X677768D02*
G02I-800J0D01*
G37*
G36*
G01X681508Y1105117D02*
G02I-800J0D01*
G37*
G36*
G01X674028Y1101376D02*
G02I-800J0D01*
G37*
G36*
G01X681508D02*
G02I-800J0D01*
G37*
G36*
G01X688989Y1105117D02*
G02I-800J0D01*
G37*
G36*
G01X696469Y1101376D02*
G02I-800J0D01*
G37*
G36*
G01X700208Y1097637D02*
G02I-800J0D01*
G37*
G36*
G01X696469Y1105117D02*
G02I-800J0D01*
G37*
G36*
G01X692728Y1093897D02*
G02I-800J0D01*
G37*
G36*
G01Y1097637D02*
G02I-800J0D01*
G37*
G36*
G01X700208Y1093897D02*
G02I-800J0D01*
G37*
G36*
G01X688989Y1101376D02*
G02I-800J0D01*
G37*
G36*
G01X715169Y1097637D02*
G02I-800J0D01*
G37*
G36*
G01X707689Y1093897D02*
G02I-800J0D01*
G37*
G36*
G01X703949Y1105117D02*
G02I-800J0D01*
G37*
G36*
G01X718910D02*
G02I-800J0D01*
G37*
G36*
G01Y1101376D02*
G02I-800J0D01*
G37*
G36*
G01X711430Y1105117D02*
G02I-800J0D01*
G37*
G36*
G01X715169Y1093897D02*
G02I-800J0D01*
G37*
G36*
G01X707689Y1097637D02*
G02I-800J0D01*
G37*
G36*
G01X703949Y1101376D02*
G02I-800J0D01*
G37*
G36*
G01X711430D02*
G02I-800J0D01*
G37*
G36*
G01X718910Y1228543D02*
G02I-800J0D01*
G37*
G36*
G01Y1224803D02*
G02I-800J0D01*
G37*
G36*
G01Y1243503D02*
G02I-800J0D01*
G37*
G36*
G01Y1247243D02*
G02I-800J0D01*
G37*
G36*
G01X726390Y1101376D02*
G02I-800J0D01*
G37*
G36*
G01X733871Y1105117D02*
G02I-800J0D01*
G37*
G36*
G01X726390D02*
G02I-800J0D01*
G37*
G36*
G01X722649Y1097637D02*
G02I-800J0D01*
G37*
G36*
G01Y1093897D02*
G02I-800J0D01*
G37*
G36*
G01X730130Y1097637D02*
G02I-800J0D01*
G37*
G36*
G01X733871Y1101376D02*
G02I-800J0D01*
G37*
G36*
G01X730130Y1093897D02*
G02I-800J0D01*
G37*
G36*
G01X726390Y1228543D02*
G02I-800J0D01*
G37*
G36*
G01X733871D02*
G02I-800J0D01*
G37*
G36*
G01X722650Y1236023D02*
G02I-800J0D01*
G37*
G36*
G01X733871Y1224803D02*
G02I-800J0D01*
G37*
G36*
G01X722650Y1232283D02*
G02I-800J0D01*
G37*
G36*
G01X726390Y1224803D02*
G02I-800J0D01*
G37*
G36*
G01X730131Y1236023D02*
G02I-800J0D01*
G37*
G36*
G01Y1232283D02*
G02I-800J0D01*
G37*
G36*
G01Y1250984D02*
G02I-800J0D01*
G37*
G36*
G01X733871Y1247243D02*
G02I-800J0D01*
G37*
G36*
G01X722650Y1250984D02*
G02I-800J0D01*
G37*
G36*
G01X726390Y1243503D02*
G02I-800J0D01*
G37*
G36*
G01X733871D02*
G02I-800J0D01*
G37*
G36*
G01X726390Y1247243D02*
G02I-800J0D01*
G37*
G36*
G01X722650Y1254724D02*
G02I-800J0D01*
G37*
G36*
G01X730131D02*
G02I-800J0D01*
G37*
G36*
G01X737610Y1097637D02*
G02I-800J0D01*
G37*
G36*
G01X748831Y1105117D02*
G02I-800J0D01*
G37*
G36*
G01X745090Y1093897D02*
G02I-800J0D01*
G37*
G36*
G01X741351Y1105117D02*
G02I-800J0D01*
G37*
G36*
G01X745090Y1097637D02*
G02I-800J0D01*
G37*
G36*
G01X737610Y1093897D02*
G02I-800J0D01*
G37*
G36*
G01X741351Y1101376D02*
G02I-800J0D01*
G37*
G36*
G01X748831D02*
G02I-800J0D01*
G37*
G36*
G01X745091Y1236023D02*
G02I-800J0D01*
G37*
G36*
G01X737611Y1232283D02*
G02I-800J0D01*
G37*
G36*
G01X745091D02*
G02I-800J0D01*
G37*
G36*
G01X737611Y1236023D02*
G02I-800J0D01*
G37*
G36*
G01X741351Y1224803D02*
G02I-800J0D01*
G37*
G36*
G01Y1228543D02*
G02I-800J0D01*
G37*
G36*
G01Y1243503D02*
G02I-800J0D01*
G37*
G36*
G01Y1247243D02*
G02I-800J0D01*
G37*
G36*
G01X745091Y1250984D02*
G02I-800J0D01*
G37*
G36*
G01X737611D02*
G02I-800J0D01*
G37*
G36*
G01X745091Y1254724D02*
G02I-800J0D01*
G37*
G36*
G01X737611D02*
G02I-800J0D01*
G37*
G36*
G01X752571Y1097637D02*
G02I-800J0D01*
G37*
G36*
G01X763792Y1101376D02*
G02I-800J0D01*
G37*
G36*
G01Y1105117D02*
G02I-800J0D01*
G37*
G36*
G01X756312D02*
G02I-800J0D01*
G37*
G36*
G01X760051Y1097637D02*
G02I-800J0D01*
G37*
G36*
G01Y1093897D02*
G02I-800J0D01*
G37*
G36*
G01X767531Y1097637D02*
G02I-800J0D01*
G37*
G36*
G01X756312Y1101376D02*
G02I-800J0D01*
G37*
G36*
G01X767531Y1093897D02*
G02I-800J0D01*
G37*
G36*
G01X752571D02*
G02I-800J0D01*
G37*
G36*
G01X756312Y1123818D02*
G02I-800J0D01*
G37*
G36*
G01X760052Y1112598D02*
G02I-800J0D01*
G37*
G36*
G01X752571Y1123818D02*
G02I-800J0D01*
G37*
G36*
G01X763792Y1112598D02*
G02I-800J0D01*
G37*
G36*
G01X756312Y1116338D02*
G02I-800J0D01*
G37*
G36*
G01X752571D02*
G02I-800J0D01*
G37*
G36*
G01X760052Y1120078D02*
G02I-800J0D01*
G37*
G36*
G01X763792D02*
G02I-800J0D01*
G37*
G36*
G01X752571Y1131299D02*
G02I-800J0D01*
G37*
G36*
G01X763792Y1135039D02*
G02I-800J0D01*
G37*
G36*
G01X756312Y1131299D02*
G02I-800J0D01*
G37*
G36*
G01X763792Y1127559D02*
G02I-800J0D01*
G37*
G36*
G01X760052Y1135039D02*
G02I-800J0D01*
G37*
G36*
G01Y1127559D02*
G02I-800J0D01*
G37*
G36*
G01X782493Y1090157D02*
G02I-800J0D01*
G37*
G36*
G01X778753D02*
G02I-800J0D01*
G37*
G36*
G01X771272Y1101377D02*
G02I-800J0D01*
G37*
G36*
G01X782493D02*
G02I-800J0D01*
G37*
G36*
G01X778753D02*
G02I-800J0D01*
G37*
G36*
G01X775012Y1097637D02*
G02I-800J0D01*
G37*
G36*
G01X771272Y1105117D02*
G02I-800J0D01*
G37*
G36*
G01X775012Y1093897D02*
G02I-800J0D01*
G37*
G36*
G01X940026Y1577634D02*
G03X940910Y1577268I884J885D01*
G01X956342D01*
G02X956484Y1577209I0J-200D01*
G01X959830Y1573863D01*
G02X959889Y1573721I-141J-142D01*
G01Y1543680D01*
G03X960255Y1542796I1251J0D01*
G01X964295Y1538756D01*
G03X965179Y1538390I884J885D01*
G01X1019906D01*
G02X1020048Y1538331I0J-200D01*
G01X1031515Y1526864D01*
G02X1031574Y1526722I-141J-142D01*
G01Y1492904D01*
G02X1031515Y1492762I-200J0D01*
G01X1031368Y1492615D01*
G02X1031226Y1492556I-142J141D01*
G01X947183D01*
G02X947041Y1492615I0J200D01*
G01X944876Y1494780D01*
G03X943992Y1495146I-884J-885D01*
G01X933579D01*
G03X932695Y1494780I0J-1251D01*
G01X917141Y1479226D01*
G03X916775Y1478342I885J-884D01*
G01Y1465020D01*
G02X916716Y1464878I-200J0D01*
G01X914188Y1462350D01*
G03X913822Y1461466I885J-884D01*
G01Y1460928D01*
G02X913763Y1460786I-200J0D01*
G01X913527Y1460550D01*
G03X913161Y1459666I885J-884D01*
G01Y1446448D01*
G02X913102Y1446306I-200J0D01*
G01X912955Y1446159D01*
G02X912813Y1446100I-142J141D01*
G01X900559D01*
G02X900417Y1446159I0J200D01*
G01X900270Y1446306D01*
G02X900211Y1446448I141J142D01*
G01Y1459640D01*
G03X899845Y1460524I-1251J0D01*
G01X899532Y1460837D01*
G02X899473Y1460979I141J142D01*
G01Y1462024D01*
G03X899107Y1462908I-1251J0D01*
G01X894403Y1467612D01*
G02X894344Y1467754I141J142D01*
G01Y1473096D01*
G03X893978Y1473980I-1251J0D01*
G01X888953Y1479005D01*
G03X888069Y1479371I-884J-885D01*
G01X880504D01*
G03X879620Y1479005I0J-1251D01*
G01X872265Y1471650D01*
G03X871899Y1470766I885J-884D01*
G01Y1460991D01*
G02X871840Y1460849I-200J0D01*
G01X871502Y1460511D01*
G03X871136Y1459627I885J-884D01*
G01Y1446423D01*
G02X871077Y1446281I-200J0D01*
G01X870968Y1446172D01*
G02X870826Y1446113I-142J141D01*
G01X858702D01*
G02X858560Y1446172I0J200D01*
G01X858139Y1446593D01*
G02X858080Y1446735I141J142D01*
G01Y1459524D01*
G03X857714Y1460408I-1251J0D01*
G01X853660Y1464462D01*
G03X852776Y1464828I-884J-885D01*
G01X828441D01*
G03X827557Y1464462I0J-1251D01*
G01X827039Y1463944D01*
G03X826673Y1463060I885J-884D01*
G01Y1461847D01*
G02X826614Y1461705I-200J0D01*
G01X826571Y1461662D01*
G02X826429Y1461603I-142J141D01*
G01X825036D01*
G03X824152Y1461237I0J-1251D01*
G01X821533Y1458618D01*
G02X821391Y1458559I-142J141D01*
G01X820451D01*
G03X819567Y1458193I0J-1251D01*
G01X819360Y1457986D01*
G03X818994Y1457102I885J-884D01*
G01Y1446462D01*
G02X818935Y1446320I-200J0D01*
G01X818826Y1446211D01*
G02X818684Y1446152I-142J141D01*
G01X806393D01*
G02X806251Y1446211I0J200D01*
G01X806063Y1446399D01*
G02X806004Y1446541I141J142D01*
G01Y1459828D01*
G02X806063Y1459970I200J0D01*
G01X806195Y1460102D01*
G03X806561Y1460986I-885J884D01*
G01Y1474310D01*
G02X806615Y1474447I200J0D01*
G03X806950Y1475299I-916J852D01*
G01Y1523715D01*
G02X807009Y1523857I200J0D01*
G01X816830Y1533678D01*
G03X817196Y1534562I-885J884D01*
G01Y1620853D01*
G02X817255Y1620995I200J0D01*
G01X822528Y1626268D01*
G02X822670Y1626327I142J-141D01*
G01X927565D01*
G02X927707Y1626268I0J-200D01*
G01X932114Y1621861D01*
G02X932173Y1621719I-141J-142D01*
G01Y1586005D01*
G03X932539Y1585121I1251J0D01*
G01X940026Y1577634D01*
G37*
G36*
G01X953110Y1480583D02*
G03X953130Y1480563I894J874D01*
G02X953192Y1480419I-138J-145D01*
G01Y1451442D01*
G02X953133Y1451300I-200J0D01*
G01X952668Y1450835D01*
G02X952526Y1450776I-142J141D01*
G01X930592D01*
G02X930450Y1450835I0J200D01*
G01X929621Y1451664D01*
G02X929562Y1451806I141J142D01*
G01Y1480891D01*
G02X929621Y1481033I200J0D01*
G01X930418Y1481830D01*
G02X930560Y1481889I142J-141D01*
G01X951737D01*
G02X951894Y1481812I-1J-200D01*
G03X951995Y1481698I984J770D01*
G01X953110Y1480583D01*
G37*
G36*
G01X955751Y1485453D02*
X957168Y1486870D01*
G02X957310Y1486929I142J-141D01*
G01X1045732D01*
G02X1045874Y1486870I0J-200D01*
G01X1046659Y1486085D01*
G02X1046718Y1485943I-141J-142D01*
G01Y1452303D01*
G02X1046659Y1452161I-200J0D01*
G01X1045333Y1450835D01*
G02X1045191Y1450776I-142J141D01*
G01X956304D01*
G02X956162Y1450835I0J200D01*
G01X955751Y1451246D01*
G02X955692Y1451388I141J142D01*
G01Y1485311D01*
G02X955751Y1485453I200J0D01*
G37*
G36*
G01X1089972Y1097637D02*
G02I-800J0D01*
G37*
G36*
G01Y1093897D02*
G02I-800J0D01*
G37*
G36*
G01Y1232283D02*
G02I-800J0D01*
G37*
G36*
G01Y1236023D02*
G02I-800J0D01*
G37*
G36*
G01X1086232Y1224803D02*
G02I-800J0D01*
G37*
G36*
G01Y1228543D02*
G02I-800J0D01*
G37*
G36*
G01X1093713Y1105116D02*
G02I-800J0D01*
G37*
G36*
G01X1104933Y1097637D02*
G02I-800J0D01*
G37*
G36*
G01X1097453D02*
G02I-800J0D01*
G37*
G36*
G01X1101193Y1105116D02*
G02I-800J0D01*
G37*
G36*
G01X1104933Y1093897D02*
G02I-800J0D01*
G37*
G36*
G01X1101193Y1101376D02*
G02I-800J0D01*
G37*
G36*
G01X1097453Y1093897D02*
G02I-800J0D01*
G37*
G36*
G01X1093713Y1101376D02*
G02I-800J0D01*
G37*
G36*
G01X1108673Y1105116D02*
G02I-800J0D01*
G37*
G36*
G01Y1101376D02*
G02I-800J0D01*
G37*
G36*
G01X1101193Y1228543D02*
G02I-800J0D01*
G37*
G36*
G01X1104933Y1236023D02*
G02I-800J0D01*
G37*
G36*
G01X1093713Y1224803D02*
G02I-800J0D01*
G37*
G36*
G01X1104933Y1232283D02*
G02I-800J0D01*
G37*
G36*
G01X1108673Y1224803D02*
G02I-800J0D01*
G37*
G36*
G01X1097453Y1236023D02*
G02I-800J0D01*
G37*
G36*
G01X1101193Y1224803D02*
G02I-800J0D01*
G37*
G36*
G01X1108673Y1228543D02*
G02I-800J0D01*
G37*
G36*
G01X1097453Y1232283D02*
G02I-800J0D01*
G37*
G36*
G01X1093713Y1228543D02*
G02I-800J0D01*
G37*
G36*
G01X1119894Y1097637D02*
G02I-800J0D01*
G37*
G36*
G01X1116154Y1101376D02*
G02I-800J0D01*
G37*
G36*
G01X1112413Y1093897D02*
G02I-800J0D01*
G37*
G36*
G01Y1097637D02*
G02I-800J0D01*
G37*
G36*
G01X1123634Y1105116D02*
G02I-800J0D01*
G37*
G36*
G01X1119894Y1093897D02*
G02I-800J0D01*
G37*
G36*
G01X1123634Y1101376D02*
G02I-800J0D01*
G37*
G36*
G01X1116154Y1105116D02*
G02I-800J0D01*
G37*
G36*
G01X1123634Y1224803D02*
G02I-800J0D01*
G37*
G36*
G01X1119894Y1232283D02*
G02I-800J0D01*
G37*
G36*
G01X1116154Y1228543D02*
G02I-800J0D01*
G37*
G36*
G01X1112413Y1232283D02*
G02I-800J0D01*
G37*
G36*
G01X1119894Y1236023D02*
G02I-800J0D01*
G37*
G36*
G01X1116154Y1224803D02*
G02I-800J0D01*
G37*
G36*
G01X1112413Y1236023D02*
G02I-800J0D01*
G37*
G36*
G01X1123634Y1228543D02*
G02I-800J0D01*
G37*
G36*
G01Y1243503D02*
G02I-800J0D01*
G37*
G36*
G01X1119894Y1250984D02*
G02I-800J0D01*
G37*
G36*
G01X1123634Y1247243D02*
G02I-800J0D01*
G37*
G36*
G01X1116154Y1243503D02*
G02I-800J0D01*
G37*
G36*
G01Y1247243D02*
G02I-800J0D01*
G37*
G36*
G01X1119894Y1254724D02*
G02I-800J0D01*
G37*
G36*
G01X1127374Y1093897D02*
G02I-800J0D01*
G37*
G36*
G01X1131114Y1105116D02*
G02I-800J0D01*
G37*
G36*
G01X1134854Y1093897D02*
G02I-800J0D01*
G37*
G36*
G01X1131114Y1101376D02*
G02I-800J0D01*
G37*
G36*
G01X1134854Y1097637D02*
G02I-800J0D01*
G37*
G36*
G01X1138594Y1105116D02*
G02I-800J0D01*
G37*
G36*
G01X1127374Y1097637D02*
G02I-800J0D01*
G37*
G36*
G01X1138594Y1101376D02*
G02I-800J0D01*
G37*
G36*
G01X1134854Y1236023D02*
G02I-800J0D01*
G37*
G36*
G01X1138595Y1228543D02*
G02I-800J0D01*
G37*
G36*
G01X1134854Y1232283D02*
G02I-800J0D01*
G37*
G36*
G01X1127374D02*
G02I-800J0D01*
G37*
G36*
G01Y1236023D02*
G02I-800J0D01*
G37*
G36*
G01X1138595Y1224803D02*
G02I-800J0D01*
G37*
G36*
G01X1131114Y1228543D02*
G02I-800J0D01*
G37*
G36*
G01Y1224803D02*
G02I-800J0D01*
G37*
G36*
G01X1138595Y1243503D02*
G02I-800J0D01*
G37*
G36*
G01X1131114Y1247243D02*
G02I-800J0D01*
G37*
G36*
G01X1127374Y1250984D02*
G02I-800J0D01*
G37*
G36*
G01X1138595Y1247243D02*
G02I-800J0D01*
G37*
G36*
G01X1131114Y1243503D02*
G02I-800J0D01*
G37*
G36*
G01X1134854Y1250984D02*
G02I-800J0D01*
G37*
G36*
G01X1127374Y1254724D02*
G02I-800J0D01*
G37*
G36*
G01X1134854D02*
G02I-800J0D01*
G37*
G36*
G01X1146075Y1105116D02*
G02I-800J0D01*
G37*
G36*
G01X1142335Y1093897D02*
G02I-800J0D01*
G37*
G36*
G01X1146075Y1101376D02*
G02I-800J0D01*
G37*
G36*
G01X1142335Y1097637D02*
G02I-800J0D01*
G37*
G36*
G01X1149814D02*
G02I-800J0D01*
G37*
G36*
G01X1157294Y1093897D02*
G02I-800J0D01*
G37*
G36*
G01X1153555Y1101376D02*
G02I-800J0D01*
G37*
G36*
G01X1157294Y1097637D02*
G02I-800J0D01*
G37*
G36*
G01X1149814Y1093897D02*
G02I-800J0D01*
G37*
G36*
G01X1153555Y1105116D02*
G02I-800J0D01*
G37*
G36*
G01X1142335Y1236023D02*
G02I-800J0D01*
G37*
G36*
G01Y1232283D02*
G02I-800J0D01*
G37*
G36*
G01Y1250984D02*
G02I-800J0D01*
G37*
G36*
G01X1146075Y1247243D02*
G02I-800J0D01*
G37*
G36*
G01X1153555Y1243503D02*
G02I-800J0D01*
G37*
G36*
G01X1146075D02*
G02I-800J0D01*
G37*
G36*
G01X1153555Y1247243D02*
G02I-800J0D01*
G37*
G36*
G01X1149815Y1250984D02*
G02I-800J0D01*
G37*
G36*
G01X1157295D02*
G02I-800J0D01*
G37*
G36*
G01X1142335Y1254724D02*
G02I-800J0D01*
G37*
G36*
G01X1149815D02*
G02I-800J0D01*
G37*
G36*
G01X1157295D02*
G02I-800J0D01*
G37*
G36*
G01X1161035Y1105116D02*
G02I-800J0D01*
G37*
G36*
G01Y1101376D02*
G02I-800J0D01*
G37*
G36*
G01X1172255Y1093897D02*
G02I-800J0D01*
G37*
G36*
G01X1168516Y1105116D02*
G02I-800J0D01*
G37*
G36*
G01X1172255Y1097637D02*
G02I-800J0D01*
G37*
G36*
G01X1164775Y1093897D02*
G02I-800J0D01*
G37*
G36*
G01Y1097637D02*
G02I-800J0D01*
G37*
G36*
G01X1168516Y1101376D02*
G02I-800J0D01*
G37*
G36*
G01X1172256Y1250984D02*
G02I-800J0D01*
G37*
G36*
G01X1168516Y1247243D02*
G02I-800J0D01*
G37*
G36*
G01X1164776Y1250984D02*
G02I-800J0D01*
G37*
G36*
G01X1161035Y1247243D02*
G02I-800J0D01*
G37*
G36*
G01Y1243503D02*
G02I-800J0D01*
G37*
G36*
G01X1168516D02*
G02I-800J0D01*
G37*
G36*
G01X1172256Y1254724D02*
G02I-800J0D01*
G37*
G36*
G01X1164776D02*
G02I-800J0D01*
G37*
G36*
G01X1179735Y1097637D02*
G02I-800J0D01*
G37*
G36*
G01X1187216Y1093897D02*
G02I-800J0D01*
G37*
G36*
G01X1183476Y1105116D02*
G02I-800J0D01*
G37*
G36*
G01X1175996D02*
G02I-800J0D01*
G37*
G36*
G01X1179735Y1093897D02*
G02I-800J0D01*
G37*
G36*
G01X1183476Y1101376D02*
G02I-800J0D01*
G37*
G36*
G01X1175996D02*
G02I-800J0D01*
G37*
G36*
G01X1187216Y1097637D02*
G02I-800J0D01*
G37*
G36*
G01X1202176Y1093897D02*
G02I-800J0D01*
G37*
G36*
G01X1194696Y1097637D02*
G02I-800J0D01*
G37*
G36*
G01X1198437Y1105116D02*
G02I-800J0D01*
G37*
G36*
G01X1205917D02*
G02I-800J0D01*
G37*
G36*
G01X1198437Y1101376D02*
G02I-800J0D01*
G37*
G36*
G01X1205917D02*
G02I-800J0D01*
G37*
G36*
G01X1190957D02*
G02I-800J0D01*
G37*
G36*
G01X1194696Y1093897D02*
G02I-800J0D01*
G37*
G36*
G01X1202176Y1097637D02*
G02I-800J0D01*
G37*
G36*
G01X1190957Y1105116D02*
G02I-800J0D01*
G37*
G36*
G01X1205917Y1228543D02*
G02I-800J0D01*
G37*
G36*
G01Y1224803D02*
G02I-800J0D01*
G37*
G36*
G01Y1243503D02*
G02I-800J0D01*
G37*
G36*
G01Y1247243D02*
G02I-800J0D01*
G37*
G36*
G01X1220878Y1105116D02*
G02I-800J0D01*
G37*
G36*
G01X1217137Y1093897D02*
G02I-800J0D01*
G37*
G36*
G01X1213398Y1101376D02*
G02I-800J0D01*
G37*
G36*
G01Y1105116D02*
G02I-800J0D01*
G37*
G36*
G01X1209657Y1093897D02*
G02I-800J0D01*
G37*
G36*
G01X1217137Y1097637D02*
G02I-800J0D01*
G37*
G36*
G01X1220878Y1101376D02*
G02I-800J0D01*
G37*
G36*
G01X1209657Y1097637D02*
G02I-800J0D01*
G37*
G36*
G01X1213398Y1123818D02*
G02I-800J0D01*
G37*
G36*
G01X1209658Y1116338D02*
G02I-800J0D01*
G37*
G36*
G01X1213398D02*
G02I-800J0D01*
G37*
G36*
G01X1217138Y1120078D02*
G02I-800J0D01*
G37*
G36*
G01Y1112598D02*
G02I-800J0D01*
G37*
G36*
G01X1209658Y1123818D02*
G02I-800J0D01*
G37*
G36*
G01X1220878Y1112598D02*
G02I-800J0D01*
G37*
G36*
G01Y1120078D02*
G02I-800J0D01*
G37*
G36*
G01X1217138Y1127559D02*
G02I-800J0D01*
G37*
G36*
G01Y1135039D02*
G02I-800J0D01*
G37*
G36*
G01X1213398Y1131299D02*
G02I-800J0D01*
G37*
G36*
G01X1209658D02*
G02I-800J0D01*
G37*
G36*
G01X1220878Y1135039D02*
G02I-800J0D01*
G37*
G36*
G01Y1127559D02*
G02I-800J0D01*
G37*
G36*
G01X1213398Y1198621D02*
G02I-800J0D01*
G37*
G36*
G01X1209658D02*
G02I-800J0D01*
G37*
G36*
G01X1217138Y1202362D02*
G02I-800J0D01*
G37*
G36*
G01X1220878D02*
G02I-800J0D01*
G37*
G36*
G01Y1217322D02*
G02I-800J0D01*
G37*
G36*
G01Y1209842D02*
G02I-800J0D01*
G37*
G36*
G01X1213398Y1206102D02*
G02I-800J0D01*
G37*
G36*
G01X1217138Y1217322D02*
G02I-800J0D01*
G37*
G36*
G01X1213398Y1213582D02*
G02I-800J0D01*
G37*
G36*
G01X1209658Y1206102D02*
G02I-800J0D01*
G37*
G36*
G01Y1213582D02*
G02I-800J0D01*
G37*
G36*
G01X1217138Y1209842D02*
G02I-800J0D01*
G37*
G36*
G01X1220878Y1224803D02*
G02I-800J0D01*
G37*
G36*
G01X1213398Y1228543D02*
G02I-800J0D01*
G37*
G36*
G01X1209658Y1232283D02*
G02I-800J0D01*
G37*
G36*
G01X1217138Y1236023D02*
G02I-800J0D01*
G37*
G36*
G01Y1232283D02*
G02I-800J0D01*
G37*
G36*
G01X1213398Y1224803D02*
G02I-800J0D01*
G37*
G36*
G01X1220878Y1228543D02*
G02I-800J0D01*
G37*
G36*
G01X1209658Y1236023D02*
G02I-800J0D01*
G37*
G36*
G01X1213398Y1243503D02*
G02I-800J0D01*
G37*
G36*
G01X1220878Y1247243D02*
G02I-800J0D01*
G37*
G36*
G01Y1243503D02*
G02I-800J0D01*
G37*
G36*
G01X1213398Y1247243D02*
G02I-800J0D01*
G37*
G36*
G01X1209658Y1250984D02*
G02I-800J0D01*
G37*
G36*
G01X1217138D02*
G02I-800J0D01*
G37*
G36*
G01X1209658Y1254724D02*
G02I-800J0D01*
G37*
G36*
G01X1217138D02*
G02I-800J0D01*
G37*
G36*
G01X1235839Y1090157D02*
G02I-800J0D01*
G37*
G36*
G01X1228358Y1101377D02*
G02I-800J0D01*
G37*
G36*
G01X1232098Y1093897D02*
G02I-800J0D01*
G37*
G36*
G01X1235839Y1101377D02*
G02I-800J0D01*
G37*
G36*
G01X1228358Y1105117D02*
G02I-800J0D01*
G37*
G36*
G01X1224617Y1093897D02*
G02I-800J0D01*
G37*
G36*
G01Y1097637D02*
G02I-800J0D01*
G37*
G36*
G01X1232098D02*
G02I-800J0D01*
G37*
G36*
G01Y1202362D02*
G02I-800J0D01*
G37*
G36*
G01X1235839Y1198621D02*
G02I-800J0D01*
G37*
G36*
G01X1228358Y1202362D02*
G02I-800J0D01*
G37*
G36*
G01X1235839Y1213582D02*
G02I-800J0D01*
G37*
G36*
G01X1232098Y1209842D02*
G02I-800J0D01*
G37*
G36*
G01X1228358D02*
G02I-800J0D01*
G37*
G36*
G01X1235839Y1221062D02*
G02I-800J0D01*
G37*
G36*
G01X1232098Y1217322D02*
G02I-800J0D01*
G37*
G36*
G01X1235839Y1206102D02*
G02I-800J0D01*
G37*
G36*
G01X1228358Y1217322D02*
G02I-800J0D01*
G37*
G36*
G01X1232098Y1232283D02*
G02I-800J0D01*
G37*
G36*
G01X1228358Y1228543D02*
G02I-800J0D01*
G37*
G36*
G01Y1224803D02*
G02I-800J0D01*
G37*
G36*
G01X1224618Y1236023D02*
G02I-800J0D01*
G37*
G36*
G01X1232098D02*
G02I-800J0D01*
G37*
G36*
G01X1235839Y1228543D02*
G02I-800J0D01*
G37*
G36*
G01X1224618Y1232283D02*
G02I-800J0D01*
G37*
G36*
G01X1228358Y1247243D02*
G02I-800J0D01*
G37*
G36*
G01X1224618Y1250984D02*
G02I-800J0D01*
G37*
G36*
G01X1235839Y1239763D02*
G02I-800J0D01*
G37*
G36*
G01X1228358Y1243503D02*
G02I-800J0D01*
G37*
G36*
G01X1232098Y1250984D02*
G02I-800J0D01*
G37*
G36*
G01X1235839Y1247243D02*
G02I-800J0D01*
G37*
G36*
G01X1232098Y1254724D02*
G02I-800J0D01*
G37*
G36*
G01X1224618D02*
G02I-800J0D01*
G37*
G36*
G01X1239579Y1090157D02*
G02I-800J0D01*
G37*
G36*
G01Y1101377D02*
G02I-800J0D01*
G37*
G36*
G01Y1198621D02*
G02I-800J0D01*
G37*
G36*
G01Y1221062D02*
G02I-800J0D01*
G37*
G36*
G01Y1206102D02*
G02I-800J0D01*
G37*
G36*
G01Y1213582D02*
G02I-800J0D01*
G37*
G36*
G01Y1228543D02*
G02I-800J0D01*
G37*
G36*
G01Y1247243D02*
G02I-800J0D01*
G37*
G36*
G01Y1239763D02*
G02I-800J0D01*
G37*
G36*
G01X1524619Y1187401D02*
G02I-800J0D01*
G37*
G36*
G01X1528359D02*
G02I-800J0D01*
G37*
G36*
G01X1517138Y1198621D02*
G02I-800J0D01*
G37*
G36*
G01X1524619Y1194881D02*
G02I-800J0D01*
G37*
G36*
G01X1520878Y1198621D02*
G02I-800J0D01*
G37*
G36*
G01X1524619Y1202362D02*
G02I-800J0D01*
G37*
G36*
G01X1517138Y1191141D02*
G02I-800J0D01*
G37*
G36*
G01X1528359Y1202362D02*
G02I-800J0D01*
G37*
G36*
G01Y1194881D02*
G02I-800J0D01*
G37*
G36*
G01X1520878Y1191141D02*
G02I-800J0D01*
G37*
G36*
G01Y1221062D02*
G02I-800J0D01*
G37*
G36*
G01X1517138Y1213582D02*
G02I-800J0D01*
G37*
G36*
G01Y1206102D02*
G02I-800J0D01*
G37*
G36*
G01X1520878D02*
G02I-800J0D01*
G37*
G36*
G01X1528359Y1217322D02*
G02I-800J0D01*
G37*
G36*
G01X1524619Y1209842D02*
G02I-800J0D01*
G37*
G36*
G01X1517138Y1221062D02*
G02I-800J0D01*
G37*
G36*
G01X1528359Y1209842D02*
G02I-800J0D01*
G37*
G36*
G01X1524619Y1217322D02*
G02I-800J0D01*
G37*
G36*
G01X1520878Y1213582D02*
G02I-800J0D01*
G37*
G36*
G01X1528359Y1228543D02*
G02I-800J0D01*
G37*
G36*
G01X1517138D02*
G02I-800J0D01*
G37*
G36*
G01X1524619Y1232283D02*
G02I-800J0D01*
G37*
G36*
G01X1520878Y1228543D02*
G02I-800J0D01*
G37*
G36*
G01X1524619Y1236023D02*
G02I-800J0D01*
G37*
G36*
G01X1528359Y1224803D02*
G02I-800J0D01*
G37*
G36*
G01X1517138Y1239763D02*
G02I-800J0D01*
G37*
G36*
G01X1520878D02*
G02I-800J0D01*
G37*
G36*
G01Y1247243D02*
G02I-800J0D01*
G37*
G36*
G01X1517138D02*
G02I-800J0D01*
G37*
G36*
G01X1528359Y1243503D02*
G02I-800J0D01*
G37*
G36*
G01Y1247243D02*
G02I-800J0D01*
G37*
G36*
G01X1524619Y1250984D02*
G02I-800J0D01*
G37*
G36*
G01Y1254724D02*
G02I-800J0D01*
G37*
G36*
G01X1547059Y1097637D02*
G02I-800J0D01*
G37*
G36*
G01Y1093897D02*
G02I-800J0D01*
G37*
G36*
G01X1535839Y1187401D02*
G02I-800J0D01*
G37*
G36*
G01X1539579D02*
G02I-800J0D01*
G37*
G36*
G01X1543319Y1191141D02*
G02I-800J0D01*
G37*
G36*
G01X1539579Y1202362D02*
G02I-800J0D01*
G37*
G36*
G01X1535839Y1194881D02*
G02I-800J0D01*
G37*
G36*
G01X1543319Y1198621D02*
G02I-800J0D01*
G37*
G36*
G01X1547059D02*
G02I-800J0D01*
G37*
G36*
G01Y1191141D02*
G02I-800J0D01*
G37*
G36*
G01X1535839Y1202362D02*
G02I-800J0D01*
G37*
G36*
G01X1539579Y1194881D02*
G02I-800J0D01*
G37*
G36*
G01X1543319Y1213582D02*
G02I-800J0D01*
G37*
G36*
G01Y1206102D02*
G02I-800J0D01*
G37*
G36*
G01X1547059Y1213582D02*
G02I-800J0D01*
G37*
G36*
G01X1535839Y1209842D02*
G02I-800J0D01*
G37*
G36*
G01Y1217322D02*
G02I-800J0D01*
G37*
G36*
G01X1547059Y1206102D02*
G02I-800J0D01*
G37*
G36*
G01X1539579Y1209842D02*
G02I-800J0D01*
G37*
G36*
G01Y1217322D02*
G02I-800J0D01*
G37*
G36*
G01X1547059Y1232283D02*
G02I-800J0D01*
G37*
G36*
G01X1535839Y1224803D02*
G02I-800J0D01*
G37*
G36*
G01X1539579Y1236023D02*
G02I-800J0D01*
G37*
G36*
G01X1532099Y1232283D02*
G02I-800J0D01*
G37*
G36*
G01X1543319Y1228543D02*
G02I-800J0D01*
G37*
G36*
G01X1535839D02*
G02I-800J0D01*
G37*
G36*
G01X1547059Y1236023D02*
G02I-800J0D01*
G37*
G36*
G01X1543319Y1224803D02*
G02I-800J0D01*
G37*
G36*
G01X1532099Y1236023D02*
G02I-800J0D01*
G37*
G36*
G01X1539579Y1232283D02*
G02I-800J0D01*
G37*
G36*
G01X1547059Y1250984D02*
G02I-800J0D01*
G37*
G36*
G01X1543319Y1243503D02*
G02I-800J0D01*
G37*
G36*
G01Y1247243D02*
G02I-800J0D01*
G37*
G36*
G01X1539579Y1250984D02*
G02I-800J0D01*
G37*
G36*
G01X1535839Y1243503D02*
G02I-800J0D01*
G37*
G36*
G01X1532099Y1250984D02*
G02I-800J0D01*
G37*
G36*
G01X1535839Y1247243D02*
G02I-800J0D01*
G37*
G36*
G01X1547059Y1254724D02*
G02I-800J0D01*
G37*
G36*
G01X1539579D02*
G02I-800J0D01*
G37*
G36*
G01X1532099D02*
G02I-800J0D01*
G37*
G36*
G01X1558280Y1101376D02*
G02I-800J0D01*
G37*
G36*
G01X1562020Y1093897D02*
G02I-800J0D01*
G37*
G36*
G01X1558280Y1105116D02*
G02I-800J0D01*
G37*
G36*
G01X1562020Y1097637D02*
G02I-800J0D01*
G37*
G36*
G01X1550800Y1101376D02*
G02I-800J0D01*
G37*
G36*
G01Y1105116D02*
G02I-800J0D01*
G37*
G36*
G01X1554540Y1093897D02*
G02I-800J0D01*
G37*
G36*
G01Y1097637D02*
G02I-800J0D01*
G37*
G36*
G01Y1232283D02*
G02I-800J0D01*
G37*
G36*
G01X1550800Y1228543D02*
G02I-800J0D01*
G37*
G36*
G01X1554540Y1236023D02*
G02I-800J0D01*
G37*
G36*
G01X1550800Y1224803D02*
G02I-800J0D01*
G37*
G36*
G01X1558280Y1228543D02*
G02I-800J0D01*
G37*
G36*
G01X1562020Y1236023D02*
G02I-800J0D01*
G37*
G36*
G01Y1232283D02*
G02I-800J0D01*
G37*
G36*
G01X1558280Y1224803D02*
G02I-800J0D01*
G37*
G36*
G01X1562020Y1250984D02*
G02I-800J0D01*
G37*
G36*
G01X1550800Y1243503D02*
G02I-800J0D01*
G37*
G36*
G01X1558280Y1247243D02*
G02I-800J0D01*
G37*
G36*
G01X1550800D02*
G02I-800J0D01*
G37*
G36*
G01X1558280Y1243503D02*
G02I-800J0D01*
G37*
G36*
G01X1554540Y1250984D02*
G02I-800J0D01*
G37*
G36*
G01X1562020Y1254724D02*
G02I-800J0D01*
G37*
G36*
G01X1554540D02*
G02I-800J0D01*
G37*
G36*
G01X1565760Y1105116D02*
G02I-800J0D01*
G37*
G36*
G01X1576981Y1097637D02*
G02I-800J0D01*
G37*
G36*
G01X1569500D02*
G02I-800J0D01*
G37*
G36*
G01X1576981Y1093897D02*
G02I-800J0D01*
G37*
G36*
G01X1569500D02*
G02I-800J0D01*
G37*
G36*
G01X1573241Y1101376D02*
G02I-800J0D01*
G37*
G36*
G01Y1105116D02*
G02I-800J0D01*
G37*
G36*
G01X1565760Y1101376D02*
G02I-800J0D01*
G37*
G36*
G01X1569500Y1236023D02*
G02I-800J0D01*
G37*
G36*
G01X1565760Y1224803D02*
G02I-800J0D01*
G37*
G36*
G01Y1228543D02*
G02I-800J0D01*
G37*
G36*
G01X1569500Y1232283D02*
G02I-800J0D01*
G37*
G36*
G01X1565760Y1243503D02*
G02I-800J0D01*
G37*
G36*
G01Y1247243D02*
G02I-800J0D01*
G37*
G36*
G01X1569500Y1250984D02*
G02I-800J0D01*
G37*
G36*
G01Y1254724D02*
G02I-800J0D01*
G37*
G36*
G01X1595681Y1105116D02*
G02I-800J0D01*
G37*
G36*
G01X1591941Y1097637D02*
G02I-800J0D01*
G37*
G36*
G01X1584461Y1093897D02*
G02I-800J0D01*
G37*
G36*
G01X1595681Y1101376D02*
G02I-800J0D01*
G37*
G36*
G01X1584461Y1097637D02*
G02I-800J0D01*
G37*
G36*
G01X1588201Y1105116D02*
G02I-800J0D01*
G37*
G36*
G01X1580721Y1101376D02*
G02I-800J0D01*
G37*
G36*
G01X1591941Y1093897D02*
G02I-800J0D01*
G37*
G36*
G01X1588201Y1101376D02*
G02I-800J0D01*
G37*
G36*
G01X1580721Y1105116D02*
G02I-800J0D01*
G37*
G36*
G01X1606901Y1093897D02*
G02I-800J0D01*
G37*
G36*
G01X1603162Y1101376D02*
G02I-800J0D01*
G37*
G36*
G01X1599422Y1097637D02*
G02I-800J0D01*
G37*
G36*
G01Y1093897D02*
G02I-800J0D01*
G37*
G36*
G01X1603162Y1105116D02*
G02I-800J0D01*
G37*
G36*
G01X1610642Y1101376D02*
G02I-800J0D01*
G37*
G36*
G01Y1105116D02*
G02I-800J0D01*
G37*
G36*
G01X1606901Y1097637D02*
G02I-800J0D01*
G37*
G36*
G01X1621862Y1093897D02*
G02I-800J0D01*
G37*
G36*
G01X1618122Y1105116D02*
G02I-800J0D01*
G37*
G36*
G01Y1101376D02*
G02I-800J0D01*
G37*
G36*
G01X1614381Y1093897D02*
G02I-800J0D01*
G37*
G36*
G01Y1097637D02*
G02I-800J0D01*
G37*
G36*
G01X1625603Y1101376D02*
G02I-800J0D01*
G37*
G36*
G01Y1105116D02*
G02I-800J0D01*
G37*
G36*
G01X1621862Y1097637D02*
G02I-800J0D01*
G37*
G36*
G01X1640563Y1101376D02*
G02I-800J0D01*
G37*
G36*
G01X1629342Y1093897D02*
G02I-800J0D01*
G37*
G36*
G01X1636822D02*
G02I-800J0D01*
G37*
G36*
G01X1640563Y1105116D02*
G02I-800J0D01*
G37*
G36*
G01X1633083D02*
G02I-800J0D01*
G37*
G36*
G01Y1101376D02*
G02I-800J0D01*
G37*
G36*
G01X1636822Y1097637D02*
G02I-800J0D01*
G37*
G36*
G01X1644303D02*
G02I-800J0D01*
G37*
G36*
G01Y1093897D02*
G02I-800J0D01*
G37*
G36*
G01X1629342Y1097637D02*
G02I-800J0D01*
G37*
G36*
G01X1633083Y1228543D02*
G02I-800J0D01*
G37*
G36*
G01X1640563Y1224803D02*
G02I-800J0D01*
G37*
G36*
G01X1636823Y1236023D02*
G02I-800J0D01*
G37*
G36*
G01X1644304Y1232283D02*
G02I-800J0D01*
G37*
G36*
G01X1633083Y1224803D02*
G02I-800J0D01*
G37*
G36*
G01X1644304Y1236023D02*
G02I-800J0D01*
G37*
G36*
G01X1636823Y1232283D02*
G02I-800J0D01*
G37*
G36*
G01X1640563Y1228543D02*
G02I-800J0D01*
G37*
G36*
G01X1633083Y1243503D02*
G02I-800J0D01*
G37*
G36*
G01X1640563D02*
G02I-800J0D01*
G37*
G36*
G01X1636823Y1250984D02*
G02I-800J0D01*
G37*
G36*
G01X1633083Y1247243D02*
G02I-800J0D01*
G37*
G36*
G01X1644304Y1250984D02*
G02I-800J0D01*
G37*
G36*
G01X1640563Y1247243D02*
G02I-800J0D01*
G37*
G36*
G01X1636823Y1254724D02*
G02I-800J0D01*
G37*
G36*
G01X1644304D02*
G02I-800J0D01*
G37*
G36*
G01X1659263Y1097637D02*
G02I-800J0D01*
G37*
G36*
G01X1648044Y1101376D02*
G02I-800J0D01*
G37*
G36*
G01X1659263Y1093897D02*
G02I-800J0D01*
G37*
G36*
G01X1655524Y1105116D02*
G02I-800J0D01*
G37*
G36*
G01X1651783Y1093897D02*
G02I-800J0D01*
G37*
G36*
G01X1648044Y1105116D02*
G02I-800J0D01*
G37*
G36*
G01X1655524Y1101376D02*
G02I-800J0D01*
G37*
G36*
G01X1651783Y1097637D02*
G02I-800J0D01*
G37*
G36*
G01X1655524Y1228543D02*
G02I-800J0D01*
G37*
G36*
G01X1648044D02*
G02I-800J0D01*
G37*
G36*
G01X1659264Y1232283D02*
G02I-800J0D01*
G37*
G36*
G01X1655524Y1224803D02*
G02I-800J0D01*
G37*
G36*
G01X1659264Y1236023D02*
G02I-800J0D01*
G37*
G36*
G01X1651784D02*
G02I-800J0D01*
G37*
G36*
G01X1648044Y1224803D02*
G02I-800J0D01*
G37*
G36*
G01X1651784Y1232283D02*
G02I-800J0D01*
G37*
G36*
G01X1655524Y1243503D02*
G02I-800J0D01*
G37*
G36*
G01X1651784Y1250984D02*
G02I-800J0D01*
G37*
G36*
G01X1648044Y1247243D02*
G02I-800J0D01*
G37*
G36*
G01X1655524D02*
G02I-800J0D01*
G37*
G36*
G01X1648044Y1243503D02*
G02I-800J0D01*
G37*
G36*
G01X1659264Y1250984D02*
G02I-800J0D01*
G37*
G36*
G01X1651784Y1254724D02*
G02I-800J0D01*
G37*
G36*
G01X1659264D02*
G02I-800J0D01*
G37*
G36*
G01X1666744Y1093897D02*
G02I-800J0D01*
G37*
G36*
G01X1663004Y1105116D02*
G02I-800J0D01*
G37*
G36*
G01X1670485D02*
G02I-800J0D01*
G37*
G36*
G01X1674224Y1097637D02*
G02I-800J0D01*
G37*
G36*
G01X1670485Y1101376D02*
G02I-800J0D01*
G37*
G36*
G01X1674224Y1093897D02*
G02I-800J0D01*
G37*
G36*
G01X1666744Y1097637D02*
G02I-800J0D01*
G37*
G36*
G01X1663004Y1101376D02*
G02I-800J0D01*
G37*
G36*
G01X1674225Y1112598D02*
G02I-800J0D01*
G37*
G36*
G01X1666745Y1123818D02*
G02I-800J0D01*
G37*
G36*
G01X1674225Y1120078D02*
G02I-800J0D01*
G37*
G36*
G01X1670485Y1123818D02*
G02I-800J0D01*
G37*
G36*
G01X1666745Y1116338D02*
G02I-800J0D01*
G37*
G36*
G01X1670485D02*
G02I-800J0D01*
G37*
G36*
G01X1666745Y1131299D02*
G02I-800J0D01*
G37*
G36*
G01X1670485D02*
G02I-800J0D01*
G37*
G36*
G01X1674225Y1127559D02*
G02I-800J0D01*
G37*
G36*
G01Y1135039D02*
G02I-800J0D01*
G37*
G36*
G01X1692926Y1090157D02*
G02I-800J0D01*
G37*
G36*
G01Y1101377D02*
G02I-800J0D01*
G37*
G36*
G01X1685445D02*
G02I-800J0D01*
G37*
G36*
G01X1677965Y1105116D02*
G02I-800J0D01*
G37*
G36*
G01X1681704Y1097637D02*
G02I-800J0D01*
G37*
G36*
G01X1677965Y1101376D02*
G02I-800J0D01*
G37*
G36*
G01X1689185Y1097637D02*
G02I-800J0D01*
G37*
G36*
G01X1685445Y1105117D02*
G02I-800J0D01*
G37*
G36*
G01X1681704Y1093897D02*
G02I-800J0D01*
G37*
G36*
G01X1689185D02*
G02I-800J0D01*
G37*
G36*
G01X1677965Y1120078D02*
G02I-800J0D01*
G37*
G36*
G01Y1112598D02*
G02I-800J0D01*
G37*
G36*
G01Y1135039D02*
G02I-800J0D01*
G37*
G36*
G01Y1127559D02*
G02I-800J0D01*
G37*
G36*
G01X1696666Y1090157D02*
G02I-800J0D01*
G37*
G36*
G01Y1101377D02*
G02I-800J0D01*
G37*
%LPD*%
G75*
G54D15*
X7271Y70981D03*
X11011Y79720D03*
X8786Y88425D03*
X14264Y94236D03*
X10292D03*
X12786Y87903D03*
X18000Y90000D03*
X18298Y102141D03*
X8000Y102500D03*
X10131Y115473D03*
X15143Y115581D03*
X14996Y133034D03*
X11442Y132719D03*
X19855Y133000D03*
X9082Y135789D03*
X19855Y141362D03*
X11999Y141415D03*
X15948Y141267D03*
X10966Y162073D03*
Y159073D03*
X16909Y153263D03*
X12247Y166341D03*
X17313Y166937D03*
X21909Y153263D03*
X22335Y166721D03*
X16709Y175943D03*
X19572Y219470D03*
Y221970D03*
X10259Y218085D03*
X13059D03*
X19638Y226320D03*
X16859Y216385D03*
X19572Y216970D03*
X22599Y228646D03*
X18206Y244571D03*
X15586Y249108D03*
X13715Y259381D03*
X8970Y254871D03*
X18206Y264571D03*
X7036Y272371D03*
X8335Y280663D03*
X14807Y282181D03*
X15586Y269108D03*
X15499Y288542D03*
X17033Y1006819D03*
X14357Y1009906D03*
X20216Y1009748D03*
X14197Y1014205D03*
Y1017759D03*
X20197Y1014205D03*
Y1017759D03*
X12599Y1438143D03*
X16304Y1468196D03*
X15889Y1494254D03*
X10089D03*
X6489Y1501334D03*
X19745Y1508846D03*
X7983Y1529035D03*
Y1525635D03*
X19735Y1530499D03*
X19859Y1520657D03*
X6951Y1538547D03*
X18879Y1534334D03*
X10367Y1553080D03*
X32350Y67562D03*
X28442Y55340D03*
X32350Y59562D03*
Y63562D03*
X26588Y97667D03*
X35442D03*
X35048Y103411D03*
X22439Y102495D03*
X35207Y106561D03*
X22935Y162073D03*
Y159073D03*
X26565Y177448D03*
X32507Y180517D03*
X30567Y195176D03*
X28067D03*
X25567D03*
X33067D03*
X29585Y199248D03*
X32585D03*
X29921Y206806D03*
X32585Y202048D03*
X25648Y210509D03*
X28148D03*
X29585Y201748D03*
X27421Y206806D03*
X27340Y230556D03*
X36185Y230117D03*
X31595Y227824D03*
X32201Y238714D03*
X23844Y239299D03*
X21556Y232971D03*
X31682Y246874D03*
X33902Y244297D03*
X26325Y262078D03*
X25549Y256394D03*
X31682Y266874D03*
X29116Y281129D03*
X37117Y279991D03*
X25549Y276394D03*
X34845Y291756D03*
X26629Y295619D03*
X35650Y491982D03*
Y495982D03*
X30177Y534211D03*
X34359Y541135D03*
X34732Y534909D03*
X25819Y527726D03*
Y548726D03*
X34425Y546553D03*
X34448Y552726D03*
X25819Y544726D03*
X30123Y611071D03*
X27686Y621311D03*
X36494Y616905D03*
X36306Y622285D03*
X27686Y629311D03*
Y625311D03*
X36692Y633724D03*
X36575Y627713D03*
X35293Y662952D03*
X35250Y671508D03*
X34565Y699082D03*
X36529Y1006321D03*
X30479Y1006509D03*
X24456Y1006401D03*
X32093Y1009748D03*
X26155Y1009985D03*
X29197Y1014205D03*
X32197Y1017759D03*
X26197D03*
X35197Y1014205D03*
X21196Y1065529D03*
Y1063029D03*
X36089Y1062601D03*
Y1065101D03*
X35925Y1075663D03*
X33425D03*
X28996Y1065529D03*
X23796D03*
X26396D03*
Y1063029D03*
X23796D03*
X28996D03*
X28606Y1082678D03*
X23406D03*
X26006D03*
Y1080178D03*
X23406D03*
X28606D03*
X20806Y1082678D03*
Y1080178D03*
X21321Y1098769D03*
X26521D03*
X29121D03*
X23921D03*
Y1101335D03*
X29121D03*
X26521D03*
X21321D03*
X32574Y1111633D03*
X29874D03*
X27274D03*
X24674D03*
Y1121333D03*
X27274D03*
X29874D03*
X32574D03*
X24674Y1130333D03*
X21974D03*
X21209Y1138705D03*
X23709D03*
X31631Y1198651D03*
X29860Y1438552D03*
X23603Y1449735D03*
X29880Y1441702D03*
X35825Y1464845D03*
X33189Y1501373D03*
X22381Y1554152D03*
X26231Y1554167D03*
X45988Y90512D03*
X51550Y90615D03*
X48476Y180812D03*
X48643Y442919D03*
X48596Y451419D03*
X45643Y472905D03*
X41643Y473419D03*
X49643Y472905D03*
Y464419D03*
X41643Y464919D03*
X48390Y485128D03*
X51239Y485138D03*
X40009Y481467D03*
X43948Y492108D03*
X44563Y482165D03*
X39801Y504825D03*
X42301D03*
X44801D03*
X43804Y500202D03*
X45256Y495993D03*
X45293Y522569D03*
X39742Y517401D03*
X42242D03*
X44742D03*
X46993Y529169D03*
X41408Y531882D03*
X43908D03*
X45293Y525369D03*
X46408Y531882D03*
X38358Y531948D03*
X52869Y537958D03*
X46643Y555194D03*
X52869Y540458D03*
X43843Y555194D03*
X46643Y571194D03*
X43843D03*
Y563194D03*
X46643D03*
X51000Y581222D03*
X45400D03*
X48200D03*
X51000Y591215D03*
X45400D03*
X48200D03*
X51172Y607762D03*
X48372D03*
X45572D03*
Y610562D03*
X48372D03*
X51172D03*
X40362Y610548D03*
X54192Y633473D03*
X42172Y633716D03*
X49192Y628078D03*
X47179Y633736D03*
X37847Y662910D03*
X39549Y682108D03*
X36910D03*
X37804Y671508D03*
X40165Y699082D03*
X37365D03*
X49249Y837718D03*
X52349D03*
X46049D03*
X53549Y843118D03*
X52077Y905295D03*
X48429Y916430D03*
X47264Y919649D03*
X48683Y1006510D03*
X42470Y1006738D03*
X50541Y1009589D03*
X44999Y1009510D03*
X38823Y1009273D03*
X47197Y1014205D03*
X41197D03*
X44197Y1017759D03*
X38197D03*
X48704Y1017982D03*
X43889Y1062601D03*
X38689D03*
X41289D03*
Y1065101D03*
X38689D03*
X43889D03*
X47314Y1072228D03*
X41172Y1079064D03*
X46166Y1093757D03*
X39659Y1105100D03*
X42259D03*
X44859D03*
X47559D03*
X48585Y1123867D03*
X47559Y1114800D03*
X44859D03*
X42259D03*
X39659D03*
X48547Y1133688D03*
X51047D03*
X55188Y1205179D03*
X51023Y1201416D03*
X48842Y1211109D03*
X53479Y1216256D03*
X43198Y1254055D03*
X45698D03*
X48198D03*
X45698Y1251555D03*
X43198D03*
X48198D03*
X47621Y1343672D03*
X39225Y1464845D03*
X48089Y1501387D03*
X39095Y1501361D03*
X47074Y1555923D03*
X40951Y1555932D03*
X64785Y79993D03*
Y82593D03*
Y85193D03*
Y74793D03*
Y77393D03*
X64829Y92874D03*
X55871Y99961D03*
X55921Y95236D03*
X66856Y104249D03*
Y107649D03*
X66478Y162368D03*
X63878D03*
X69261Y211695D03*
Y208695D03*
X65189Y210713D03*
Y213213D03*
Y208213D03*
X54733Y212978D03*
Y215478D03*
Y207978D03*
Y210478D03*
X65189Y215713D03*
X57987Y258880D03*
X60562Y264180D03*
X58062D03*
X66956Y267526D03*
Y270026D03*
X54167Y457339D03*
X56667D03*
X65737Y445603D03*
X57857Y446071D03*
X56667Y459839D03*
X54167D03*
Y462339D03*
X56667D03*
X62224Y473045D03*
X67670Y464818D03*
X58224Y465004D03*
X63154Y462371D03*
X55124Y478625D03*
X53739Y485138D03*
X56239D03*
X56824Y482425D03*
X55124Y475825D03*
X62700Y491214D03*
X66403Y495487D03*
X62700Y493714D03*
X66403Y492987D03*
X68202Y537877D03*
X56572Y539731D03*
X68202Y542877D03*
Y545377D03*
Y540377D03*
X61330Y544895D03*
X56572Y542231D03*
X64130Y541895D03*
Y544895D03*
X61630Y541895D03*
X68188Y548358D03*
X64408Y582747D03*
X63859Y590801D03*
X67684Y597232D03*
X63684Y597130D03*
X67684Y605637D03*
X61854Y617853D03*
Y620653D03*
X53972Y607762D03*
Y610562D03*
X59684Y605443D03*
X63684D03*
X66530Y625013D03*
X58181Y627908D03*
X64692Y642184D03*
X56049Y827218D03*
X68649D03*
X69049Y847718D03*
X65549Y850718D03*
X68598Y859415D03*
X68778Y873821D03*
X63969Y869475D03*
X63930Y874694D03*
X68100Y910122D03*
X71528Y913190D03*
X64632Y901500D03*
X59962Y910251D03*
X53197Y1014205D03*
Y1017759D03*
X55699Y1072761D03*
X61588Y1074481D03*
X62109Y1087656D03*
Y1084656D03*
Y1079656D03*
Y1091656D03*
X60269Y1198820D03*
X63094Y1207604D03*
X55596Y1210466D03*
X68245Y1212054D03*
X58443Y1272257D03*
X54843Y1501625D03*
X60227Y1514751D03*
X60277Y1528395D03*
X55862Y1541791D03*
X65478Y1541980D03*
X60303Y1534436D03*
X60747Y1555890D03*
X64747D03*
X60864Y1583484D03*
X58064D03*
X55264D03*
X69816Y1592527D03*
X60554Y1615152D03*
X73110Y98551D03*
X77804Y95879D03*
X76005Y114623D03*
Y111223D03*
X76660Y103783D03*
X76005Y125396D03*
Y128796D03*
X75194Y141247D03*
X71422Y147540D03*
X82661Y143740D03*
X80041Y148277D03*
X73578Y165393D03*
Y162793D03*
Y170493D03*
Y167993D03*
X80502Y177616D03*
X81083Y172190D03*
X72575Y181426D03*
X75786Y181366D03*
X78581Y181009D03*
X83756Y168697D03*
X84844Y191941D03*
X75400Y184012D03*
X72783Y184221D03*
X72061Y208695D03*
X71761Y211695D03*
X76819Y213859D03*
Y211359D03*
X80522Y213132D03*
Y215632D03*
X80766Y256303D03*
X75438Y265701D03*
X85541Y266114D03*
X80525Y265896D03*
X72256Y267526D03*
X69756D03*
Y270026D03*
X72256D03*
X83014Y281982D03*
X77073Y281716D03*
X71130Y462152D03*
Y459652D03*
Y464652D03*
X73630Y459652D03*
Y462152D03*
Y464652D03*
X78033Y491133D03*
X71461Y498151D03*
Y495151D03*
X73961D03*
X78033Y498633D03*
Y496133D03*
Y493633D03*
X73961Y498151D03*
X78133Y553297D03*
Y555897D03*
X75688Y548358D03*
X73188D03*
X70688D03*
X78133Y558497D03*
Y566597D03*
Y563697D03*
Y561097D03*
X72128Y570686D03*
X74923Y570478D03*
X75340Y576484D03*
X74983Y573689D03*
X72337Y573303D03*
X78733Y578405D03*
X84159Y578986D03*
X83684Y596729D03*
X72515Y596089D03*
X77734Y596782D03*
X81740Y619758D03*
Y616958D03*
Y614158D03*
X69670Y619513D03*
Y616713D03*
Y613913D03*
X79684Y605443D03*
X82648Y670679D03*
X73914Y660107D03*
X79043Y667391D03*
X84845Y659857D03*
X84314Y686107D03*
X82562Y680037D03*
X78735Y683426D03*
X72149Y827318D03*
X74349Y824718D03*
Y821918D03*
X74700Y842890D03*
X84367Y878286D03*
X76528Y878533D03*
X74028Y889065D03*
X83079Y888515D03*
X72035Y898346D03*
X80339Y897943D03*
X76203Y897910D03*
X80593Y946082D03*
X78167Y949261D03*
X76332Y953421D03*
X87632Y1007522D03*
X70059Y1075656D03*
X70302Y1067656D03*
X77734Y1095676D03*
X70947Y1201565D03*
Y1205835D03*
X71006Y1228684D03*
X71020Y1224323D03*
X74909Y1593009D03*
X71910Y1625009D03*
X78291Y1625743D03*
X83689Y1624736D03*
X82291Y1633801D03*
X78291D03*
X70291D03*
X86407Y132509D03*
Y118335D03*
Y121735D03*
Y135909D03*
X91224Y141247D03*
X92337Y144172D03*
X95711Y143518D03*
X94811Y152373D03*
X97961Y152562D03*
X103456Y157370D03*
X98826Y172665D03*
X98763Y178560D03*
X98653Y183834D03*
X99639Y186629D03*
X98943Y200864D03*
X92898Y192490D03*
X98173Y190185D03*
X89353Y206767D03*
X86853D03*
X91853D03*
X98966Y207037D03*
X99032Y212455D03*
X89483Y221708D03*
X86983D03*
X86398Y224421D03*
X88098Y231021D03*
Y228221D03*
X96333Y221642D03*
X91983Y221708D03*
X103841Y228631D03*
X93649Y236189D03*
X91149D03*
X88649D03*
X91090Y248765D03*
X88590D03*
X93590D03*
X97747Y265897D03*
X100247D03*
X94087Y270695D03*
X91287D03*
X88787D03*
Y268195D03*
X91287D03*
X94087D03*
X98255Y374510D03*
X100120Y377898D03*
X100066Y381976D03*
X86788Y581659D03*
X87684Y605443D03*
X95973Y655660D03*
X92897Y658359D03*
X95917Y658374D03*
X95539Y664443D03*
X86289Y822088D03*
X86367Y848086D03*
X90000Y871389D03*
X103770Y868206D03*
X103692Y900295D03*
X91387Y905295D03*
X100058Y977651D03*
X99836Y980330D03*
X103836Y988813D03*
X100200Y988800D03*
X95836Y988813D03*
X85706Y998507D03*
X94398Y1006648D03*
X101025Y1009655D03*
X94586Y1023900D03*
X91765Y1018307D03*
X88007Y1013678D03*
X88479Y1023731D03*
X88287Y1026537D03*
X97609Y1018469D03*
X90450Y1033542D03*
X93496Y1547768D03*
X107364Y116594D03*
X118307Y110784D03*
X113307D03*
X107364Y119594D03*
X117886Y124663D03*
X112864Y124879D03*
X107798Y124283D03*
X119230Y138838D03*
X106205Y161306D03*
X107540Y176665D03*
Y168665D03*
Y196665D03*
Y192665D03*
X107653Y186778D03*
X107572Y204864D03*
Y208864D03*
X112621Y218085D03*
X115421D03*
X103213Y219379D03*
X117948Y249108D03*
X109329Y248371D03*
X111993Y710102D03*
X120250Y758841D03*
X113505Y796856D03*
X109591Y796905D03*
X102355Y874267D03*
X102947Y877196D03*
X102320Y891043D03*
X110887Y884000D03*
X103972Y977609D03*
X103836Y980330D03*
X111836Y988813D03*
X119836D03*
X115836D03*
X107836D03*
X103825Y1009655D03*
X105971Y1025745D03*
X114770Y1016827D03*
X110409Y1024094D03*
X114770Y1029427D03*
X110970Y1030672D03*
X101970D03*
X104970D03*
X107970D03*
X102761Y1096233D03*
X108971Y1109564D03*
X103124D03*
Y1122164D03*
X108971D03*
X103124Y1134764D03*
X108971D03*
X103124Y1147364D03*
X108971D03*
X103124Y1172564D03*
X108971D03*
X103124Y1159964D03*
X108971D03*
X103861Y1182703D03*
X118533Y1207737D03*
X112048Y1214372D03*
X107803Y1218169D03*
X128950Y97667D03*
X133200Y95111D03*
X124606Y102495D03*
X119333Y116594D03*
Y119594D03*
X122867Y125107D03*
X124340Y142862D03*
X131481Y143762D03*
X125381Y148717D03*
X131947Y199248D03*
X127929Y195176D03*
X130429D03*
X132929D03*
X134947Y199248D03*
X128010Y210509D03*
X130510D03*
X132283Y206806D03*
X129783D03*
X131947Y201748D03*
X122000Y226320D03*
X119221Y216385D03*
X121934Y216970D03*
Y219470D03*
Y221970D03*
X129702Y230556D03*
X133957Y227824D03*
X124961Y228646D03*
X128687Y242078D03*
X123918Y232971D03*
X134044Y246874D03*
X120568Y244571D03*
X127911Y256394D03*
X126131Y359511D03*
X125753Y365856D03*
X119099Y755052D03*
X118467Y796785D03*
X122437Y860775D03*
X125698Y857515D03*
X122432Y857540D03*
X129666Y857514D03*
X133424Y857303D03*
X122887Y888000D03*
X123387Y892000D03*
X135836Y988813D03*
X131836D03*
X123836D03*
X127836D03*
X120617Y1029427D03*
Y1016827D03*
X133579Y1097469D03*
X124925Y1102091D03*
X130380Y1105091D03*
X124880D03*
X124925Y1114691D03*
Y1127291D03*
X124880Y1117691D03*
X130380D03*
X124925Y1139891D03*
X124880Y1130291D03*
X130380D03*
X130434Y1144964D03*
X124474Y1142997D03*
X130380Y1155491D03*
X124880D03*
X124925Y1152491D03*
X124474Y1168197D03*
X130434Y1170164D03*
X124925Y1165091D03*
Y1177691D03*
X131000Y1180266D03*
X124765Y1180691D03*
X135757Y1221407D03*
X135448Y1229402D03*
Y1234921D03*
X126433Y1230407D03*
X129250Y1227650D03*
X137410Y103411D03*
X137804Y97667D03*
X148600Y90650D03*
X148350Y95236D03*
X137569Y106561D03*
X135429Y195176D03*
X134947Y202048D03*
X138547Y230117D03*
X134563Y238714D03*
X138664Y241699D03*
X148061Y378600D03*
X148692Y391001D03*
X148061Y382600D03*
X148692Y394401D03*
Y405174D03*
X140690Y401513D03*
Y398113D03*
X148692Y408574D03*
X138290Y412287D03*
X148692Y419347D03*
Y422747D03*
X138290Y415687D03*
Y426460D03*
X148692Y433521D03*
X138290Y429860D03*
X148692Y436921D03*
X138290Y440633D03*
X148176Y458711D03*
X138290Y444033D03*
X148940Y455921D03*
X145376Y458711D03*
X138290Y469387D03*
Y472787D03*
X147520Y463600D03*
X148692Y476499D03*
X138290Y483560D03*
X148692Y490673D03*
X138290Y486960D03*
X148692Y479899D03*
Y494073D03*
Y524033D03*
Y520633D03*
X138290Y516921D03*
Y513521D03*
Y531094D03*
X148692Y538206D03*
Y534806D03*
X138290Y527694D03*
X142024Y552466D03*
X147925Y603600D03*
Y619600D03*
Y623600D03*
X149469Y634190D03*
X152658Y645389D03*
X136862Y857244D03*
X147836Y988813D03*
X139836D03*
X151836D03*
X143836D03*
X142026Y1012354D03*
X136571Y1009354D03*
X136526Y1012354D03*
X136571Y1021954D03*
X142026Y1024954D03*
X136526D03*
X144640Y1039439D03*
X150952Y1040115D03*
X146595Y1053457D03*
X136432Y1224472D03*
X167191Y92874D03*
X153912Y90615D03*
X158283Y95236D03*
X158233Y99961D03*
X166240Y162368D03*
X157095Y210478D03*
Y207978D03*
Y215478D03*
Y212978D03*
X160424Y264180D03*
X162924D03*
X160349Y258880D03*
X164496Y309405D03*
X150703Y453682D03*
X159836Y988813D03*
X155836Y997860D03*
X160733Y1056594D03*
X153693Y1051037D03*
X160547Y1049283D03*
X160627Y1053561D03*
X160807Y1043955D03*
X166188Y1066551D03*
X163191Y1065313D03*
X159228Y1065613D03*
X165649Y1159350D03*
Y1151870D03*
X167147Y77393D03*
Y74793D03*
Y85193D03*
Y82593D03*
Y79993D03*
X175472Y98551D03*
X178367Y111223D03*
Y114623D03*
X179022Y103783D03*
X169218Y107649D03*
Y104249D03*
X178367Y128796D03*
Y125396D03*
X173784Y147540D03*
X177556Y141247D03*
X185023Y143740D03*
X182403Y148277D03*
X175940Y162793D03*
Y165393D03*
X168840Y162368D03*
X175940Y167993D03*
Y170493D03*
X178148Y181366D03*
X180943Y181009D03*
X174937Y181426D03*
X182864Y177616D03*
X183445Y172190D03*
X175145Y184221D03*
X177762Y184012D03*
X171623Y211695D03*
X182884Y213132D03*
X179181Y211359D03*
Y213859D03*
X174123Y211695D03*
X167551Y208213D03*
Y213213D03*
Y210713D03*
X171623Y208695D03*
X174423D03*
X167551Y215713D03*
X182884Y215632D03*
X177800Y265701D03*
X182887Y265896D03*
X174618Y267526D03*
Y270026D03*
X169318Y267526D03*
X172118D03*
Y270026D03*
X169318D03*
X179435Y281716D03*
X170215Y311671D03*
X175615Y550907D03*
X173115D03*
X175615Y553407D03*
X173115D03*
X174923Y545263D03*
Y541863D03*
X177385Y566929D03*
X171339Y572070D03*
X172686Y569928D03*
X175033Y570962D03*
X174776Y568475D03*
X177099Y569426D03*
X169389Y1155610D03*
X191568Y76587D03*
Y72615D03*
X193007Y100625D03*
X186026Y97475D03*
X185957Y106186D03*
X197380Y112083D03*
X188769Y118335D03*
Y121735D03*
Y132509D03*
Y135909D03*
X193586Y141247D03*
X198073Y143518D03*
X197173Y152373D03*
X201015Y183834D03*
X201125Y178560D03*
X186118Y168697D03*
X201188Y172665D03*
X187206Y191941D03*
X195260Y192490D03*
X200535Y190185D03*
X201305Y200864D03*
X189215Y206767D03*
X191715D03*
X194215D03*
X201394Y212455D03*
X201328Y207037D03*
X194345Y221708D03*
X198695Y221642D03*
X190460Y228221D03*
Y231021D03*
X191845Y221708D03*
X188760Y224421D03*
X189345Y221708D03*
X191011Y236189D03*
X193511D03*
X196011D03*
X190952Y248765D03*
X193452D03*
X195952D03*
X183128Y256303D03*
X187903Y266114D03*
X196449Y268195D03*
X193649D03*
X196449Y270695D03*
X193649D03*
X191149D03*
Y268195D03*
X185376Y281982D03*
X185328Y545528D03*
X194063Y577716D03*
X191125Y610400D03*
X203248Y55513D03*
X199473Y68581D03*
X205848Y60513D03*
X208645Y60369D03*
X199486Y80581D03*
X214389Y86012D03*
X203616Y88801D03*
X214389Y94374D03*
X206533Y94351D03*
X210482Y94279D03*
X209530Y86046D03*
X205976Y85731D03*
X209726Y116594D03*
X201669Y103621D03*
X215669Y110784D03*
X209726Y119594D03*
X210160Y124283D03*
X215226Y124879D03*
X208567Y161306D03*
X200323Y152562D03*
X205818Y157370D03*
X209902Y176665D03*
Y168665D03*
X202001Y186629D03*
X209902Y196665D03*
Y192665D03*
X210015Y186778D03*
X209934Y204864D03*
Y208864D03*
X214983Y218085D03*
X205575Y219379D03*
X206203Y228631D03*
X211691Y248371D03*
X200109Y265897D03*
X202609D03*
X204675Y382109D03*
X204674Y551683D03*
Y558917D03*
Y561420D03*
X200495Y577937D03*
X208500Y595500D03*
X203500Y606929D03*
X208000Y604567D03*
X203460Y618400D03*
X203741Y612592D03*
X209158Y610072D03*
X209094Y616317D03*
X208540Y621591D03*
X205941Y668934D03*
X201115Y695581D03*
X203046Y693716D03*
X213969Y1447453D03*
Y1461853D03*
Y1458453D03*
Y1450853D03*
X231312Y97667D03*
X221695Y116594D03*
X226968Y102495D03*
X220669Y110784D03*
X221695Y119594D03*
X225229Y125107D03*
X220248Y124663D03*
X226702Y142862D03*
X227743Y148717D03*
X221592Y138838D03*
X230291Y195176D03*
X230372Y210509D03*
X224362Y226320D03*
X224296Y216970D03*
Y219470D03*
Y221970D03*
X221583Y216385D03*
X217783Y218085D03*
X232064Y230556D03*
X227323Y228646D03*
X231049Y242078D03*
X226280Y232971D03*
X220310Y249108D03*
X222930Y244571D03*
X233417Y253198D03*
X230842Y313888D03*
X233258Y359186D03*
X228267Y396718D03*
X221375Y455024D03*
X220349Y465622D03*
X225500Y530000D03*
X225000Y540500D03*
X224000Y547075D03*
X224200Y549800D03*
X223500Y568000D03*
X224104Y562800D03*
X224040Y558800D03*
X221693Y594982D03*
X222289Y590895D03*
X220333Y617930D03*
X220255Y629749D03*
X217906Y1430452D03*
Y1427052D03*
X219525Y1440028D03*
X216125D03*
X227249Y1447453D03*
Y1450853D03*
Y1458453D03*
Y1461853D03*
X224780Y1478149D03*
X217985Y1483055D03*
X225765Y1471985D03*
X233313Y1476699D03*
X221899Y1488800D03*
X218021Y1494724D03*
X222843Y1498442D03*
X217614Y1489671D03*
X233180Y1486442D03*
X233166Y1491454D03*
X226135Y1502442D03*
X230758Y1505046D03*
X226971Y1514578D03*
X227552Y1530675D03*
X232622Y1531104D03*
X226971Y1522578D03*
X219981Y1530797D03*
X223322Y1518578D03*
X222119Y1539941D03*
X227882Y1540816D03*
X233753Y1539752D03*
X239772Y103411D03*
X240166Y97667D03*
X235562Y95111D03*
X239931Y106561D03*
X233843Y143762D03*
X232791Y195176D03*
X235291D03*
X237309Y199248D03*
X234309D03*
X237791Y195176D03*
X237309Y202048D03*
X232872Y210509D03*
X234645Y206806D03*
X232145D03*
X234309Y201748D03*
X240909Y230117D03*
X236319Y227824D03*
X236925Y238714D03*
X236406Y246874D03*
X238626Y244297D03*
X234986Y336161D03*
X236264Y342494D03*
X245362Y546712D03*
Y542712D03*
X247536Y602689D03*
X247278Y618288D03*
X243278D03*
X240194Y643113D03*
X242102Y656321D03*
X250102D03*
X246102D03*
X245000Y678462D03*
X244267Y696911D03*
X235790Y754332D03*
X241204Y814841D03*
X237591Y815266D03*
X248556Y824003D03*
X246311Y819000D03*
X238400Y836900D03*
X234976Y1481676D03*
X243535Y1511473D03*
X245500Y1517033D03*
X237633Y1511909D03*
X244600Y1531700D03*
X240808Y1519942D03*
X235687Y1522578D03*
X237580Y1528604D03*
X245937Y1524237D03*
X239949Y1541327D03*
X244912Y1539389D03*
X250962Y90650D03*
X256274Y90615D03*
X260595Y99961D03*
X260645Y95236D03*
X250712D03*
X259457Y210478D03*
Y207978D03*
Y215478D03*
Y212978D03*
X262786Y264180D03*
X262711Y258880D03*
X257993Y307994D03*
X256475Y422088D03*
X252695Y442956D03*
X254512Y438323D03*
X261965Y458455D03*
X250336Y456386D03*
X254678Y445873D03*
X263301Y444232D03*
X262526Y451108D03*
X249125Y465874D03*
X252688Y636364D03*
X248690Y678519D03*
X248090Y691114D03*
X254634Y698241D03*
X248506Y812042D03*
X256303Y812254D03*
X250700Y819900D03*
X254058Y819851D03*
X255289Y824340D03*
X252305Y831018D03*
X252100Y836800D03*
X250876Y1532782D03*
X255909Y1542043D03*
X250790Y1539759D03*
X269509Y77393D03*
Y74793D03*
Y85193D03*
Y82593D03*
Y79993D03*
X277834Y98551D03*
X269553Y92874D03*
X271580Y107649D03*
Y104249D03*
X276146Y147540D03*
X279918Y141247D03*
X268602Y162368D03*
X271202D03*
X278302Y162793D03*
Y165393D03*
Y167993D03*
Y170493D03*
X277299Y181426D03*
X280124Y184012D03*
X277507Y184221D03*
X269913Y210713D03*
X273985Y208695D03*
X276785D03*
X273985Y211695D03*
X276485D03*
X269913Y208213D03*
Y213213D03*
Y215713D03*
X265286Y264180D03*
X280162Y265701D03*
X276980Y267526D03*
Y270026D03*
X271680Y267526D03*
X274480D03*
Y270026D03*
X271680D03*
X281797Y281716D03*
X277575Y395084D03*
X274425Y381500D03*
X278784Y435158D03*
X278529Y440489D03*
X274949Y442606D03*
X278827Y444841D03*
X282230Y458572D03*
X265011Y453881D03*
X280220Y448493D03*
X274866Y446606D03*
X265011Y446595D03*
X275873Y463479D03*
X276344Y467367D03*
X274096Y820725D03*
X274697Y830951D03*
X275123Y847874D03*
X269700Y853100D03*
X275400Y864400D03*
X278400Y890839D03*
X275400Y899400D03*
X279261Y926339D03*
X278739Y936439D03*
X289797Y36735D03*
X290113Y23188D03*
X284666Y34068D03*
X289631Y28281D03*
X293930Y76587D03*
Y72615D03*
X295369Y100625D03*
X288388Y97475D03*
X280729Y111223D03*
Y114623D03*
X281384Y103783D03*
X288319Y106186D03*
X280729Y125396D03*
X291131Y121735D03*
X280729Y128796D03*
X291131Y118335D03*
Y132509D03*
Y135909D03*
X295948Y141247D03*
X287385Y143740D03*
X284765Y148277D03*
X285807Y172190D03*
X280510Y181366D03*
X283305Y181009D03*
X288480Y168697D03*
X285226Y177616D03*
X289568Y191941D03*
X297622Y192490D03*
X291577Y206767D03*
X294077D03*
X296577D03*
X285246Y213132D03*
X281543Y211359D03*
Y213859D03*
X296707Y221708D03*
X292822Y228221D03*
Y231021D03*
X294207Y221708D03*
X291122Y224421D03*
X291707Y221708D03*
X285246Y215632D03*
X293373Y236189D03*
X295873D03*
X293314Y248765D03*
X295814D03*
X285490Y256303D03*
X290265Y266114D03*
X285249Y265896D03*
X296011Y270695D03*
X293511D03*
Y268195D03*
X296011D03*
X287738Y281982D03*
X286940Y315039D03*
X297719Y339559D03*
X291396Y350223D03*
X292520Y384410D03*
X292358Y393858D03*
X298000Y391496D03*
X295699Y382047D03*
X296000Y403500D03*
X298000Y409000D03*
X294000Y398583D03*
X295253Y440869D03*
Y438269D03*
X292453D03*
Y440869D03*
Y435669D03*
Y430469D03*
Y433069D03*
X295253D03*
Y430469D03*
Y435669D03*
X293307Y451677D03*
X295807D03*
X293307Y454177D03*
X295807D03*
X295011Y460218D03*
Y463618D03*
X281980Y953926D03*
X312256Y37543D03*
X305610Y55513D03*
X301835Y68581D03*
X310817Y60393D03*
X307916Y60529D03*
X301848Y80581D03*
X305978Y88801D03*
X312844Y94279D03*
X308895Y94351D03*
X308338Y85731D03*
X311892Y86046D03*
X312088Y116594D03*
X299742Y112083D03*
X304031Y103621D03*
X312088Y119594D03*
X312522Y124283D03*
X300435Y143518D03*
X299535Y152373D03*
X310929Y161306D03*
X302685Y152562D03*
X308180Y157370D03*
X312264Y176665D03*
Y168665D03*
X303377Y183834D03*
X303550Y172665D03*
X303487Y178560D03*
X304363Y186629D03*
X302897Y190185D03*
X312264Y196665D03*
Y192665D03*
X303667Y200864D03*
X312377Y186778D03*
X300814Y192859D03*
X312296Y204864D03*
Y208864D03*
X303756Y212455D03*
X303690Y207037D03*
X301057Y221642D03*
X307937Y219379D03*
X308565Y228631D03*
X298373Y236189D03*
X298314Y248765D03*
X302471Y265897D03*
X304971D03*
X298811Y270695D03*
Y268195D03*
X315079Y314890D03*
X312263Y324518D03*
X301943Y328867D03*
X308952Y356875D03*
X312316Y356747D03*
X299000Y377912D03*
Y386500D03*
X299088Y397912D03*
X322847Y19806D03*
X321840Y14408D03*
X322113Y26187D03*
X316751Y86012D03*
Y94374D03*
X324057Y116594D03*
X318031Y110784D03*
X323031D03*
X324057Y119594D03*
X327591Y125107D03*
X322610Y124663D03*
X317588Y124879D03*
X329064Y142862D03*
X330105Y148717D03*
X323954Y138838D03*
X317345Y218085D03*
X320145D03*
X323945Y216385D03*
X326658Y216970D03*
Y219470D03*
X326724Y226320D03*
X326658Y221970D03*
X329685Y228646D03*
X328642Y232971D03*
X322672Y249108D03*
X325292Y244571D03*
X314053Y248371D03*
X327032Y303962D03*
X314855Y311740D03*
X318508Y324322D03*
X315944Y332584D03*
X316067Y347937D03*
X321416Y348015D03*
X317333Y353470D03*
X318500Y356519D03*
X315310Y356712D03*
X320993Y467306D03*
Y470706D03*
Y481479D03*
Y484879D03*
Y514839D03*
Y511439D03*
Y525613D03*
Y529013D03*
X318660Y539315D03*
X320785Y553287D03*
X327456Y550065D03*
X320993Y564879D03*
Y561479D03*
Y575652D03*
Y579052D03*
Y603999D03*
Y593225D03*
Y589825D03*
Y607399D03*
X321119Y622912D03*
X330905Y15806D03*
Y19806D03*
Y27806D03*
X333674Y97667D03*
X342134Y103411D03*
X342528Y97667D03*
X337924Y95111D03*
X329330Y102495D03*
X342293Y106561D03*
X336205Y143762D03*
X335153Y195176D03*
X332653D03*
X336671Y199248D03*
X337653Y195176D03*
X340153D03*
X339671Y199248D03*
X336671Y201748D03*
X334507Y206806D03*
X337007D03*
X335234Y210509D03*
X332734D03*
X339671Y202048D03*
X343271Y230117D03*
X338681Y227824D03*
X334426Y230556D03*
X339287Y238714D03*
X333411Y242078D03*
X338768Y246874D03*
X340988Y244297D03*
X332635Y256394D03*
X347058Y399918D03*
X339072Y416888D03*
Y419488D03*
Y422088D03*
X345050Y454334D03*
X331395Y474418D03*
Y488591D03*
Y477818D03*
Y491991D03*
Y518552D03*
Y521952D03*
Y536125D03*
Y532725D03*
X337078Y551381D03*
X335399Y544718D03*
X331395Y568591D03*
Y571991D03*
Y586165D03*
Y582765D03*
Y600338D03*
Y596938D03*
Y611111D03*
Y614511D03*
X333985Y1017945D03*
X341077Y1018056D03*
X339251Y1138130D03*
X336755Y1143489D03*
X340500Y1147500D03*
X335190Y1173065D03*
X341266Y1171956D03*
X330800Y1174500D03*
X343121Y1188412D03*
X342009Y1176100D03*
X339776Y1187962D03*
X335502Y1188222D03*
X339540Y1196894D03*
X358636Y90615D03*
X353324Y90650D03*
X362957Y99961D03*
X353074Y95236D03*
X359376Y290592D03*
X348351Y319372D03*
X348806Y315427D03*
X351132Y322202D03*
X349120Y336100D03*
X351136Y372334D03*
X350486Y377173D03*
X358491D03*
X347591Y391533D03*
X359486Y385123D03*
X349311Y385644D03*
X354486Y385123D03*
X357655Y405889D03*
Y408489D03*
X358248Y403300D03*
X353894Y406060D03*
X354155Y421489D03*
Y418889D03*
Y416289D03*
X350163Y412106D03*
X357655Y413689D03*
Y416289D03*
Y421489D03*
Y418889D03*
Y424089D03*
Y411089D03*
X358042Y432718D03*
X357655Y426689D03*
X358042Y435518D03*
X358754Y450091D03*
X356241Y447001D03*
X359241D03*
X353320Y454214D03*
X353663Y449045D03*
X353367Y459330D03*
X358754Y462060D03*
X353670Y473571D03*
Y481071D03*
Y478571D03*
Y476071D03*
X360242Y477053D03*
X357742D03*
X358207Y836462D03*
X346366Y1134729D03*
X361621D03*
X349748D03*
X357748D03*
X353748D03*
X352545Y1142666D03*
X360877Y1157404D03*
X354420Y1157544D03*
X352931Y1167768D03*
X357950D03*
X357057Y1179542D03*
X357796Y1188058D03*
X357083Y1185205D03*
X361792Y1187310D03*
X348432Y1187215D03*
X348125Y1180175D03*
X358368Y1201043D03*
X354398D03*
X350402D03*
X346387Y1199256D03*
X360523Y1192282D03*
X349276Y1217228D03*
X351940Y1219895D03*
X362332Y1230265D03*
X355215Y1223170D03*
X360273Y1228226D03*
X358062Y1226016D03*
X371871Y85193D03*
Y82593D03*
Y79993D03*
Y77393D03*
Y74793D03*
X371915Y92874D03*
X363007Y95236D03*
X373942Y104249D03*
Y107649D03*
X370964Y162368D03*
X373564D03*
X372275Y208213D03*
X379147Y208695D03*
X376347D03*
Y211695D03*
X372275Y210713D03*
Y213213D03*
X361819Y207978D03*
Y212978D03*
Y215478D03*
Y210478D03*
X372275Y215713D03*
X367648Y264180D03*
X365148D03*
X365073Y258880D03*
X374042Y270026D03*
X376842D03*
X374042Y267526D03*
X376842D03*
X371417Y353820D03*
X365559Y354300D03*
X377237Y371060D03*
X373264Y379429D03*
X378875Y379088D03*
X366526Y377173D03*
X370486D03*
X362486Y385123D03*
X366486D03*
X370160Y391569D03*
X368587Y401066D03*
X378927Y406739D03*
X367919Y439318D03*
X375919Y442118D03*
Y439318D03*
X367919Y442118D03*
X361754Y450091D03*
X367564Y456034D03*
Y461034D03*
X373546Y470001D03*
X376046D03*
X361754Y462060D03*
X373971Y489036D03*
X371832Y485580D03*
X374332D03*
X376832D03*
X366420Y479986D03*
Y477486D03*
X363686Y478668D03*
Y476168D03*
X376207Y492836D03*
Y495636D03*
X376881Y518564D03*
X363015Y710365D03*
X365887Y710329D03*
X372400Y746300D03*
X372300Y750000D03*
X373500Y767300D03*
X376300D03*
X370415Y766108D03*
X373703Y782555D03*
X365850Y773950D03*
X371436Y791188D03*
X365691Y815127D03*
X371507Y815303D03*
X362042Y814772D03*
X368067Y925136D03*
X370214Y943812D03*
X368626Y931346D03*
X368964Y937738D03*
X372858Y935136D03*
X366761Y934550D03*
X363893Y946863D03*
X379928Y949774D03*
X379245Y956643D03*
X378875Y961862D03*
X370214Y947812D03*
X370101Y953699D03*
X370214Y963812D03*
Y971812D03*
X378928Y967812D03*
X372501Y1123695D03*
X365748Y1134325D03*
X368657Y1150087D03*
X366133Y1170767D03*
X366429Y1185238D03*
X366222Y1180235D03*
X362402Y1201039D03*
X366402Y1200969D03*
X366521Y1208993D03*
X370202Y1314764D03*
Y1311364D03*
X383612Y33768D03*
X388612Y31168D03*
X387948Y27288D03*
X380196Y98551D03*
X390750Y97475D03*
X383091Y111223D03*
Y114623D03*
X383746Y103783D03*
X390681Y106186D03*
X393493Y118335D03*
X383091Y125396D03*
Y128796D03*
X393493Y132509D03*
Y121735D03*
Y135909D03*
X380664Y165393D03*
Y162793D03*
Y167993D03*
Y170493D03*
X387588Y177616D03*
X382872Y181366D03*
X379661Y181426D03*
X385667Y181009D03*
X390842Y168697D03*
X388169Y172190D03*
X391930Y191941D03*
X382486Y184012D03*
X379869Y184221D03*
X393939Y206767D03*
X383905Y211359D03*
X387608Y213132D03*
X378847Y211695D03*
X383905Y213859D03*
X394069Y221708D03*
X393484Y224421D03*
X387608Y215632D03*
X387852Y256303D03*
X387611Y265896D03*
X382524Y265701D03*
X392627Y266114D03*
X379342Y270026D03*
Y267526D03*
X384159Y281716D03*
X390100Y281982D03*
X391737Y377581D03*
X384173Y379028D03*
X381237Y371076D03*
X394237Y379591D03*
X391940Y383817D03*
Y388817D03*
Y386317D03*
X385864Y398278D03*
X383364D03*
X378927Y409539D03*
X381927D03*
Y407039D03*
X381591Y401981D03*
X384091D03*
X378210Y424067D03*
X380710D03*
X385710D03*
X383210D03*
X378445Y413611D03*
X380945D03*
X385945D03*
X383445D03*
X385584Y438293D03*
Y441093D03*
Y443893D03*
X393646Y474382D03*
X385634Y472020D03*
X393662Y470382D03*
X385694Y477318D03*
X385293Y466409D03*
X387141Y484882D03*
X385131Y487382D03*
X391470Y732865D03*
X380963Y731000D03*
X381875Y740341D03*
X379800Y769200D03*
X380331Y782627D03*
X380607Y786932D03*
X392415Y792725D03*
X389015D03*
X387958Y813700D03*
X381631Y814147D03*
X384666Y814103D03*
X383391Y804000D03*
X386589Y864408D03*
X383462Y860535D03*
X392584Y875845D03*
X382675Y870151D03*
X391614Y930676D03*
X384856Y947987D03*
X378119Y953696D03*
X392910Y948536D03*
X393998Y971780D03*
X378790Y1001083D03*
X380280Y1006071D03*
X383710Y1007283D03*
X382465Y1012430D03*
X378410Y1131573D03*
X380261Y1129692D03*
X385091Y1297453D03*
Y1300853D03*
X386415Y1321645D03*
X391691Y1326715D03*
X392234Y1369579D03*
Y1364501D03*
X391757Y1383480D03*
X391852Y1389931D03*
X393951Y1447455D03*
X381900Y1544800D03*
X389700Y1536900D03*
X391740Y1545629D03*
Y1540529D03*
X382017Y1559700D03*
X395296Y1561024D03*
X391740Y1550729D03*
Y1555829D03*
X410789Y22627D03*
X408680Y37530D03*
X396680Y37543D03*
X400714Y45448D03*
X404686D03*
X397731Y100625D03*
X402104Y112083D03*
X406393Y103621D03*
X405912Y172665D03*
X405739Y183834D03*
X405849Y178560D03*
X406725Y186629D03*
X399984Y192490D03*
X405259Y190185D03*
X406029Y200864D03*
X395942Y192300D03*
X398939Y206767D03*
X396439D03*
X406118Y212455D03*
X406052Y207037D03*
X395184Y228221D03*
X399069Y221708D03*
X396569D03*
X403419Y221642D03*
X395184Y231021D03*
X410299Y219379D03*
X410927Y228631D03*
X400735Y236189D03*
X398235D03*
X395735D03*
X400676Y248765D03*
X398176D03*
X395676D03*
X407333Y265897D03*
X404833D03*
X401173Y268195D03*
Y270695D03*
X398373Y268195D03*
X395873D03*
Y270695D03*
X398373D03*
X405843Y315158D03*
X403343D03*
X394883Y341777D03*
Y338377D03*
X410086Y336795D03*
X409655Y331589D03*
X410688Y344736D03*
X400993Y331589D03*
Y335589D03*
X400728Y353152D03*
X411007Y356743D03*
X406421Y387151D03*
Y382151D03*
Y384651D03*
X398453Y387702D03*
X401253D03*
X394653Y389402D03*
X395577Y438293D03*
Y441093D03*
Y443893D03*
X397315Y471560D03*
X405801Y475560D03*
X405301Y467560D03*
X397315Y475560D03*
X406200Y741300D03*
X397223Y796792D03*
X400023D03*
X397900Y789000D03*
X407000Y784700D03*
X404468Y864407D03*
X396306Y864409D03*
X406770Y869767D03*
X405466Y881299D03*
X397431Y870654D03*
X401108Y878487D03*
X401121Y929686D03*
X409121D03*
X401121Y932186D03*
X409121D03*
X405179Y959051D03*
X404971Y956256D03*
X402354Y956465D03*
X401968Y959111D03*
X399173Y959468D03*
X397252Y962861D03*
X404176Y977684D03*
Y975084D03*
Y969984D03*
Y972484D03*
X396671Y968287D03*
X406954Y982970D03*
X409554D03*
X404354D03*
X407547Y1058097D03*
X410047D03*
X405047D03*
X407547Y1060697D03*
X410047D03*
X405047D03*
X408989Y1082501D03*
X409015Y1087705D03*
Y1085205D03*
X408847Y1090956D03*
Y1093956D03*
X406895Y1107997D03*
X402695D03*
Y1110897D03*
X407780Y1113648D03*
X409231Y1118801D03*
X406995Y1110597D03*
X404895Y1112397D03*
X404795Y1109397D03*
X402695Y1113797D03*
X408961Y1162384D03*
Y1164884D03*
Y1167384D03*
Y1169884D03*
Y1172384D03*
X403263Y1160834D03*
X408961Y1174884D03*
X406319Y1186709D03*
Y1184209D03*
Y1181709D03*
Y1179209D03*
X404004Y1192621D03*
Y1190121D03*
X397063Y1221428D03*
X401063D03*
X405063D03*
X409063D03*
X397063Y1233428D03*
Y1229428D03*
Y1225428D03*
X401063Y1237428D03*
Y1233428D03*
Y1229428D03*
Y1225428D03*
X405063Y1237428D03*
Y1233428D03*
Y1229428D03*
Y1225428D03*
X409063Y1237428D03*
Y1233428D03*
Y1229428D03*
Y1225428D03*
X401063Y1241428D03*
X405063Y1245428D03*
Y1241428D03*
X409063Y1245428D03*
Y1241428D03*
X404324Y1271889D03*
Y1275889D03*
X407767Y1292198D03*
X403678Y1295426D03*
X398584Y1313443D03*
X401011Y1307258D03*
X402967Y1319815D03*
X409220Y1315516D03*
X404583Y1316131D03*
X404921Y1321819D03*
X408787Y1321795D03*
X399959Y1352153D03*
X408159Y1349072D03*
X404759D03*
X395112Y1395690D03*
X398340Y1399779D03*
X395770Y1389817D03*
X410172Y1402446D03*
X402489Y1417275D03*
X405889D03*
X407970Y1449751D03*
X404500Y1452500D03*
X395888Y1450022D03*
X395199Y1482223D03*
X395380Y1485778D03*
X397266Y1514647D03*
X398747Y1500959D03*
X395370Y1501022D03*
X397266Y1518047D03*
X408964Y1531149D03*
X394391Y1537786D03*
Y1535286D03*
X399373Y1555855D03*
X405496Y1561024D03*
X400396D03*
X410596D03*
X397461Y1569560D03*
X401461D03*
X416900Y33400D03*
X422473Y22627D03*
X422450Y30483D03*
X422378Y26534D03*
X414145Y27486D03*
X413904Y32569D03*
X426147Y147540D03*
X414626Y176665D03*
Y168665D03*
Y196665D03*
Y192665D03*
X414739Y186778D03*
X414658Y204864D03*
Y208864D03*
X423651Y307470D03*
X419177Y304470D03*
X415777D03*
X422988Y323627D03*
X415129Y325181D03*
X412671Y333418D03*
X412812Y330617D03*
X426830Y359026D03*
X426138Y355079D03*
X416574Y357528D03*
X421413Y359053D03*
X412318Y367903D03*
X420422Y367859D03*
X418997Y382210D03*
Y384710D03*
Y387210D03*
X422215Y424939D03*
Y427439D03*
X414924Y435321D03*
Y438121D03*
X412124Y435321D03*
Y438121D03*
X414924Y440921D03*
X412124D03*
X414924Y443721D03*
X412124D03*
X426647Y452987D03*
X421267Y452799D03*
X414910Y448931D03*
X415433Y459170D03*
X425673Y461607D03*
X424876Y471334D03*
X418801Y474513D03*
X414275Y492469D03*
X424731Y492704D03*
X414275Y497469D03*
Y499969D03*
X427693Y498943D03*
X424731Y497704D03*
Y495204D03*
Y500204D03*
X414275Y494969D03*
X419340Y549990D03*
X419140Y547390D03*
Y544790D03*
X419340Y552590D03*
Y555190D03*
X423963Y625778D03*
X426607Y712360D03*
Y709760D03*
X424993Y728291D03*
X423700Y795500D03*
X426300Y797400D03*
X421200Y786400D03*
X411267Y829193D03*
Y831693D03*
X416267D03*
X413767D03*
Y829193D03*
X416267D03*
X425062Y883981D03*
X417121Y929686D03*
X425121D03*
X417121Y932186D03*
X425121D03*
X411960Y962261D03*
X414560D03*
X417160D03*
X411276Y978109D03*
X416476D03*
X413876D03*
X415047Y1058097D03*
X412547D03*
X415047Y1060697D03*
X412547D03*
X411989Y1082501D03*
X412015Y1085205D03*
X414989Y1082501D03*
X415015Y1085205D03*
Y1088205D03*
X412015D03*
X412297Y1091227D03*
X425060Y1101917D03*
X420782Y1105552D03*
X423340Y1104335D03*
X424995Y1106897D03*
X416988Y1104792D03*
X418495Y1106867D03*
X414580Y1113648D03*
X412080D03*
X411461Y1162384D03*
Y1164884D03*
Y1167384D03*
Y1169884D03*
Y1172384D03*
X420619Y1179421D03*
Y1181921D03*
Y1184421D03*
Y1186921D03*
X411461Y1174884D03*
X422934Y1192621D03*
Y1190121D03*
X417469Y1192621D03*
Y1190121D03*
X413063Y1221428D03*
X417063D03*
X421063D03*
X425063D03*
X413063Y1237428D03*
Y1233428D03*
Y1229428D03*
Y1225428D03*
X417063Y1237428D03*
Y1233428D03*
Y1229428D03*
Y1225428D03*
X421063Y1237428D03*
Y1233428D03*
Y1229428D03*
Y1225428D03*
X425063Y1237428D03*
Y1233428D03*
Y1229428D03*
Y1225428D03*
X413063Y1245428D03*
Y1241428D03*
X417063Y1245428D03*
Y1241428D03*
X421063Y1245428D03*
Y1241428D03*
X425063Y1245428D03*
Y1241428D03*
X425702Y1257160D03*
X422702Y1260160D03*
Y1257160D03*
X425702Y1260160D03*
X419702Y1257160D03*
Y1260160D03*
X413526Y1288938D03*
X419977Y1288843D03*
X413640Y1292856D03*
X419545Y1317722D03*
X413127Y1318011D03*
X425283Y1364023D03*
X417305Y1359169D03*
X425855Y1360495D03*
X425912Y1357141D03*
X416029Y1371572D03*
X420636Y1383912D03*
X418610Y1371590D03*
X423400Y1394500D03*
X423200Y1397500D03*
X418430Y1394237D03*
X422729Y1400490D03*
X420925Y1390330D03*
X419045Y1398874D03*
X421300Y1415400D03*
X419100Y1402200D03*
X421200Y1417900D03*
X411000Y1463500D03*
Y1460500D03*
Y1457500D03*
Y1454500D03*
Y1451000D03*
X413934Y1477101D03*
X417334D03*
X415202Y1496118D03*
Y1499518D03*
X417153Y1516886D03*
X413753D03*
X419619Y1539978D03*
X421454Y1544625D03*
X422539Y1534361D03*
X426701Y1541947D03*
X418151Y1552470D03*
X417461Y1569584D03*
X429919Y141247D03*
X437386Y143740D03*
X434766Y148277D03*
X431525Y304470D03*
X434925D03*
X427051Y307470D03*
X441296Y325061D03*
X436666Y322583D03*
X427713Y321965D03*
X430361Y323187D03*
X443424Y332988D03*
X440538Y355372D03*
X428420Y353578D03*
X435886Y353867D03*
X431524Y370309D03*
X434924D03*
X428637Y408104D03*
X431437D03*
X434237D03*
X428354Y420375D03*
X431154D03*
X433954D03*
X438098Y442114D03*
X437835Y435101D03*
X432270Y431112D03*
X432440Y440101D03*
X432075Y452718D03*
X438086Y452601D03*
X438078Y447121D03*
X433673Y461607D03*
X429673D03*
X435789Y501525D03*
X427568Y502003D03*
X435831Y498923D03*
X438644Y500461D03*
X428740Y549990D03*
X442804Y546990D03*
Y544390D03*
X428740Y546990D03*
Y544390D03*
Y555190D03*
Y552590D03*
X431384D03*
Y555190D03*
Y544390D03*
Y546990D03*
Y549990D03*
X443144Y628667D03*
X441162Y638313D03*
X439290Y712399D03*
X436790D03*
X439290Y709799D03*
X436790D03*
X434290Y712399D03*
Y709799D03*
X429290D03*
X431790Y712399D03*
X429290D03*
X431790Y709799D03*
X429253Y759847D03*
X432303Y785067D03*
X434100Y797400D03*
X430600D03*
X443091Y1026266D03*
X432678Y1016186D03*
X429878D03*
X427078D03*
X427052Y1019384D03*
X429852D03*
X432652D03*
X433378Y1091816D03*
Y1089316D03*
X430878Y1084316D03*
Y1086816D03*
X433378D03*
Y1084316D03*
X436244Y1090288D03*
X433378Y1081816D03*
X430878D03*
X429677Y1106955D03*
X439023Y1107997D03*
X436244Y1093088D03*
X434823Y1107997D03*
X431476Y1115896D03*
X427810Y1110092D03*
X439908Y1113648D03*
X441359Y1116101D03*
Y1118801D03*
X439123Y1110597D03*
X434823Y1113797D03*
Y1110897D03*
X437023Y1112397D03*
X436923Y1109397D03*
X431476Y1118396D03*
X429348Y1129092D03*
X432838Y1128821D03*
X436789Y1167384D03*
Y1164884D03*
Y1162384D03*
Y1172384D03*
Y1169884D03*
X439289Y1167384D03*
Y1164884D03*
Y1162384D03*
X427231D03*
X429731D03*
Y1164884D03*
Y1167384D03*
Y1169884D03*
Y1172384D03*
X427231D03*
Y1169884D03*
Y1167384D03*
Y1164884D03*
X439289Y1172384D03*
Y1169884D03*
X437132Y1158266D03*
X433249Y1186709D03*
Y1184209D03*
Y1181709D03*
Y1179209D03*
X429731Y1174884D03*
X427231D03*
X436789D03*
X439289D03*
X430934Y1190121D03*
Y1192621D03*
X429063Y1221428D03*
X433063D03*
X429063Y1237428D03*
Y1233428D03*
Y1229428D03*
Y1225428D03*
X433063Y1237428D03*
Y1233428D03*
Y1229428D03*
Y1225428D03*
X429063Y1245428D03*
Y1241428D03*
X433063Y1245428D03*
Y1241428D03*
X440702Y1260160D03*
Y1257160D03*
X437702Y1260160D03*
Y1257160D03*
X428702D03*
X431702Y1260160D03*
Y1257160D03*
X434702Y1260160D03*
Y1257160D03*
X428702Y1260160D03*
X434424Y1286274D03*
X430527Y1289198D03*
X440906D03*
X431867Y1315696D03*
X431885Y1313115D03*
X439434Y1322369D03*
X429530Y1325051D03*
X445949Y141247D03*
X450436Y143518D03*
X449536Y152373D03*
X452686Y152562D03*
X458181Y157370D03*
X443508Y337713D03*
X446566Y337917D03*
X443480Y344014D03*
X450852Y372054D03*
X455885Y367702D03*
X448391Y382641D03*
X448323Y379643D03*
X451144Y468809D03*
X459414Y468689D03*
X459757Y463520D03*
X459461Y473805D03*
X459929Y491669D03*
X450942Y506449D03*
X448442D03*
X445942D03*
X460537Y501905D03*
X459952Y496842D03*
X459645Y509486D03*
X446025Y511512D03*
X448525D03*
X446025Y519699D03*
X448525D03*
X452404Y549790D03*
X443004Y549890D03*
X452404Y546990D03*
Y544390D03*
X443004Y555090D03*
X452404Y552390D03*
Y554990D03*
X443004Y552490D03*
X455009Y554912D03*
Y552312D03*
Y544312D03*
Y546912D03*
Y549712D03*
X447279Y637031D03*
X447921Y630789D03*
X453552Y631779D03*
X446987Y643360D03*
X456469Y638302D03*
X460498Y870334D03*
X458120Y974701D03*
X451460Y974695D03*
X450591Y1004766D03*
X453270Y1003763D03*
X459360Y1012325D03*
X443591Y1019766D03*
X459885Y1018860D03*
X451140Y1021793D03*
X447091Y1019766D03*
X450875Y1028416D03*
X443091Y1034266D03*
X452091Y1039880D03*
X459700Y1032266D03*
X455468Y1104335D03*
X457188Y1101917D03*
X452910Y1105552D03*
X457123Y1106897D03*
X449116Y1104792D03*
X450623Y1106867D03*
X444208Y1113648D03*
X446708D03*
X457559Y1169884D03*
Y1167384D03*
Y1164884D03*
Y1162384D03*
X455059D03*
Y1164884D03*
Y1167384D03*
Y1169884D03*
Y1172384D03*
X457559D03*
X455059Y1174884D03*
X457559D03*
X447549Y1179421D03*
Y1181921D03*
Y1184421D03*
Y1186921D03*
X449864Y1190121D03*
Y1192621D03*
X449702Y1260160D03*
Y1257160D03*
X443702Y1260160D03*
X446702D03*
Y1257160D03*
X443702D03*
X451304Y1297045D03*
X454385Y1301845D03*
Y1305245D03*
X444288Y1314391D03*
X462089Y116594D03*
X474058D03*
X473032Y110784D03*
X468032D03*
X462089Y119594D03*
X474058D03*
X477592Y125107D03*
X462523Y124283D03*
X467589Y124879D03*
X472611Y124663D03*
X473955Y138838D03*
X460930Y161306D03*
X467346Y218085D03*
X470146D03*
X473946Y216385D03*
X475293Y244571D03*
X472673Y249108D03*
X464054Y248371D03*
X460950Y328185D03*
Y324785D03*
X463950Y332659D03*
Y336059D03*
X460950Y343933D03*
Y340533D03*
X472810Y347995D03*
X472913Y360089D03*
X472608Y352495D03*
X467335Y359944D03*
X463950Y351807D03*
Y348407D03*
X472913Y369089D03*
Y373589D03*
X469530Y366754D03*
X472913Y387089D03*
Y391589D03*
Y382589D03*
Y378089D03*
X470796Y394592D03*
X464848Y464566D03*
X467848D03*
X465126Y460435D03*
X462126D03*
X473658Y470509D03*
Y475509D03*
X467848Y476535D03*
X464848D03*
X468558Y495669D03*
Y499669D03*
Y516609D03*
X464199Y510184D03*
X468850Y545586D03*
X469300Y799500D03*
X459245Y807152D03*
X473654Y821234D03*
X472399Y839566D03*
X463404Y846870D03*
X465492Y861970D03*
X471726Y883705D03*
X474540Y927341D03*
X471110Y921577D03*
X471876Y937236D03*
X471068Y930235D03*
X473992Y952546D03*
X475018Y992568D03*
X467345Y996480D03*
X459360Y1004680D03*
X464795Y1000647D03*
X462185Y1016825D03*
X459860Y1015825D03*
X464385Y1038534D03*
X471558Y1029482D03*
X471755Y1038665D03*
X470610Y1033783D03*
X475588Y1043055D03*
X473639Y1030952D03*
X459700Y1035716D03*
X470978Y1046591D03*
X474348Y1090171D03*
X462913Y1106365D03*
X474277Y1093048D03*
X472482Y1107997D03*
X468282D03*
X459938Y1110092D03*
X463604Y1115896D03*
X473367Y1113648D03*
X474818Y1116101D03*
Y1118801D03*
X472582Y1110597D03*
X470482Y1112397D03*
X468282Y1110897D03*
Y1113797D03*
X470382Y1109397D03*
X463604Y1118396D03*
X462687Y1160834D03*
X474548Y1172384D03*
Y1169884D03*
Y1167384D03*
Y1164884D03*
Y1162384D03*
X468850Y1160834D03*
X474548Y1174884D03*
X465785Y1197471D03*
X461285Y1193471D03*
Y1197471D03*
X465785Y1193471D03*
X474647Y1260160D03*
Y1257160D03*
X471647D03*
Y1260160D03*
X459290Y1297035D03*
X463290D03*
X492135Y103411D03*
X492529Y97667D03*
X483675D03*
X487925Y95111D03*
X479331Y102495D03*
X479065Y142862D03*
X486206Y143762D03*
X480106Y148717D03*
X487654Y195176D03*
X489672Y199248D03*
X485154Y195176D03*
X482654D03*
X486672Y199248D03*
X490154Y195176D03*
X485235Y210509D03*
X482735D03*
X489672Y202048D03*
X486672Y201748D03*
X484508Y206806D03*
X487008D03*
X476659Y216970D03*
Y219470D03*
X476725Y226320D03*
X476659Y221970D03*
X493272Y230117D03*
X484427Y230556D03*
X488682Y227824D03*
X479686Y228646D03*
X483412Y242078D03*
X478643Y232971D03*
X488769Y246874D03*
X489288Y238714D03*
X490989Y244297D03*
X482636Y256394D03*
X492817Y357111D03*
X491843Y351089D03*
X481724Y373589D03*
Y369089D03*
X490885Y373589D03*
X491053Y365423D03*
X491289Y391589D03*
X481724Y382589D03*
Y378089D03*
X490885Y382570D03*
X490985Y412342D03*
X488438Y418417D03*
X485485Y439903D03*
X489485D03*
X481485Y439900D03*
Y431917D03*
X489485Y431417D03*
X492736Y491982D03*
X482836Y534249D03*
X491818Y534909D03*
X491445Y541135D03*
X482905Y527726D03*
Y548726D03*
Y544726D03*
X491534Y552726D03*
X491511Y546553D03*
X487209Y611071D03*
X484772Y621311D03*
X493392Y622285D03*
X493580Y616905D03*
X484772Y629311D03*
Y625311D03*
X493661Y627713D03*
X493778Y633724D03*
X481165Y646036D03*
X483059Y662649D03*
X488765Y667224D03*
X481742Y657477D03*
X486837Y701306D03*
Y704706D03*
X489406Y797558D03*
X489572Y822805D03*
X479448Y828594D03*
X479700Y847600D03*
X477574Y860815D03*
X490706Y859339D03*
X491616Y938771D03*
X476475Y952249D03*
X479613Y952189D03*
X489163Y977163D03*
X487091Y989550D03*
X480711Y999941D03*
X477857Y1004375D03*
X488041Y1020440D03*
X485678Y1039880D03*
X485633Y1036155D03*
X477765Y1093432D03*
X477607Y1089942D03*
X491503Y1086796D03*
Y1084296D03*
X478517Y1086724D03*
Y1084224D03*
Y1081724D03*
X476017D03*
Y1084224D03*
Y1086724D03*
X486369Y1105552D03*
X490647Y1101917D03*
X488927Y1104335D03*
X490582Y1106897D03*
X482575Y1104792D03*
X484082Y1106867D03*
X480167Y1113648D03*
X477667D03*
X477048Y1172384D03*
Y1169884D03*
Y1167384D03*
Y1164884D03*
Y1162384D03*
X479521Y1179209D03*
Y1181709D03*
Y1184209D03*
Y1186709D03*
X477048Y1174884D03*
X490671Y1192621D03*
Y1190121D03*
X477206Y1192621D03*
Y1190121D03*
X489647Y1260160D03*
Y1257160D03*
X486647D03*
Y1260160D03*
X480647Y1257160D03*
X477647D03*
Y1260160D03*
X480647D03*
X483647Y1257160D03*
Y1260160D03*
X490100Y1302100D03*
X487600D03*
X503325Y90650D03*
X508637Y90615D03*
X503075Y95236D03*
X492294Y106561D03*
X496023Y362913D03*
X497048Y369450D03*
X495750Y377531D03*
X506500Y379687D03*
X495203Y386890D03*
X503729Y439919D03*
X503682Y448419D03*
X500729Y469905D03*
X496729Y470419D03*
X504729Y469905D03*
X496729Y461919D03*
X504729Y461419D03*
X505476Y485128D03*
X497095Y481467D03*
X501224Y492050D03*
X501649Y482165D03*
X501887Y504825D03*
X499387D03*
X496887D03*
X500890Y500202D03*
X502493Y495917D03*
X492736Y495982D03*
X501828Y517401D03*
X499328D03*
X496828D03*
X502379Y522569D03*
X495444Y531948D03*
X503494Y531882D03*
X502379Y525369D03*
X500994Y531882D03*
X498494D03*
X504079Y529169D03*
X503729Y555194D03*
X500929D03*
Y571194D03*
X503729D03*
Y563194D03*
X500929D03*
X505286Y581222D03*
X502486D03*
X505286Y591215D03*
X502486D03*
X505458Y610562D03*
X502658D03*
Y607762D03*
X505458D03*
X497448Y610548D03*
X504265Y633736D03*
X499258Y633716D03*
X506278Y628078D03*
X494465Y657772D03*
X502755Y657694D03*
X496070Y665976D03*
X499528Y657843D03*
X504966Y678098D03*
X498284Y681453D03*
Y678953D03*
X500714Y708755D03*
X502832Y720491D03*
X504895Y770457D03*
X501495D03*
X504508Y783817D03*
X506166Y793224D03*
X504641Y789139D03*
X507095Y814784D03*
X494677Y830468D03*
X509665Y824512D03*
X495073Y835586D03*
X495470Y844271D03*
X495700Y849389D03*
X503383Y863025D03*
X498507Y865392D03*
X508248Y873319D03*
X509791Y881932D03*
X509017Y905295D03*
X494315Y941212D03*
X503144Y957934D03*
X504088Y985171D03*
X506888D03*
X506702Y978947D03*
X493091Y989550D03*
X503933Y981392D03*
X498435Y1008766D03*
X506566D03*
Y996766D03*
X498524Y997590D03*
X498585Y1016266D03*
X506566Y1012266D03*
X503177Y1058097D03*
X495677D03*
X493177D03*
X498177D03*
X500677D03*
X503177Y1060697D03*
X495677D03*
X493177D03*
X498177D03*
X500677D03*
X494003Y1086796D03*
X496503D03*
X499003D03*
X501503D03*
Y1084296D03*
X499003D03*
X496503D03*
X494003D03*
X501831Y1090288D03*
X496372Y1106298D03*
X504610Y1107997D03*
X501831Y1093088D03*
X500410Y1107997D03*
X497063Y1115896D03*
X505495Y1113648D03*
X506946Y1116101D03*
Y1118801D03*
X504710Y1110597D03*
X500410Y1113797D03*
X502610Y1112397D03*
X500410Y1110897D03*
X502510Y1109397D03*
X493397Y1110092D03*
X497063Y1118396D03*
X498727Y1128759D03*
X495236Y1129094D03*
X502376Y1172384D03*
Y1169884D03*
Y1167384D03*
Y1164884D03*
Y1162384D03*
X504876Y1172384D03*
Y1169884D03*
Y1167384D03*
Y1164884D03*
Y1162384D03*
X492818D03*
Y1164884D03*
Y1167384D03*
Y1169884D03*
Y1172384D03*
X495318D03*
Y1169884D03*
Y1167384D03*
Y1164884D03*
Y1162384D03*
X502562Y1158200D03*
X506451Y1179209D03*
Y1181709D03*
Y1184209D03*
Y1186709D03*
X504876Y1174884D03*
X493821Y1186921D03*
Y1184421D03*
Y1181921D03*
Y1179421D03*
X492818Y1174884D03*
X495318D03*
X502376D03*
X504136Y1190121D03*
Y1192621D03*
X496136Y1190121D03*
Y1192621D03*
X506562Y1222194D03*
X502562D03*
X498562D03*
X494562D03*
X506562Y1226194D03*
Y1230194D03*
Y1234194D03*
Y1238194D03*
X502562Y1226194D03*
Y1230194D03*
Y1234194D03*
Y1238194D03*
X498562Y1226194D03*
Y1230194D03*
Y1234194D03*
Y1238194D03*
X494562Y1226194D03*
Y1230194D03*
Y1234194D03*
Y1238194D03*
Y1246194D03*
Y1242194D03*
X506562D03*
Y1246194D03*
X502562Y1242194D03*
Y1246194D03*
X498562Y1242194D03*
Y1246194D03*
X504647Y1257160D03*
X507347D03*
X501647D03*
Y1260160D03*
X495647D03*
X492647D03*
Y1257160D03*
X495647D03*
X498647D03*
Y1260160D03*
X507347D03*
X504647D03*
X521872Y82593D03*
Y85193D03*
Y74793D03*
Y77393D03*
Y79993D03*
X521916Y92874D03*
X512958Y99961D03*
X513008Y95236D03*
X523943Y107649D03*
Y104249D03*
X520965Y162368D03*
X523565D03*
X511820Y207978D03*
Y210478D03*
Y215478D03*
Y212978D03*
X522276Y208213D03*
Y213213D03*
Y210713D03*
Y215713D03*
X515149Y264180D03*
X517649D03*
X515074Y258880D03*
X524043Y270026D03*
Y267526D03*
X514769Y312953D03*
X519638Y314346D03*
X511790Y313804D03*
X512943Y443071D03*
X520823Y442603D03*
X511753Y454339D03*
Y456839D03*
X509253D03*
Y454339D03*
X518240Y459371D03*
X509253Y459339D03*
X511753D03*
X512210Y475825D03*
X517310Y470045D03*
X513310Y462004D03*
X522756Y461818D03*
X508325Y485138D03*
X512210Y478625D03*
X513910Y482425D03*
X513325Y485138D03*
X510825D03*
X519786Y491214D03*
X523489Y492987D03*
X519786Y493714D03*
X523489Y495487D03*
X509955Y537958D03*
X513658Y539731D03*
X518716Y541895D03*
X521216Y544895D03*
Y541895D03*
X513658Y542231D03*
X518416Y544895D03*
X509955Y540458D03*
X521494Y582747D03*
X508086Y581222D03*
X520945Y590801D03*
X508086Y591215D03*
X520770Y597130D03*
X524770Y605637D03*
X518940Y620653D03*
Y617853D03*
X511058Y610562D03*
Y607762D03*
X508258Y610562D03*
Y607762D03*
X520770Y605443D03*
X516770D03*
X523616Y625013D03*
X515267Y627908D03*
X511278Y633473D03*
X521778Y642184D03*
X521868Y666577D03*
X518812Y662874D03*
X510425Y683246D03*
X522200Y677613D03*
X521540Y686319D03*
X515484Y695757D03*
X515504Y701351D03*
X521159Y706388D03*
X515649D03*
X512530Y718301D03*
X514531Y716398D03*
X523929Y706388D03*
X518389D03*
X521131Y741071D03*
X517731D03*
X511724Y741035D03*
X508324D03*
X520549Y761982D03*
X509096Y753072D03*
X515422Y753455D03*
X513504Y755804D03*
X513278Y783286D03*
X520833Y773389D03*
X513551Y773203D03*
X522697Y797102D03*
X519891Y795848D03*
X518157Y803973D03*
X518565Y811973D03*
X520741Y805149D03*
X522481Y824661D03*
X517702Y826600D03*
X514682Y834590D03*
X511741Y846649D03*
X524741Y845149D03*
X520870Y874694D03*
X525159Y913818D03*
X521572Y901500D03*
X516902Y910251D03*
X520146Y939241D03*
X523289Y939195D03*
X521353Y952266D03*
X522544Y992854D03*
X512232Y985172D03*
X514566Y1000766D03*
X514690Y996766D03*
Y1004766D03*
X514566Y1016266D03*
X514649Y1020266D03*
X514843Y1030766D03*
X519500Y1028377D03*
X518497Y1105552D03*
X522775Y1101917D03*
X521055Y1104335D03*
X514703Y1104792D03*
X522710Y1106897D03*
X516210Y1106867D03*
X509795Y1113648D03*
X512295D03*
X520646Y1169884D03*
Y1167384D03*
Y1164884D03*
Y1162384D03*
X523146D03*
Y1164884D03*
Y1167384D03*
Y1169884D03*
Y1172384D03*
X520646D03*
X520751Y1186921D03*
Y1184421D03*
Y1181921D03*
Y1179421D03*
X523146Y1174884D03*
X520646D03*
X523066Y1190121D03*
Y1192621D03*
X522562Y1222194D03*
X518562D03*
X514562D03*
X510562D03*
X522562Y1226194D03*
X518562D03*
Y1230194D03*
Y1234194D03*
X514562Y1226194D03*
Y1230194D03*
Y1234194D03*
Y1238194D03*
X510562Y1226194D03*
Y1230194D03*
Y1234194D03*
Y1238194D03*
X514562Y1242194D03*
Y1246194D03*
X510562Y1242194D03*
Y1246194D03*
X530197Y98551D03*
X540751Y97475D03*
X533092Y114623D03*
Y111223D03*
X533747Y103783D03*
X533092Y128796D03*
Y125396D03*
X532281Y141247D03*
X528509Y147540D03*
X539748Y143740D03*
X537128Y148277D03*
X530665Y162793D03*
Y165393D03*
Y170493D03*
Y167993D03*
X538170Y172190D03*
X535668Y181009D03*
X529662Y181426D03*
X532873Y181366D03*
X537589Y177616D03*
X529870Y184221D03*
X532487Y184012D03*
X533906Y211359D03*
Y213859D03*
X528848Y211695D03*
X537609Y213132D03*
X526348Y208695D03*
X529148D03*
X526348Y211695D03*
X537609Y215632D03*
X537853Y256303D03*
X532525Y265701D03*
X537612Y265896D03*
X526843Y270026D03*
X529343D03*
X526843Y267526D03*
X529343D03*
X534160Y281716D03*
X540101Y281982D03*
X532659Y359557D03*
X526388Y351301D03*
X531612Y354272D03*
X531636Y349057D03*
X528812Y369164D03*
X533211Y364746D03*
X533115Y371856D03*
X530144Y376062D03*
X531953Y380749D03*
X542034Y392209D03*
X541706Y386223D03*
X533189Y390723D03*
X531953Y385749D03*
X531992Y397552D03*
X526216Y456652D03*
X528716D03*
X526216Y459152D03*
Y461652D03*
X528716Y459152D03*
Y461652D03*
X535119Y491133D03*
X531047Y498151D03*
X535119Y493633D03*
Y496133D03*
Y498633D03*
X531047Y495151D03*
X528547D03*
X528247Y498151D03*
X525288Y537877D03*
X535219Y555897D03*
Y553297D03*
X533488Y548344D03*
X525288Y540377D03*
Y545377D03*
Y542877D03*
X528488Y548344D03*
X525988D03*
X530988D03*
X535219Y561097D03*
Y563697D03*
Y566797D03*
Y558497D03*
X532009Y570478D03*
X529214Y570686D03*
X529423Y573303D03*
X532069Y573689D03*
X532426Y576484D03*
X535819Y578405D03*
X541245Y578986D03*
X524770Y597232D03*
X534820Y596782D03*
X540770Y596729D03*
X529601Y596089D03*
X526756Y613913D03*
Y616713D03*
Y619513D03*
X538826Y614158D03*
Y616958D03*
Y619758D03*
X536770Y605443D03*
X537664Y661556D03*
X534264D03*
X529664Y664056D03*
X526264D03*
X538316Y687357D03*
X535738Y687489D03*
X536087Y702364D03*
X529469Y706230D03*
X526699Y706388D03*
X535585Y736593D03*
X538985D03*
X530985Y741593D03*
X527585D03*
X524598Y753387D03*
X539449Y782389D03*
X537578Y772428D03*
X532304Y806649D03*
X531313Y812850D03*
Y826630D03*
X532316Y833649D03*
X534000Y843000D03*
X537300Y842900D03*
X530741Y845149D03*
X534632Y849830D03*
X525718Y873821D03*
X533468Y878533D03*
X538468Y888033D03*
X530968Y888283D03*
X528975Y898346D03*
X537279Y897943D03*
X533143Y897910D03*
X531076Y913190D03*
X527879Y952189D03*
X530473Y961728D03*
X528500Y1106365D03*
X529191Y1115896D03*
X525525Y1110092D03*
X529191Y1118396D03*
X528274Y1160834D03*
X554198Y68581D03*
X554211Y80581D03*
X546293Y76587D03*
Y72615D03*
X547732Y100625D03*
X540682Y106186D03*
X552105Y112083D03*
X556394Y103621D03*
X543494Y121735D03*
Y132509D03*
Y118335D03*
Y135909D03*
X548311Y141247D03*
X552798Y143518D03*
X551898Y152373D03*
X555048Y152562D03*
X540843Y168697D03*
X555850Y178560D03*
X555913Y172665D03*
X555740Y183834D03*
X541931Y191941D03*
X555260Y190185D03*
X549985Y192490D03*
X556030Y200864D03*
X548940Y206767D03*
X546440D03*
X543940D03*
X556119Y212455D03*
X556053Y207037D03*
X549070Y221708D03*
X546570D03*
X553420Y221642D03*
X545185Y231021D03*
Y228221D03*
X544070Y221708D03*
X543485Y224421D03*
X550736Y236189D03*
X548236D03*
X545736D03*
X550677Y248765D03*
X548177D03*
X545677D03*
X542628Y266114D03*
X545874Y268195D03*
X548374D03*
X551174Y270695D03*
X554834Y265897D03*
X551174Y268195D03*
X548374Y270695D03*
X545874D03*
X551536Y359223D03*
Y354723D03*
Y350223D03*
Y345723D03*
Y377223D03*
Y372723D03*
Y368223D03*
Y363723D03*
Y381723D03*
X551620Y390723D03*
X553563Y384987D03*
X544738Y581659D03*
X544770Y605443D03*
X551475Y661504D03*
X547227Y678299D03*
X547276Y675521D03*
X543101Y698772D03*
X540379Y719785D03*
X557751Y750851D03*
X549168Y781600D03*
X545768D03*
X550420Y793743D03*
X556326D03*
X540578Y793889D03*
X544515Y793875D03*
X544741Y809649D03*
X544878Y816309D03*
X546855Y829949D03*
X550087Y829836D03*
X556326Y829989D03*
X556741Y820149D03*
X544741Y823149D03*
X546241Y843149D03*
X557836Y851669D03*
X548665Y850399D03*
X540968Y878360D03*
X546940Y871389D03*
X548327Y905295D03*
X552238Y959102D03*
X552923Y988813D03*
X542793Y998507D03*
X544719Y1007522D03*
X551485Y1006648D03*
X551673Y1023900D03*
X548852Y1018307D03*
X545094Y1013678D03*
X545566Y1023731D03*
X554696Y1018469D03*
X556493Y1118351D03*
X557584Y1543411D03*
X560573Y60513D03*
X563433Y60438D03*
X557973Y55513D03*
X569114Y86012D03*
X558341Y88801D03*
X569114Y94374D03*
X561258Y94351D03*
X565207Y94279D03*
X560701Y85731D03*
X564255Y86046D03*
X564451Y116594D03*
X570394Y110784D03*
X564451Y119594D03*
X574973Y124663D03*
X564885Y124283D03*
X569951Y124879D03*
X563292Y161306D03*
X560543Y157370D03*
X564627Y176665D03*
Y168665D03*
X556726Y186629D03*
X564627Y196665D03*
Y192665D03*
X564740Y186778D03*
X564659Y204864D03*
Y208864D03*
X569708Y218085D03*
X572508D03*
X560300Y219379D03*
X560928Y228631D03*
X575035Y249108D03*
X566416Y248371D03*
X557334Y265897D03*
X573479Y374705D03*
X569938Y378317D03*
X559070Y684809D03*
Y700809D03*
Y688209D03*
X561570Y696209D03*
Y692809D03*
X559070Y716809D03*
X561570Y708809D03*
Y712209D03*
X559070Y704209D03*
Y720209D03*
X558616Y732530D03*
X562001Y732834D03*
X562374Y721593D03*
X567428Y750145D03*
X557847Y744599D03*
X563200Y739600D03*
X571493Y763090D03*
X570038Y752339D03*
X564362Y757979D03*
X560263Y782207D03*
X567126Y779066D03*
X571984Y784507D03*
X561001Y806889D03*
X567559Y803008D03*
Y824661D03*
X562400Y818900D03*
X560813Y840574D03*
X568990Y844721D03*
X572476Y845535D03*
X559295Y874267D03*
X559887Y877196D03*
X561134Y869291D03*
X559260Y891043D03*
X559214Y897425D03*
X564165Y894411D03*
X567827Y884000D03*
X562328Y957307D03*
X566303Y951807D03*
X569403D03*
X563103D03*
X570603Y957207D03*
X560923Y980443D03*
X556923Y980523D03*
X564923Y988813D03*
X560923D03*
X556923D03*
X568923D03*
X558112Y1009655D03*
X560912D03*
X567484Y1024003D03*
X571857Y1016827D03*
X559057Y1030563D03*
X562057D03*
X568057Y1030672D03*
X565057D03*
X571857Y1029427D03*
X566058Y1109564D03*
X560211D03*
X566058Y1122164D03*
X560211D03*
X566058Y1134764D03*
X560211D03*
X566058Y1147364D03*
X560211D03*
X566058Y1159964D03*
X560211D03*
X566058Y1172564D03*
X560211D03*
X566058Y1185164D03*
X560211D03*
X568532Y1200001D03*
X575620Y1207737D03*
X569135Y1214372D03*
X564890Y1218169D03*
X570796Y1530309D03*
X567324Y1528151D03*
X572432Y1521462D03*
X565400Y1535100D03*
X563968Y1541445D03*
X568279Y1538438D03*
X572507Y1541375D03*
X586037Y97667D03*
X581693Y102495D03*
X576420Y116594D03*
X575394Y110784D03*
X576420Y119594D03*
X579954Y125107D03*
X581427Y142862D03*
X588568Y143762D03*
X582468Y148717D03*
X576317Y138838D03*
X587516Y195176D03*
X585016D03*
X589034Y199248D03*
X587597Y210509D03*
X585097D03*
X589034Y201748D03*
X586870Y206806D03*
X576308Y216385D03*
X579021Y216970D03*
Y219470D03*
X579087Y226320D03*
X579021Y221970D03*
X586789Y230556D03*
X591044Y227824D03*
X582048Y228646D03*
X585774Y242078D03*
X581005Y232971D03*
X577655Y244571D03*
X584998Y256394D03*
X578193Y336391D03*
X584679Y336285D03*
X576556Y728219D03*
X575979Y732517D03*
X573778Y747437D03*
X577638Y769772D03*
X578271Y763556D03*
X583102Y767137D03*
X587183Y785008D03*
X578204Y775137D03*
X585912Y778470D03*
X588345Y798030D03*
X588659Y790336D03*
X582100Y787600D03*
X586060Y793145D03*
X581001Y810973D03*
X588377Y807536D03*
X588272Y804601D03*
X588231Y801520D03*
X577501Y829069D03*
X588001Y829624D03*
X582737Y819831D03*
X581158Y823473D03*
X573300Y829600D03*
X579827Y888000D03*
X580327Y892000D03*
X586136Y908935D03*
X583065Y903294D03*
X573103Y941307D03*
X585703D03*
X586103Y961807D03*
X573895Y965319D03*
X584923Y988813D03*
X576923D03*
X580923D03*
X588923D03*
X572923D03*
X577704Y1029427D03*
Y1016827D03*
X587880Y1034834D03*
X581967Y1105091D03*
X587467D03*
X582012Y1102091D03*
X587467Y1117691D03*
X581967D03*
X582012Y1127291D03*
Y1114691D03*
X587467Y1130291D03*
X581967D03*
X587467Y1142891D03*
X582012Y1139891D03*
X581967Y1155491D03*
X587467D03*
X581967Y1142891D03*
X582012Y1152491D03*
X581967Y1168091D03*
X587467D03*
X582012Y1165091D03*
X581967Y1180691D03*
X587467D03*
X582012Y1177691D03*
X586502Y1227300D03*
X583520Y1230407D03*
X581803Y1493687D03*
X578859Y1497758D03*
X588859Y1490895D03*
X590826Y1495688D03*
X588507Y1514141D03*
X582027Y1502800D03*
X581803Y1509687D03*
X577931Y1505687D03*
X575809Y1532912D03*
X572849Y1518702D03*
X587809Y1528389D03*
X583809Y1533025D03*
X579809Y1528163D03*
X587809Y1545854D03*
X583809Y1541607D03*
X577571Y1544013D03*
X594497Y103411D03*
X594891Y97667D03*
X605687Y90650D03*
X590287Y95111D03*
X594656Y106561D03*
X590016Y195176D03*
X592516D03*
X592034Y199248D03*
Y202048D03*
X589370Y206806D03*
X595634Y230117D03*
X591131Y246874D03*
X591650Y238714D03*
X593351Y244297D03*
X592900Y309871D03*
X605147Y378600D03*
Y382600D03*
X597776Y401513D03*
Y398113D03*
X595376Y412287D03*
Y426460D03*
Y415687D03*
Y440633D03*
Y429860D03*
X605262Y458711D03*
X595376Y444033D03*
X602462Y458711D03*
X595376Y469387D03*
Y472787D03*
X604606Y463600D03*
X595376Y483560D03*
Y486960D03*
X598462Y504684D03*
X595376Y513521D03*
Y516921D03*
Y531094D03*
Y527694D03*
X599110Y552466D03*
X605011Y603600D03*
Y619600D03*
Y623600D03*
X592272Y877262D03*
X592110Y895611D03*
X601084Y913544D03*
X604715Y914640D03*
X589203Y941407D03*
X591403Y938807D03*
Y936007D03*
X591754Y956979D03*
X597556Y965829D03*
X602484Y965764D03*
X600923Y988813D03*
X592923D03*
X604923D03*
X596923D03*
X599113Y1012354D03*
X593658Y1009354D03*
X593613Y1012354D03*
X599113Y1024954D03*
X593613D03*
X593658Y1021954D03*
X606434Y1041904D03*
X603682Y1053457D03*
X594183Y1220068D03*
X593519Y1224472D03*
X592885Y1229402D03*
X592634Y1234921D03*
X591487Y1501687D03*
X591481Y1509313D03*
X595809Y1532133D03*
X591872Y1518071D03*
X595809Y1546214D03*
X591809Y1542407D03*
X610999Y90615D03*
X615370Y95236D03*
X615320Y99961D03*
X605437Y95236D03*
X620727Y162368D03*
X614182Y210478D03*
Y215478D03*
Y212978D03*
Y207978D03*
X617511Y264180D03*
X620011D03*
X617436Y258880D03*
X605778Y391001D03*
Y405174D03*
Y394401D03*
Y408574D03*
Y422747D03*
Y419347D03*
Y433521D03*
Y436921D03*
X607789Y453682D03*
X606026Y455921D03*
X605778Y479899D03*
Y490673D03*
Y476499D03*
Y494073D03*
Y520633D03*
Y524033D03*
Y534806D03*
Y538206D03*
X609133Y941137D03*
X605733D03*
X608965Y966414D03*
X616923Y988813D03*
X608923D03*
X612923Y997860D03*
X618878Y1011914D03*
X621479Y1030482D03*
X607993Y1036920D03*
X610780Y1051037D03*
X617634Y1049283D03*
X617894Y1043955D03*
X612955Y1062941D03*
X622736Y1151870D03*
Y1159350D03*
X613738Y1546507D03*
X624234Y74793D03*
Y82593D03*
Y85193D03*
Y77393D03*
Y79993D03*
X624278Y92874D03*
X632559Y98551D03*
X635454Y114623D03*
Y111223D03*
X636109Y103783D03*
X626305Y104249D03*
Y107649D03*
X635454Y128796D03*
Y125396D03*
X630871Y147540D03*
X634643Y141247D03*
X639490Y148277D03*
X625927Y162368D03*
X623327D03*
X633027Y165393D03*
Y162793D03*
Y170493D03*
Y167993D03*
X639951Y177616D03*
X632024Y181426D03*
X635235Y181366D03*
X632232Y184221D03*
X634849Y184012D03*
X628710Y211695D03*
Y208695D03*
X631510D03*
X624638Y208213D03*
X636268Y211359D03*
Y213859D03*
X631210Y211695D03*
X624638Y213213D03*
Y210713D03*
Y215713D03*
X639974Y265896D03*
X634887Y265701D03*
X629205Y267526D03*
X626405D03*
X631705D03*
X629205Y270026D03*
X626405D03*
X631705D03*
X636522Y281716D03*
X632009Y541863D03*
Y545263D03*
X630201Y553407D03*
X632701D03*
X630201Y550907D03*
X632701D03*
X634185Y569426D03*
X634471Y566929D03*
X628425Y572070D03*
X629772Y569928D03*
X632119Y570962D03*
X631862Y568475D03*
X621592Y1033862D03*
X626476Y1155610D03*
X621727Y1556800D03*
X648655Y76587D03*
Y72615D03*
X650094Y100625D03*
X643113Y97475D03*
X643044Y106186D03*
X645856Y118335D03*
Y132509D03*
Y121735D03*
Y135909D03*
X650673Y141247D03*
X655160Y143518D03*
X642110Y143740D03*
X654260Y152373D03*
X640532Y172190D03*
X638030Y181009D03*
X643205Y168697D03*
X644293Y191941D03*
X652347Y192490D03*
X646302Y206767D03*
X651302D03*
X648802D03*
X639971Y213132D03*
X648932Y221708D03*
X647547Y228221D03*
X645847Y224421D03*
X647547Y231021D03*
X646432Y221708D03*
X651432D03*
X639971Y215632D03*
X650598Y236189D03*
X648098D03*
X653098D03*
X653039Y248765D03*
X650539D03*
X648039D03*
X640215Y256303D03*
X644990Y266114D03*
X650736Y268195D03*
X653536Y270695D03*
Y268195D03*
X650736Y270695D03*
X648236D03*
Y268195D03*
X642463Y281982D03*
X642414Y545528D03*
X651149Y577716D03*
X648211Y610400D03*
X650958Y668153D03*
X662935Y60513D03*
X665795Y60438D03*
X657507Y58013D03*
X656560Y68581D03*
X671476Y86012D03*
X656573Y80581D03*
X660703Y88801D03*
X663620Y94351D03*
X667569Y94279D03*
X663063Y85731D03*
X666617Y86046D03*
X658756Y103621D03*
X666813Y116594D03*
X654467Y112083D03*
X666813Y119594D03*
X667247Y124283D03*
X672313Y124879D03*
X665654Y161306D03*
X657410Y152562D03*
X662905Y157370D03*
X666989Y176665D03*
Y168665D03*
X658275Y172665D03*
X658212Y178560D03*
X658102Y183834D03*
X659088Y186629D03*
X657622Y190185D03*
X658392Y200864D03*
X666989Y196665D03*
Y192665D03*
X667102Y186778D03*
X667021Y204864D03*
Y208864D03*
X658481Y212455D03*
X658415Y207037D03*
X655782Y221642D03*
X662662Y219379D03*
X663290Y228631D03*
X668886Y248371D03*
X657196Y265897D03*
X659696D03*
X661761Y382109D03*
X661760Y551683D03*
Y561420D03*
Y558917D03*
X657581Y577937D03*
X660586Y606929D03*
X665086Y604567D03*
X665586Y595500D03*
X660827Y612592D03*
X666244Y610072D03*
X660546Y618400D03*
X666180Y616317D03*
X665643Y646055D03*
X658233Y646449D03*
X658064Y650119D03*
X657967Y662981D03*
X662092Y666275D03*
X659209Y691851D03*
X661018Y707592D03*
X688399Y97667D03*
X671476Y94374D03*
X678782Y116594D03*
X684055Y102495D03*
X677756Y110784D03*
X672756D03*
X678782Y119594D03*
X682316Y125107D03*
X677335Y124663D03*
X683789Y142862D03*
X684830Y148717D03*
X678679Y138838D03*
X674870Y218085D03*
X681383Y219470D03*
Y216970D03*
X678670Y216385D03*
X681383Y221970D03*
X681449Y226320D03*
X672070Y218085D03*
X684410Y228646D03*
X683367Y232971D03*
X677397Y249108D03*
X680017Y244571D03*
X682857Y339477D03*
X687055Y376456D03*
X685353Y396718D03*
X678461Y455981D03*
X675237Y465611D03*
X682586Y530000D03*
X682086Y540500D03*
X681086Y547075D03*
X681286Y549800D03*
X680586Y568000D03*
X681126Y558800D03*
X681190Y562800D03*
X696859Y103411D03*
X697253Y97667D03*
X692649Y95111D03*
X697018Y106561D03*
X690930Y143762D03*
X691396Y199248D03*
X687378Y195176D03*
X689878D03*
X694396Y199248D03*
X694878Y195176D03*
X692378D03*
X691396Y201748D03*
X689232Y206806D03*
X687459Y210509D03*
X689959D03*
X694396Y202048D03*
X691732Y206806D03*
X697996Y230117D03*
X689151Y230556D03*
X693406Y227824D03*
X694012Y238714D03*
X688136Y242078D03*
X693493Y246874D03*
X695713Y244297D03*
X690504Y253198D03*
X689486Y339583D03*
X702448Y546712D03*
Y542712D03*
X699188Y656321D03*
X702086Y678462D03*
X692478Y730641D03*
X702691Y762971D03*
Y756971D03*
X692356Y764614D03*
X691991Y759581D03*
X702677Y780659D03*
Y775159D03*
X692155Y778974D03*
X692221Y773449D03*
X690449Y814406D03*
X708049Y90650D03*
X713361Y90615D03*
X717732Y95236D03*
X717682Y99961D03*
X707799Y95236D03*
X716544Y215478D03*
Y210478D03*
Y207978D03*
Y212978D03*
X718338Y305272D03*
X712692Y356779D03*
X717105Y410964D03*
X717420Y404334D03*
X709781Y442956D03*
X720996Y442856D03*
X711598Y438323D03*
X719051Y458455D03*
X719612Y451108D03*
X710643Y456335D03*
X711764Y445873D03*
X706211Y465874D03*
X711463Y546712D03*
X704364Y618288D03*
X711328Y653821D03*
X705390Y655789D03*
X705776Y678519D03*
X713200Y699676D03*
X716623Y702463D03*
X703600Y702212D03*
X703680Y697094D03*
X715802Y706446D03*
X710196Y707562D03*
X717434Y782500D03*
X710275Y786131D03*
X713222Y793312D03*
Y790812D03*
X712901Y821600D03*
X726596Y74793D03*
Y77393D03*
Y79993D03*
Y85193D03*
Y82593D03*
X726640Y92874D03*
X734921Y98551D03*
X728667Y104249D03*
Y107649D03*
X733233Y147540D03*
X728289Y162368D03*
X725689D03*
X734386Y181426D03*
X734594Y184221D03*
X727000Y213213D03*
Y208213D03*
X733872Y208695D03*
X731072D03*
X733572Y211695D03*
X731072D03*
X727000Y210713D03*
Y215713D03*
X722373Y264180D03*
X719873D03*
X719798Y258880D03*
X737249Y265701D03*
X731567Y267526D03*
X728767D03*
X734067D03*
Y270026D03*
X731567D03*
X728767D03*
X723404Y379657D03*
X721900Y384500D03*
X723440Y391496D03*
X734661Y393633D03*
X731511Y381113D03*
X723440Y398583D03*
X732035Y442606D03*
X722097Y453881D03*
X731952Y446606D03*
X722097Y446595D03*
X732959Y463479D03*
X733430Y467367D03*
X724362Y504731D03*
X722473Y693718D03*
X723656Y705858D03*
X720985Y711658D03*
X725667Y732161D03*
X723177Y728219D03*
X721163Y738981D03*
X733000Y816000D03*
X730880Y828924D03*
X733680Y828977D03*
X732713Y853890D03*
X722600Y869600D03*
X728503Y891692D03*
X736452Y890548D03*
X728692Y886653D03*
X724707Y893143D03*
X719661Y904900D03*
X722789Y927095D03*
X722400Y942500D03*
X725194Y942073D03*
X720271Y931730D03*
X732306Y942682D03*
X728846Y948331D03*
X733798Y950186D03*
X727116Y959326D03*
X732825Y1604100D03*
X736067Y1611892D03*
X729600Y1625165D03*
X732268Y1618260D03*
X751017Y76587D03*
Y72615D03*
X752456Y100625D03*
X745475Y97475D03*
X737816Y114623D03*
Y111223D03*
X745406Y106186D03*
X738471Y103783D03*
X748218Y118335D03*
X737816Y128796D03*
X748218Y132509D03*
Y121735D03*
X737816Y125396D03*
X748218Y135909D03*
X737005Y141247D03*
X744472Y143740D03*
X741852Y148277D03*
X735389Y165393D03*
Y162793D03*
Y170493D03*
Y167993D03*
X740392Y181009D03*
X737597Y181366D03*
X745567Y168697D03*
X742894Y172190D03*
X742313Y177616D03*
X746655Y191941D03*
X737211Y184012D03*
X750667Y192300D03*
X751164Y206767D03*
X748664D03*
X738630Y213859D03*
Y211359D03*
X742333Y213132D03*
X749909Y228221D03*
Y231021D03*
X751294Y221708D03*
X748209Y224421D03*
X748794Y221708D03*
X742333Y215632D03*
X750460Y236189D03*
X750401Y248765D03*
X742577Y256303D03*
X747352Y266114D03*
X742336Y265896D03*
X750598Y268195D03*
Y270695D03*
X744825Y281982D03*
X738884Y281716D03*
X741051Y316389D03*
X749444Y393858D03*
X749606Y384410D03*
X752785Y382047D03*
X753086Y403500D03*
X751086Y398583D03*
X749539Y438269D03*
Y440869D03*
Y435669D03*
Y430469D03*
Y433069D03*
X735599Y449961D03*
X739316Y458572D03*
X750393Y451677D03*
Y454177D03*
X741992Y763480D03*
X742000Y768137D03*
X743428Y772418D03*
X741993Y775909D03*
X736000Y864266D03*
X742407Y988452D03*
X743062Y1004460D03*
X749439Y1458777D03*
X740530Y1524113D03*
X747140Y1581335D03*
X749786Y1590517D03*
X738775Y1597866D03*
X737892Y1602340D03*
X749704Y1608631D03*
X744924Y1617709D03*
X743331Y1627871D03*
X741705Y1622015D03*
X738325Y1634485D03*
X762697Y55513D03*
X758922Y68581D03*
X765297Y60513D03*
X758935Y80581D03*
X763065Y88801D03*
X765982Y94351D03*
X769931Y94279D03*
X765425Y85731D03*
X756829Y112083D03*
X761118Y103621D03*
X769609Y124283D03*
X753035Y141247D03*
X757522Y143518D03*
X756622Y152373D03*
X759772Y152562D03*
X765267Y157370D03*
X760637Y172665D03*
X760464Y183834D03*
X760574Y178560D03*
X761450Y186629D03*
X754709Y192490D03*
X759984Y190185D03*
X760754Y200864D03*
X753182Y198671D03*
X753664Y206767D03*
X769383Y208864D03*
X760843Y212455D03*
X760777Y207037D03*
X753794Y221708D03*
X758144Y221642D03*
X765024Y219379D03*
X763653Y224536D03*
X752960Y236189D03*
X755460D03*
X755401Y248765D03*
X752901D03*
X753098Y268195D03*
X755898D03*
X753098Y270695D03*
X755898D03*
X759558Y265897D03*
X762058D03*
X769349Y324518D03*
X759029Y328867D03*
X754805Y339559D03*
X759624Y353961D03*
X756086Y377912D03*
X766344D03*
X755086Y391496D03*
X756086Y386500D03*
X766344Y381912D03*
X756174Y397912D03*
X755086Y409000D03*
X766344Y397912D03*
X752339Y438269D03*
Y433069D03*
Y430469D03*
Y435669D03*
Y440869D03*
X752893Y451677D03*
Y454177D03*
X752097Y460218D03*
Y463618D03*
X755035Y1443524D03*
X765713Y1437365D03*
X760398Y1440276D03*
X755187Y1580821D03*
X759802Y1590864D03*
X763542Y1590186D03*
X768361Y1610083D03*
X762671Y1619367D03*
X756358Y1613767D03*
X768157Y60438D03*
X773838Y86012D03*
Y94374D03*
X768979Y86046D03*
X781144Y116594D03*
X769175D03*
X775118Y110784D03*
X780118D03*
X781144Y119594D03*
X769175D03*
X784678Y125107D03*
X779697Y124663D03*
X774675Y124879D03*
X781041Y138838D03*
X768016Y161306D03*
X769351Y176665D03*
Y168665D03*
Y192665D03*
X769464Y186778D03*
X769383Y204864D03*
X774432Y218085D03*
X777232D03*
X783745Y216970D03*
X781032Y216385D03*
X783745Y221970D03*
X783811Y226320D03*
X783745Y219470D03*
X782379Y244571D03*
X779759Y249108D03*
X771140Y248371D03*
X772165Y314890D03*
X784118Y303962D03*
X771941Y311740D03*
X772162Y332584D03*
X778502Y348015D03*
X772859Y347937D03*
X774419Y353470D03*
X784902Y428653D03*
X778079Y467306D03*
Y470706D03*
Y481479D03*
Y484879D03*
Y514839D03*
Y511439D03*
Y529013D03*
Y525613D03*
X775746Y539315D03*
X777708Y553287D03*
X781429Y545017D03*
X778079Y561479D03*
Y564879D03*
Y575652D03*
Y579052D03*
Y589825D03*
Y593225D03*
Y603999D03*
Y607399D03*
X778860Y626912D03*
X778205Y622912D03*
X783694Y1410977D03*
X778685Y1416198D03*
X780162Y1412848D03*
X777749Y1431432D03*
X783469Y1424655D03*
X771557Y1446818D03*
X768910Y1437741D03*
X777749Y1435432D03*
Y1439432D03*
X777260Y1446237D03*
X778428Y1455156D03*
X777725Y1450193D03*
X783620Y1460108D03*
X768812Y1453306D03*
X781124Y1583553D03*
X781110Y1595254D03*
X777059Y1608982D03*
X784046Y1600438D03*
X778045Y1619395D03*
X778358Y1627418D03*
X771383Y1616917D03*
X799221Y103411D03*
X799615Y97667D03*
X790761D03*
X795011Y95111D03*
X786417Y102495D03*
X799380Y106561D03*
X786151Y142862D03*
X793292Y143762D03*
X787192Y148717D03*
X796758Y199248D03*
X797240Y195176D03*
X794740D03*
X789740D03*
X792240D03*
X793758Y199248D03*
X794094Y206806D03*
X791594D03*
X789821Y210509D03*
X792321D03*
X793758Y201748D03*
X796758Y202048D03*
X800358Y230117D03*
X795768Y227824D03*
X791513Y230556D03*
X786772Y228646D03*
X796374Y238714D03*
X790498Y242078D03*
X785729Y232971D03*
X795855Y246874D03*
X798075Y244297D03*
X789722Y256394D03*
X786461Y293028D03*
X790280Y287421D03*
X800155Y337368D03*
X800029Y333368D03*
X797141Y350368D03*
X795445Y356950D03*
X789581Y405011D03*
X793893Y409502D03*
X784804Y425371D03*
X794173Y450510D03*
X802136Y448334D03*
X788481Y474418D03*
Y477818D03*
Y488591D03*
Y491991D03*
Y518552D03*
Y521952D03*
Y532725D03*
Y536125D03*
X796000Y553101D03*
X788481Y571991D03*
Y568591D03*
Y586165D03*
Y582765D03*
Y600338D03*
Y596938D03*
Y614511D03*
Y611111D03*
X788600Y1006923D03*
X799631Y1025440D03*
X795631D03*
X789050Y1026150D03*
X796338Y1138130D03*
X793842Y1143384D03*
X797160Y1146609D03*
X792277Y1173065D03*
X799020Y1175975D03*
X798353Y1172011D03*
X787887Y1174500D03*
X798542Y1188345D03*
X792382Y1191664D03*
X794533Y1195766D03*
X794983Y1334030D03*
Y1331230D03*
X793548Y1397690D03*
X795296Y1416995D03*
X792848Y1414718D03*
X793459Y1429165D03*
X789647Y1427518D03*
X788648Y1422044D03*
X785820Y1425993D03*
X798601Y1431673D03*
X793288Y1450918D03*
X793744Y1437159D03*
X786787Y1433800D03*
X787694Y1442749D03*
X800607Y1440760D03*
X790361Y1447895D03*
X790754Y1441399D03*
X793994Y1441499D03*
X799057Y1449158D03*
X797083Y1467883D03*
X799057Y1456016D03*
X794005Y1464178D03*
X790296Y1463459D03*
X787038Y1460533D03*
X786591Y1452803D03*
X790989Y1455695D03*
X799314Y1475693D03*
X797318Y1471242D03*
X810411Y90650D03*
X815723Y90615D03*
X810161Y95236D03*
X805952Y301675D03*
X817456Y305368D03*
Y313368D03*
X809490Y305368D03*
X809466Y310604D03*
X801097Y325858D03*
X817100Y319600D03*
X809457Y330459D03*
X809490Y325368D03*
Y317368D03*
X809489Y313830D03*
X809490Y321368D03*
Y333368D03*
X816177Y441442D03*
X813456Y441474D03*
X810749Y443045D03*
X815840Y444091D03*
Y456060D03*
X810453Y453330D03*
X810406Y448214D03*
X810756Y471071D03*
Y468571D03*
X814580Y468806D03*
X814828Y472053D03*
X810756Y473571D03*
Y476071D03*
X813902Y730738D03*
X813678Y740979D03*
X813653Y746856D03*
X817584Y764219D03*
X813635Y762000D03*
X818000Y797000D03*
X817845Y817879D03*
X818500Y810135D03*
X813000Y805000D03*
X813548Y814000D03*
X813009Y819734D03*
X815500Y824000D03*
X815863Y830097D03*
X814299Y840877D03*
X813887Y835146D03*
X816037Y845578D03*
X812440Y862306D03*
X814080Y864464D03*
X812575Y880834D03*
X812219Y883586D03*
X817884Y915425D03*
X803673Y1025440D03*
X803453Y1134729D03*
X814835D03*
X806835D03*
X809632Y1142666D03*
X817964Y1157404D03*
X811507Y1157544D03*
X810018Y1167768D03*
X815037D03*
X814160Y1178240D03*
X814170Y1185205D03*
X805212Y1180175D03*
X805519Y1187215D03*
X815455Y1201043D03*
X811485D03*
X807489D03*
X804452Y1199814D03*
X804458Y1193112D03*
X809027Y1219895D03*
X807020Y1217900D03*
X812302Y1223170D03*
X815149Y1226016D03*
X810148Y1374884D03*
X806148Y1383715D03*
Y1375208D03*
X810204Y1401661D03*
X804654Y1404769D03*
X812901Y1432804D03*
X815901D03*
X810059Y1432778D03*
X812104Y1426483D03*
X809986Y1438785D03*
X812986D03*
X815986D03*
X809986Y1441485D03*
X812986D03*
X815986D03*
X812901Y1435504D03*
X815901D03*
X810001D03*
X803057Y1449158D03*
X801057Y1447158D03*
X805569Y1441519D03*
X803057Y1456016D03*
X801057Y1458016D03*
X802684Y1465549D03*
X801354Y1478681D03*
X807576Y1469584D03*
X804919Y1489247D03*
X828958Y79993D03*
Y77393D03*
Y74793D03*
Y85193D03*
Y82593D03*
X829002Y92874D03*
X820094Y95236D03*
X820044Y99961D03*
X831029Y104249D03*
Y107649D03*
X830651Y162368D03*
X828051D03*
X829362Y213213D03*
X818906Y207978D03*
Y212978D03*
Y215478D03*
Y210478D03*
X829362Y208213D03*
Y210713D03*
Y215713D03*
X822235Y264180D03*
X824735D03*
X822160Y258880D03*
X831129Y267526D03*
Y270026D03*
X822477Y309368D03*
X825971Y345101D03*
X829485D03*
X822626Y348066D03*
X818840Y444091D03*
X825103Y430358D03*
Y435558D03*
Y432958D03*
X831378Y433086D03*
Y435686D03*
Y430486D03*
X818840Y456060D03*
X824650Y455034D03*
Y450034D03*
X817328Y472053D03*
X820810Y471243D03*
X817380Y468806D03*
X823544Y475061D03*
Y472561D03*
X820810Y473743D03*
X828918Y480580D03*
X831418D03*
X831057Y484036D03*
X834282Y536085D03*
X828272Y535462D03*
X827291Y533100D03*
X829496Y676793D03*
X829784Y716589D03*
Y705489D03*
X823890Y703415D03*
X823670Y710542D03*
X824387Y726246D03*
X818307Y724144D03*
X821582Y727140D03*
X826484Y747127D03*
X827500Y750000D03*
X819788Y739634D03*
X830484Y738750D03*
X824500Y760500D03*
X830075Y769000D03*
X822151Y752283D03*
X824500Y756000D03*
X817365Y756827D03*
X824500Y778500D03*
Y774000D03*
Y782500D03*
X830075Y787000D03*
X824500Y796500D03*
X824342Y792315D03*
X824500Y800500D03*
X830075Y805000D03*
X824500Y814500D03*
X830075Y823000D03*
X829946Y829788D03*
X825721Y839816D03*
X830014Y833046D03*
X829757Y842672D03*
X822608Y848526D03*
X822916Y852576D03*
X823540Y857956D03*
X831654Y864494D03*
X831583Y853454D03*
X822938Y863298D03*
X826209Y866052D03*
X823234Y870830D03*
X833194Y873561D03*
X827992Y874107D03*
X826070Y893014D03*
X817152Y896380D03*
X817139Y890330D03*
X830063Y898500D03*
X819918Y889365D03*
X823900Y882083D03*
X824804Y898395D03*
X834465Y884538D03*
X829848Y914211D03*
X818031Y907747D03*
X825336Y916774D03*
X831057Y916745D03*
X834751Y922368D03*
X823552Y930700D03*
X829617Y939583D03*
X824414Y939655D03*
X816519Y931147D03*
X824168Y949538D03*
X825670Y964671D03*
X832423Y964669D03*
X828964Y977780D03*
X830356Y1116251D03*
X827856D03*
X825335Y1137129D03*
X819449Y1134534D03*
X819026Y1128137D03*
X825744Y1150087D03*
X823220Y1170767D03*
X818879Y1187310D03*
X823309Y1180235D03*
X823516Y1185238D03*
X819489Y1201039D03*
X823489Y1200969D03*
X823608Y1208993D03*
X819419Y1230265D03*
X817360Y1228226D03*
X816648Y1380758D03*
X824901Y1427404D03*
X827901D03*
X821901D03*
X818901Y1430104D03*
X821901D03*
X830901D03*
X827901D03*
X824901D03*
Y1432804D03*
X827901D03*
X830901D03*
X821901D03*
X818901D03*
X824901Y1435504D03*
X827901D03*
X821901D03*
X818901D03*
X821986Y1441485D03*
X818986D03*
Y1438785D03*
X821986D03*
X826204Y1444689D03*
Y1440689D03*
X826341Y1451236D03*
X826365Y1458974D03*
X826219Y1455244D03*
X837283Y98551D03*
X847837Y97475D03*
X840178Y114623D03*
Y111223D03*
X840833Y103783D03*
X847768Y106186D03*
X840178Y128796D03*
Y125396D03*
X837751Y165393D03*
Y162793D03*
Y170493D03*
Y167993D03*
X842754Y181009D03*
X839959Y181366D03*
X836748Y181426D03*
X847929Y168697D03*
X844675Y177616D03*
X845256Y172190D03*
X839573Y184012D03*
X836956Y184221D03*
X836234Y208695D03*
X833434D03*
X835934Y211695D03*
X840992Y213859D03*
Y211359D03*
X833434Y211695D03*
X844695Y213132D03*
Y215632D03*
X844939Y256303D03*
X844698Y265896D03*
X839611Y265701D03*
X849714Y266114D03*
X836429Y267526D03*
X833929D03*
Y270026D03*
X836429D03*
X841246Y281716D03*
X847187Y281982D03*
X842240Y324854D03*
X848879Y360849D03*
X845435Y356172D03*
X846098Y408715D03*
X849591Y411388D03*
X842515Y461382D03*
X850732Y469382D03*
X842779Y473076D03*
X842916Y467009D03*
X833293Y490636D03*
Y487836D03*
X833918Y480580D03*
X834215Y484138D03*
X844227Y479882D03*
X842476Y482382D03*
X833269Y506683D03*
X833953Y530621D03*
X848444Y657756D03*
X837272Y663910D03*
X839636Y666533D03*
X842352Y659243D03*
X842640Y662814D03*
X838152Y700215D03*
X845784Y705489D03*
Y716589D03*
X845850Y710969D03*
X845784Y708089D03*
X836078Y709619D03*
X835987Y713745D03*
X838484Y746701D03*
X846484Y738750D03*
X836713Y738751D03*
X842661Y769521D03*
X846000Y772079D03*
X840136Y830903D03*
X836839Y831301D03*
X836894Y824401D03*
X848224Y823502D03*
X835626Y843629D03*
X838189Y843459D03*
Y847490D03*
X835215Y847719D03*
X848384Y843459D03*
X846239Y847490D03*
X835553Y835119D03*
X848384Y839459D03*
Y835459D03*
X838194Y836962D03*
X848739Y847459D03*
X837183Y855459D03*
X840234Y851459D03*
X847138Y859459D03*
X839530Y859408D03*
X848384Y863459D03*
X846336Y855459D03*
X845820Y863413D03*
X848384Y851459D03*
X843574Y859423D03*
X837434Y851459D03*
X833327Y855560D03*
X837383Y879530D03*
X837396Y871459D03*
X840234Y875459D03*
X836999Y867413D03*
X845876Y879459D03*
X848384Y867459D03*
X845820Y867413D03*
X848384Y879459D03*
Y871459D03*
Y875459D03*
X837290Y887490D03*
X842827Y895443D03*
X835346Y891346D03*
X848322Y888421D03*
X848792Y896472D03*
X836066Y894955D03*
X847098Y891213D03*
X845633Y883492D03*
X845964Y887490D03*
X837276Y883459D03*
X848200Y883400D03*
X841329Y926602D03*
X841274Y914060D03*
X843315Y916612D03*
X836909Y916618D03*
Y914018D03*
X833683Y939579D03*
X836243D03*
X833683Y949105D03*
X836243D03*
X842856Y949146D03*
X836423Y964669D03*
X835431Y977775D03*
X840935Y1011499D03*
X844058Y1011738D03*
X848045Y1019310D03*
X848070Y1022190D03*
X839744Y1444959D03*
Y1440859D03*
Y1448959D03*
X836704Y1448849D03*
Y1440849D03*
X836744Y1444849D03*
X845306Y1438269D03*
X846844Y1454334D03*
X837685Y1453196D03*
X839744Y1457959D03*
X835474Y1457397D03*
X846044Y1451459D03*
X839744Y1461959D03*
X834475Y1460059D03*
X865059Y55513D03*
X861284Y68581D03*
X861297Y80581D03*
X853379Y76587D03*
Y72615D03*
X854818Y100625D03*
X859191Y112083D03*
X863480Y103621D03*
X850580Y118335D03*
Y132509D03*
Y121735D03*
Y135909D03*
X862826Y183834D03*
X862999Y172665D03*
X862936Y178560D03*
X849017Y191941D03*
X863812Y186629D03*
X857071Y192490D03*
X862346Y190185D03*
X863116Y200864D03*
X853029Y192300D03*
X853526Y206767D03*
X856026D03*
X851026D03*
X863205Y212455D03*
X863139Y207037D03*
X860506Y221642D03*
X852271Y228221D03*
Y231021D03*
X853656Y221708D03*
X856156D03*
X850571Y224421D03*
X851156Y221708D03*
X866015Y224536D03*
X852822Y236189D03*
X855322D03*
X857822D03*
X852763Y248765D03*
X855263D03*
X857763D03*
X852960Y268195D03*
Y270695D03*
X855460D03*
X864420Y265897D03*
X858260Y268195D03*
Y270695D03*
X861920Y265897D03*
X855460Y268195D03*
X863430Y309368D03*
Y316970D03*
X863114Y324505D03*
X863040Y330140D03*
X861770Y343006D03*
X852569Y356712D03*
X856069Y356426D03*
X854086Y374500D03*
X858586D03*
X863086D03*
X860586Y383000D03*
X861235Y394000D03*
X854086Y392999D03*
X864086Y384000D03*
X855017Y411969D03*
X861413Y417071D03*
X858827Y419896D03*
X858410Y413890D03*
X858767Y416685D03*
X861622Y419688D03*
X862882Y458991D03*
X854882D03*
X862882Y461791D03*
X854882D03*
X850748Y465382D03*
X861468Y483303D03*
Y487303D03*
X858169Y495032D03*
X853989Y630453D03*
Y632953D03*
X861663Y646653D03*
X855300Y646819D03*
X853982Y657506D03*
X859441Y678015D03*
X849680Y694789D03*
X858186Y701170D03*
X855646Y692710D03*
X864029Y688970D03*
X867455Y710611D03*
X858002Y707244D03*
X857986Y722670D03*
X854484Y746701D03*
X859199Y744517D03*
X854484Y738633D03*
X859000Y756000D03*
X849500Y758500D03*
Y763500D03*
X863443Y753254D03*
X859000Y764000D03*
Y760000D03*
Y774000D03*
X849500Y776500D03*
Y781500D03*
X861425Y770500D03*
X859000Y781000D03*
Y778000D03*
X853282Y789887D03*
X857632Y789385D03*
X859000Y792000D03*
X849500Y794500D03*
Y799500D03*
X861425Y788500D03*
X859000Y800000D03*
Y796000D03*
X861425Y806500D03*
X859000Y810000D03*
X849500Y812500D03*
X859000Y814000D03*
X850496Y831469D03*
X861425Y824500D03*
X849500Y817500D03*
X859000Y818000D03*
X851184Y839459D03*
Y835459D03*
X859165Y848728D03*
X851239Y847459D03*
X851184Y843459D03*
Y863459D03*
X862114Y859479D03*
X851184Y851459D03*
X859603Y863570D03*
X859461Y859459D03*
X851184Y867459D03*
Y871459D03*
Y875459D03*
X859234Y879600D03*
X859463Y866125D03*
X851184Y879459D03*
X849267Y892567D03*
X859614Y883800D03*
Y887846D03*
X850900Y888359D03*
X850800Y883500D03*
X858988Y898307D03*
X855524Y898505D03*
X864253Y918042D03*
X856628D03*
X849600Y918028D03*
X849205Y924129D03*
X867096Y935963D03*
X858601Y934505D03*
X853030Y934690D03*
X851925Y951350D03*
X850686Y1006923D03*
X853449Y1007048D03*
X863334Y1009393D03*
X861047Y1018909D03*
X860887Y1023208D03*
Y1026762D03*
X863956Y1020763D03*
X863689Y1024974D03*
X863944Y1432359D03*
Y1429359D03*
X860944Y1432359D03*
X857944Y1429359D03*
X860944D03*
Y1426359D03*
X857944D03*
X863944D03*
X857944Y1432359D03*
X863944Y1435359D03*
Y1441359D03*
Y1438359D03*
X860944Y1441359D03*
X857944Y1435359D03*
X860944D03*
X857944Y1441359D03*
Y1438359D03*
X860944D03*
X850544Y1447559D03*
X853514Y1457510D03*
X850644Y1457359D03*
X870519Y60438D03*
X867659Y60513D03*
X876200Y86012D03*
X867787Y85731D03*
X865427Y88801D03*
X876200Y94374D03*
X872293Y94279D03*
X868344Y94351D03*
X871341Y86046D03*
X871713Y168665D03*
Y176665D03*
Y196665D03*
Y192665D03*
X871826Y186778D03*
X871745Y204864D03*
Y208864D03*
X867386Y219379D03*
X883118Y262687D03*
X876622Y293721D03*
X872050Y302644D03*
X873262Y300030D03*
X869924Y305368D03*
X879112Y302369D03*
X877977Y305368D03*
Y309368D03*
X869924Y313368D03*
X877977D03*
Y325368D03*
Y317368D03*
Y321368D03*
X869924D03*
Y328722D03*
X874005Y344917D03*
X870413Y342791D03*
X869924Y333722D03*
X877977Y333368D03*
Y329368D03*
X872158Y359962D03*
X868086Y373750D03*
X876736Y383125D03*
X877909Y391731D03*
X880736Y383125D03*
X882925Y391099D03*
X872736Y391754D03*
X867586Y393000D03*
Y385000D03*
X869342Y407627D03*
X868586Y398500D03*
X877253Y420380D03*
X876917Y415322D03*
X879417D03*
X881190Y411619D03*
X878690D03*
X874253Y422880D03*
Y420080D03*
X877253Y422880D03*
X881271Y426952D03*
X878771D03*
X873536Y437408D03*
X876036D03*
X881036D03*
X878536D03*
X873771Y426952D03*
X876271D03*
X870882Y458991D03*
X880910Y454634D03*
Y457434D03*
Y460234D03*
X870882Y461791D03*
X869454Y479303D03*
X869954Y487303D03*
X882954Y486256D03*
X882195Y539204D03*
X867093Y554703D03*
X866938Y549771D03*
X878382Y554942D03*
X874649Y545296D03*
X876949Y571419D03*
X867093Y586828D03*
Y574703D03*
X881476Y588202D03*
X881131Y577349D03*
X875290Y578703D03*
X876351Y605023D03*
Y608523D03*
X879135Y632552D03*
X872862Y666859D03*
X878881Y667156D03*
X876286Y690970D03*
X868919Y700894D03*
X876286Y694970D03*
Y698970D03*
X881157Y749148D03*
X874142Y748914D03*
X879875Y753612D03*
X873728Y752692D03*
X875473Y742056D03*
X878670Y742841D03*
X869325Y761259D03*
X870017Y757313D03*
X867000Y774000D03*
X870000Y780000D03*
X879887Y784719D03*
X880040Y792851D03*
X867000Y792000D03*
X876402Y797415D03*
X874925Y800746D03*
X870035Y801032D03*
X867000Y810000D03*
X879916Y808965D03*
X877407Y828017D03*
X877818Y824214D03*
X876475Y830372D03*
X871600Y898584D03*
X872628Y918042D03*
X876628Y915242D03*
X880628Y918042D03*
X876628D03*
X872126Y934766D03*
X865830Y961600D03*
X870209Y949384D03*
X865973Y978187D03*
X874066Y977928D03*
X875391Y993796D03*
X872183Y993980D03*
X878976Y994020D03*
X871069Y1023114D03*
X878927Y1022387D03*
X878783Y1018751D03*
X872845Y1018988D03*
X866906Y1018751D03*
X866887Y1023208D03*
X875887D03*
X878887Y1026762D03*
X872887D03*
X866887D03*
X869741Y1025895D03*
X873824Y1071604D03*
X871224D03*
X876424D03*
Y1074104D03*
X871224D03*
X873824D03*
X868624Y1071604D03*
Y1074104D03*
X870057Y1091604D03*
X875257D03*
Y1089104D03*
X870057D03*
X872657D03*
X880115Y1084666D03*
X867457Y1091604D03*
Y1089104D03*
X872657Y1091604D03*
X875375Y1107647D03*
X872675D03*
X870075D03*
X867475D03*
X871364Y1120636D03*
X873964D03*
X876564D03*
X879264D03*
X875376Y1110175D03*
X872676D03*
X870076D03*
X867476D03*
X871364Y1139336D03*
X868664D03*
X879264Y1130336D03*
X876564D03*
X873964D03*
X871364D03*
X870522Y1148080D03*
X868022D03*
X875321Y1207654D03*
X872600Y1300833D03*
Y1298333D03*
X872944Y1432359D03*
Y1429359D03*
Y1426359D03*
X869944Y1432359D03*
Y1429359D03*
Y1426359D03*
X866944Y1432359D03*
Y1429359D03*
Y1426359D03*
X872944Y1435359D03*
Y1441359D03*
Y1438359D03*
X869944Y1435359D03*
X866944D03*
X869944Y1441359D03*
Y1438359D03*
X866944Y1441359D03*
Y1438359D03*
X881244Y1448859D03*
Y1440859D03*
X878244Y1451605D03*
X881244Y1464859D03*
Y1453059D03*
Y1456859D03*
X875744Y1453573D03*
X881244Y1476859D03*
X883233Y147540D03*
X887005Y141247D03*
X894472Y143740D03*
X891852Y148277D03*
X893284Y233339D03*
Y236739D03*
X895064Y250186D03*
X891383Y243203D03*
X896034Y243307D03*
X885884Y255118D03*
X897004Y257480D03*
X892484Y260860D03*
X887148Y249670D03*
X896953Y272012D03*
X886496Y268968D03*
X895140Y265236D03*
X886059Y284644D03*
X885918Y289500D03*
X885989Y309368D03*
Y305368D03*
Y317368D03*
X885953Y325368D03*
X885989Y313368D03*
X885953Y321368D03*
Y329368D03*
Y333368D03*
X896592Y358369D03*
Y354369D03*
X888812Y357372D03*
X883552Y357276D03*
X896592Y374369D03*
X891251Y387484D03*
X890553Y392038D03*
X887266Y400158D03*
Y405158D03*
Y402658D03*
X896579Y404043D03*
X893779D03*
X889979Y405743D03*
X890903Y454634D03*
Y457434D03*
Y460234D03*
X891454Y486303D03*
X892931Y534093D03*
X885931D03*
X891449Y547363D03*
X893949D03*
X886549Y553963D03*
X885556Y543664D03*
X887417Y566713D03*
X891673Y600049D03*
X891933Y618143D03*
X895933Y609696D03*
X883309Y666608D03*
X892461Y666671D03*
X886304Y666650D03*
X884903Y696678D03*
X884911Y690279D03*
X886836Y715970D03*
X893241Y704656D03*
X883686Y729778D03*
X889525Y722060D03*
X882098Y741565D03*
X884976Y740891D03*
X884463Y744757D03*
X881637Y744154D03*
X883126Y766124D03*
X883413Y759855D03*
X892040Y784511D03*
X889763Y788159D03*
X898737Y792289D03*
X889516Y792851D03*
X891916Y799605D03*
X884002Y797616D03*
X887916Y800815D03*
X895916Y808965D03*
X883916D03*
X887916D03*
X895829Y800660D03*
X883916Y800815D03*
X890326Y828548D03*
X895050D03*
X889178Y905619D03*
X884628Y915242D03*
Y918042D03*
X896553D03*
X892628Y915242D03*
X888628D03*
Y918042D03*
X882763Y933472D03*
X891367Y941126D03*
X888400Y994579D03*
X894660Y994330D03*
X891343Y994378D03*
X885099Y1021685D03*
X881887Y1023208D03*
X888743Y1019931D03*
X895394Y1026985D03*
X893147Y1020025D03*
X893887Y1023208D03*
X887887D03*
X890887Y1026762D03*
X884887D03*
X882779Y1074104D03*
Y1071604D03*
X887979Y1074104D03*
X885379D03*
X890579D03*
Y1071604D03*
X885379D03*
X887979D03*
X882615Y1084666D03*
X887862Y1088067D03*
X894004Y1081231D03*
X892856Y1102760D03*
X894249Y1114103D03*
X891549D03*
X888949D03*
X886349D03*
Y1123803D03*
X888949D03*
X891549D03*
X894249D03*
X895275Y1132870D03*
X892575D03*
X895547Y1145169D03*
X894713Y1210419D03*
X898878Y1214182D03*
X899286Y1219469D03*
X892532Y1220112D03*
X897169Y1225259D03*
X886888Y1263058D03*
X889388D03*
X891888D03*
X889388Y1260558D03*
X886888D03*
X891888D03*
X886926Y1298712D03*
X889729Y1295516D03*
X891107Y1314305D03*
X887342Y1314990D03*
X889244Y1444859D03*
X892244Y1449636D03*
Y1440859D03*
X889944Y1457959D03*
X889244Y1460859D03*
X895244Y1457510D03*
X889336Y1452554D03*
X893919Y1462132D03*
X889244Y1472859D03*
Y1468859D03*
X903035Y141247D03*
X907522Y143518D03*
X906622Y152373D03*
X909772Y152562D03*
X899573Y158195D03*
X910977Y243307D03*
Y248032D03*
Y262205D03*
X898048Y269387D03*
X913057Y311046D03*
X915653Y307438D03*
X899352Y308560D03*
Y311960D03*
X909298Y302347D03*
X905898D03*
X898533Y334498D03*
X908521Y356708D03*
X908625Y359317D03*
X905483Y355262D03*
X905000Y362158D03*
X898869Y351114D03*
X906161Y367191D03*
X913288Y372752D03*
X910646Y376084D03*
X906344Y372524D03*
X911072Y386992D03*
X897736Y383125D03*
X901747Y398492D03*
Y403492D03*
Y400992D03*
X910250Y457262D03*
Y454462D03*
X907450D03*
Y457262D03*
X910250Y451662D03*
X907450D03*
X910250Y460062D03*
X907450D03*
X910236Y465272D03*
X910759Y475511D03*
X899931Y534093D03*
X899530Y530753D03*
X914296Y558143D03*
X913728Y550495D03*
X899407Y560019D03*
X908846Y560124D03*
X910789Y598726D03*
X898207Y599891D03*
X900676Y621536D03*
X904076D03*
X909508Y621616D03*
X912908D03*
X900753Y656925D03*
X912462Y683770D03*
X909265Y677795D03*
X912462Y687770D03*
X906886Y702285D03*
X902236Y689332D03*
Y694332D03*
X908699Y709387D03*
X913247Y714204D03*
X902841Y703665D03*
X910836Y721570D03*
X913858Y721289D03*
X907866Y795572D03*
X911028Y796598D03*
X909785Y810778D03*
X903916Y810809D03*
X913716Y811954D03*
X899916Y808965D03*
X902641Y800748D03*
X907884Y829866D03*
X908920Y905630D03*
X900628Y918042D03*
X912628Y915242D03*
X908628Y918042D03*
X900628Y915242D03*
X912628Y918042D03*
X904838D03*
X908628Y915242D03*
X900983Y940895D03*
X903759Y951358D03*
X909811Y962400D03*
X913005Y969605D03*
X912690Y994350D03*
X897825Y994413D03*
X909166Y994188D03*
X897717Y1019915D03*
X899887Y1023208D03*
Y1026762D03*
X908422Y1023103D03*
X908856Y1017677D03*
X902389Y1081764D03*
X908799Y1093659D03*
Y1088659D03*
X908278Y1083484D03*
X908799Y1096659D03*
Y1100659D03*
X902353Y1104333D03*
X898278Y1136426D03*
X898047Y1145169D03*
X903959Y1207823D03*
X906784Y1216607D03*
X913784Y1221057D03*
X910633Y1222799D03*
X906309Y1226647D03*
X909077Y1232724D03*
X899699Y1283872D03*
X910788Y1299456D03*
X906506Y1299188D03*
X902908Y1299828D03*
X911117Y1314130D03*
X902875Y1309301D03*
X905740Y1309264D03*
X908700Y1316300D03*
X911135Y1345560D03*
X904177Y1359955D03*
X899944Y1432359D03*
X908944Y1426359D03*
Y1429359D03*
Y1432359D03*
X911944Y1426359D03*
Y1429359D03*
Y1432359D03*
X905944Y1426359D03*
X899944D03*
X902944D03*
Y1429359D03*
X899944D03*
X902944Y1432359D03*
X905944Y1429359D03*
Y1432359D03*
X902944Y1438359D03*
X899944D03*
Y1441359D03*
X902944Y1435359D03*
X899944D03*
X908944Y1438359D03*
Y1441359D03*
X911944Y1438359D03*
Y1441359D03*
X902944D03*
X905944Y1438359D03*
Y1441359D03*
X908944Y1435359D03*
X911944D03*
X905944D03*
X919175Y116594D03*
X930118Y110784D03*
X925118D03*
X919175Y119594D03*
X924675Y124879D03*
X929697Y124663D03*
X919609Y124283D03*
X931041Y138838D03*
X918016Y161306D03*
X915267Y157370D03*
X916453Y167975D03*
X927898Y203256D03*
X925098D03*
X919577Y240945D03*
Y250394D03*
Y271654D03*
X919616Y268462D03*
X919577Y264567D03*
X923732Y304585D03*
X917882Y328216D03*
Y324816D03*
X915954Y344150D03*
X916229Y336333D03*
X919354Y344150D03*
X919629Y336333D03*
X927964Y344041D03*
X924564D03*
X923311Y349959D03*
X929943Y372600D03*
X921343Y376888D03*
X916330Y377748D03*
X929947Y376821D03*
X915072Y386992D03*
X914323Y398551D03*
Y403551D03*
Y401051D03*
X927563Y424445D03*
X924763D03*
X921963D03*
X927280Y436716D03*
X921680D03*
X924480D03*
X917541Y441280D03*
Y443780D03*
X927766Y456442D03*
X927596Y447453D03*
X921973Y469328D03*
X927401Y469059D03*
X916593Y469140D03*
X928999Y477948D03*
X920999D03*
X924999D03*
X917811Y544325D03*
X923453Y569578D03*
X923642Y561578D03*
X919080Y587640D03*
X921507Y578791D03*
X919038Y579378D03*
X923599Y581578D03*
X921217Y589216D03*
X913998Y597103D03*
X925949Y612363D03*
Y608863D03*
X922626Y633772D03*
X915800Y629700D03*
X918300D03*
X929690Y666593D03*
X920090Y666714D03*
X928353Y686342D03*
X928704Y680261D03*
X921061Y715386D03*
X926961Y723797D03*
X914202Y797460D03*
X923872Y798271D03*
X922352Y800809D03*
X917803Y811365D03*
X927916Y800909D03*
X929790Y828603D03*
X927916Y817015D03*
X925228Y816934D03*
X929181Y895029D03*
X921451Y903800D03*
X920628Y918042D03*
X916628D03*
X924628D03*
X928628D03*
X924628Y915242D03*
X920628D03*
X928628D03*
X916628D03*
X914193Y945318D03*
X928227Y951125D03*
X921364Y951251D03*
X918265Y969745D03*
X923289Y965780D03*
X926796Y966297D03*
X929741Y967006D03*
X916932Y994405D03*
X924956Y994321D03*
X924864Y1026762D03*
Y1023208D03*
X925024Y1018909D03*
X927861Y1024768D03*
X916749Y1084659D03*
X916992Y1076659D03*
X916749Y1092664D03*
X916875Y1098643D03*
X916749Y1104659D03*
X914637Y1210568D03*
Y1214838D03*
X930754Y1310564D03*
X924650Y1327819D03*
Y1324419D03*
X914033Y1345613D03*
X927193Y1361547D03*
X931159Y1379427D03*
X920360Y1387039D03*
X920255Y1383264D03*
X931199Y1371951D03*
X931159Y1390827D03*
Y1406027D03*
X914944Y1426359D03*
Y1429359D03*
Y1432359D03*
Y1438359D03*
Y1441359D03*
Y1435359D03*
X921498Y1446692D03*
X925697Y1460109D03*
X917744Y1453573D03*
X920244Y1451605D03*
X919285Y1456226D03*
X924803Y1474743D03*
X925435Y1478114D03*
X940761Y97667D03*
X945011Y95111D03*
X931144Y116594D03*
X936417Y102495D03*
X931144Y119594D03*
X934678Y125107D03*
X936151Y142862D03*
X943292Y143762D03*
X937192Y148717D03*
X945406Y180347D03*
X940406D03*
X942906D03*
X947424Y184419D03*
X944424Y186919D03*
X944760Y191977D03*
X942260D03*
X940487Y195680D03*
X942987D03*
X944424Y184419D03*
X934411Y202141D03*
X931698Y201556D03*
X934411Y207141D03*
X934477Y211491D03*
X934411Y204641D03*
X946234Y213390D03*
X942179Y215727D03*
X937438Y213817D03*
X936395Y218142D03*
X933403Y245507D03*
X936962Y249807D03*
X944248Y239844D03*
X945018Y276051D03*
X943183Y281652D03*
X930727Y302571D03*
X937000Y312284D03*
Y315684D03*
X942731Y324044D03*
X939331D03*
X940997Y331912D03*
Y335312D03*
X942700Y346363D03*
X939300D03*
X934128Y355168D03*
X934464Y358618D03*
X944238Y360828D03*
X934047Y369160D03*
X936175Y364823D03*
X931072Y386992D03*
X941872Y440942D03*
X933424Y458455D03*
X933161Y451442D03*
X933404Y463462D03*
X933412Y468942D03*
X936653Y526836D03*
X944351Y534211D03*
X948532Y541135D03*
X939992Y527726D03*
Y548726D03*
Y544726D03*
X948598Y546553D03*
X948621Y552726D03*
X931627Y557641D03*
Y569578D03*
Y581578D03*
Y577578D03*
Y573578D03*
X933725Y585936D03*
X933741Y598087D03*
Y594687D03*
X933725Y589336D03*
X944296Y611071D03*
X941859Y621311D03*
Y629311D03*
X943181Y632536D03*
X945434Y634325D03*
X941859Y625311D03*
X946128Y666522D03*
X935281Y680945D03*
X936026Y727450D03*
X933974Y719371D03*
X942676Y789286D03*
X933201Y798297D03*
X946970Y786366D03*
X944916Y808965D03*
X938357Y808856D03*
X931916Y817015D03*
X942858Y819430D03*
X945736Y819397D03*
X935124Y831382D03*
X940100Y830700D03*
X935262Y825135D03*
X932418D03*
X940716Y840074D03*
X944297Y839975D03*
X933021Y840893D03*
X933054Y843804D03*
X937200Y841000D03*
X936450Y858327D03*
X937551Y860801D03*
X932770Y878233D03*
X935765Y878317D03*
X934928Y871727D03*
X932319Y871626D03*
X938729Y874396D03*
X932300Y890200D03*
X942194Y891216D03*
X930800Y904840D03*
X941592Y900908D03*
X936628Y915242D03*
X940628D03*
X932628D03*
X936628Y918042D03*
X932628D03*
X936371Y951484D03*
X940716Y951733D03*
X946363Y951179D03*
X935255Y962725D03*
X945671Y982191D03*
X940015Y1020176D03*
X934911Y1023579D03*
X945864Y1023208D03*
X930864Y1026762D03*
X936864D03*
X942864D03*
X939864Y1023208D03*
X930864D03*
X930883Y1018751D03*
X936822Y1018988D03*
X942760Y1018751D03*
X943093Y1021769D03*
X932289Y1074182D03*
Y1071682D03*
X937489Y1074182D03*
X934889D03*
X940089D03*
Y1071682D03*
X934889D03*
X937489D03*
X944092Y1084666D03*
X931628Y1091409D03*
Y1088909D03*
X936828Y1091409D03*
X934228D03*
X939428D03*
Y1088909D03*
X934228D03*
X936828D03*
X943241Y1120636D03*
X940541D03*
X937941D03*
X935341D03*
X937941Y1130336D03*
X940541D03*
X943241D03*
X932641Y1139336D03*
X935341Y1130336D03*
Y1139336D03*
X934500Y1147708D03*
X932000D03*
X939298Y1207654D03*
X943891Y1306608D03*
X944207Y1320739D03*
X947308Y1325035D03*
X931137Y1375878D03*
X931159Y1383227D03*
X939559Y1398427D03*
X931159Y1394627D03*
Y1387027D03*
Y1398427D03*
Y1402227D03*
X939559D03*
X944235Y1406262D03*
X943725Y1430744D03*
Y1427744D03*
X934725Y1430744D03*
X940725Y1427744D03*
Y1430744D03*
X934725Y1427744D03*
X937725D03*
Y1430744D03*
X943725Y1433744D03*
Y1439744D03*
Y1436744D03*
X940725Y1433744D03*
Y1439744D03*
Y1436744D03*
X934725Y1433744D03*
X937725D03*
X934725Y1439744D03*
X937725D03*
X934725Y1436744D03*
X937725D03*
X937671Y1492139D03*
Y1488139D03*
X949221Y103411D03*
X949615Y97667D03*
X960411Y90650D03*
X960161Y95236D03*
X949380Y106561D03*
X947906Y180347D03*
X947424Y187219D03*
X950177Y215730D03*
X947040Y223885D03*
X948741Y229468D03*
X948785Y242464D03*
X951278Y250583D03*
X946482Y255940D03*
X949974Y291554D03*
X947733Y319680D03*
X950953Y317947D03*
X960376Y392807D03*
X962769Y451419D03*
X959816Y472905D03*
X955816Y473419D03*
Y464919D03*
X963816Y464419D03*
X962563Y485128D03*
X954182Y481467D03*
X958124Y492354D03*
X958736Y482165D03*
X958974Y504825D03*
X956474D03*
X953974D03*
X949823Y491982D03*
X959600Y496486D03*
X949823Y495982D03*
X957977Y500202D03*
X958915Y517401D03*
X956415D03*
X953915D03*
X959466Y522569D03*
Y525369D03*
X958081Y531882D03*
X955581D03*
X961166Y529169D03*
X952531Y531948D03*
X960581Y531882D03*
X948905Y534909D03*
X958016Y555194D03*
X960816D03*
X958016Y563194D03*
X960816D03*
Y571194D03*
X958016D03*
X959573Y581222D03*
X962373D03*
X959573Y591215D03*
X962373D03*
X962545Y607762D03*
X959745D03*
Y610562D03*
X962545D03*
X950479Y622285D03*
X954535Y610548D03*
X950667Y616905D03*
X963365Y628078D03*
X961352Y633736D03*
X950865Y633724D03*
X950748Y627713D03*
X956345Y633716D03*
X949137Y666660D03*
X954526Y666671D03*
X947556Y699550D03*
X956023Y706907D03*
X951151Y730111D03*
X963869Y725057D03*
X955950Y734178D03*
X957763Y725336D03*
X959950Y734178D03*
X957579Y744168D03*
X953837Y763025D03*
X950699Y779711D03*
X956017Y770300D03*
X957500Y780800D03*
X955076Y784861D03*
X950475Y789361D03*
X955225Y788984D03*
X949609Y796051D03*
X957487Y798553D03*
X951461Y812223D03*
X951791Y808121D03*
X957379Y826586D03*
X954760Y826734D03*
X951708Y818894D03*
X955712Y833988D03*
X956239Y829577D03*
X960100Y846665D03*
X954700Y837700D03*
X961175Y838525D03*
X955343Y866850D03*
X955850Y862902D03*
X957900Y856300D03*
X950300Y877800D03*
X953240Y876834D03*
X954567Y927654D03*
X964280Y927777D03*
X958567Y927654D03*
X947029Y915242D03*
X959545Y918306D03*
X951863Y936168D03*
X957235Y936398D03*
X962329Y936229D03*
X957671Y977921D03*
X949671D03*
X961671Y991564D03*
X953671D03*
X949671D03*
X953671Y982191D03*
X954937Y1021998D03*
X948864Y1026762D03*
X954864D03*
X951864Y1023208D03*
X957864D03*
X957678Y1018555D03*
X961208Y1018592D03*
X960636Y1021917D03*
X959371Y1026985D03*
X948975Y1021325D03*
X951956Y1071604D03*
X949356D03*
X954556D03*
Y1074104D03*
X949356D03*
X951956D03*
X946756Y1071604D03*
Y1074104D03*
X946592Y1084666D03*
X957981Y1081231D03*
X951839Y1088067D03*
X956833Y1102760D03*
X950326Y1114103D03*
Y1123803D03*
X952926D03*
X955526D03*
Y1114103D03*
X958226D03*
X952926D03*
X958226Y1123803D03*
X956552Y1132870D03*
X959252D03*
X962255Y1136426D03*
X962024Y1145169D03*
X959524D03*
X958690Y1210419D03*
X963263Y1219469D03*
X962855Y1214182D03*
X956509Y1220112D03*
X961146Y1225259D03*
X950865Y1263058D03*
X953365D03*
X955865D03*
X953365Y1260558D03*
X950865D03*
X955865D03*
X948259Y1295965D03*
X948832Y1371654D03*
X951832D03*
X952561Y1383465D03*
X952417Y1379528D03*
X949469D03*
X949385Y1375591D03*
X952385D03*
X952514Y1391339D03*
X952395Y1395276D03*
X952716Y1387402D03*
X952180Y1407087D03*
X950239Y1409555D03*
X948235Y1406262D03*
X946725Y1427744D03*
Y1430744D03*
X949725D03*
Y1427744D03*
X960883Y1427997D03*
Y1430997D03*
X946725Y1433744D03*
X949725D03*
X946725Y1439744D03*
X949725D03*
X946725Y1436744D03*
X949725D03*
X960883Y1433997D03*
Y1436997D03*
Y1439997D03*
X952695Y1444139D03*
X979002Y92874D03*
X965723Y90615D03*
X970094Y95236D03*
X970044Y99961D03*
X978051Y162368D03*
X968906Y207978D03*
Y212978D03*
Y215478D03*
Y210478D03*
X970865Y264068D03*
X973365D03*
X972160Y258880D03*
X977150Y331972D03*
Y338972D03*
X975631Y343112D03*
Y346612D03*
X971721Y407762D03*
X968348Y402369D03*
X971826Y430187D03*
X966694Y427599D03*
X968462Y429368D03*
X970840Y457339D03*
X968340D03*
X962816Y442919D03*
X972030Y446071D03*
X979910Y445603D03*
X970840Y459839D03*
Y462339D03*
X968340D03*
Y459839D03*
X963816Y472905D03*
X976397Y473045D03*
X972397Y465004D03*
X977327Y462371D03*
X965412Y485138D03*
X969297Y478625D03*
Y475825D03*
X970997Y482425D03*
X970412Y485138D03*
X967912D03*
X976873Y491214D03*
Y493714D03*
X970745Y539731D03*
X967042Y537658D03*
X970745Y542231D03*
X978303Y541895D03*
X975803D03*
X967042Y540458D03*
X975503Y544895D03*
X978303D03*
X978581Y582747D03*
X965173Y581222D03*
X978032Y590801D03*
X965173Y591215D03*
X977857Y597130D03*
X976027Y620653D03*
Y617853D03*
X968145Y610562D03*
X965345Y607762D03*
Y610562D03*
X968145Y607762D03*
X977857Y605443D03*
X973857D03*
X972354Y627908D03*
X968365Y633473D03*
X978865Y642184D03*
X966797Y667653D03*
X970197D03*
X965774Y706907D03*
X973712Y722064D03*
X968589Y722434D03*
X970839Y729923D03*
X965042Y722234D03*
X971081Y722637D03*
X978352Y730766D03*
X963950Y734178D03*
X973450Y747280D03*
X965983Y763567D03*
X966127Y776382D03*
X968094Y799792D03*
X976186Y789819D03*
X967562Y802982D03*
X978978Y817618D03*
X978214Y821224D03*
X967337Y828901D03*
X970040Y842903D03*
X969309Y839334D03*
X974437Y849140D03*
X973510Y834991D03*
X967842Y864801D03*
X970299Y853773D03*
X978880Y869552D03*
X967510Y868971D03*
X966813Y904556D03*
X973988Y910038D03*
X968507Y937615D03*
X971443Y938828D03*
X965671Y991564D03*
Y982191D03*
X963864Y1026762D03*
Y1023208D03*
X966366Y1081764D03*
X972776Y1093659D03*
X972255Y1083484D03*
X972776Y1088659D03*
Y1096659D03*
X966330Y1104333D03*
X972776Y1100659D03*
X967936Y1207823D03*
X978614Y1210568D03*
X970761Y1216607D03*
X978614Y1214838D03*
X978169Y1221268D03*
X974985Y1290950D03*
X979996Y1386100D03*
X963883Y1430997D03*
Y1427997D03*
X966883Y1430997D03*
Y1427997D03*
X969883D03*
Y1430997D03*
X975883Y1427997D03*
Y1430997D03*
X972883D03*
Y1427997D03*
X963883Y1433997D03*
X966883D03*
X969883D03*
X963883Y1436997D03*
Y1439997D03*
X966883Y1436997D03*
Y1439997D03*
X969883Y1436997D03*
Y1439997D03*
X975883Y1433997D03*
X972883D03*
X975883Y1436997D03*
X972883D03*
X975883Y1439997D03*
X972883D03*
X977547Y1546081D03*
X974547D03*
X971547D03*
X978958Y85193D03*
Y82593D03*
Y77393D03*
Y74793D03*
Y79993D03*
X987283Y98551D03*
X990178Y114623D03*
Y111223D03*
X990833Y103783D03*
X981029Y104249D03*
Y107649D03*
X990178Y128796D03*
Y125396D03*
X985595Y147540D03*
X989367Y141247D03*
X996834Y143740D03*
X994214Y148277D03*
X980651Y162368D03*
X987751Y162793D03*
Y165393D03*
Y167993D03*
Y170493D03*
X995256Y172190D03*
X994675Y177616D03*
X989959Y181366D03*
X986748Y181426D03*
X992754Y181009D03*
X986956Y184221D03*
X989573Y184012D03*
X994695Y213132D03*
X979362Y208213D03*
Y210713D03*
Y213213D03*
X986234Y208695D03*
X983434D03*
X985934Y211695D03*
X990992Y213859D03*
Y211359D03*
X983434Y211695D03*
X979362Y215713D03*
X994695Y215632D03*
X994939Y256303D03*
X989611Y265701D03*
X994698Y265896D03*
X986429Y270026D03*
X983929D03*
X981129D03*
X983929Y267526D03*
X986429D03*
X981129D03*
X991246Y281716D03*
X997187Y281982D03*
X987517Y314092D03*
X993552Y318175D03*
X990420Y340454D03*
Y337954D03*
X989630Y343862D03*
X983717Y341665D03*
X983956Y346652D03*
X993026Y353813D03*
X981719Y352217D03*
X988631Y349496D03*
X980045Y366559D03*
X986373Y370467D03*
X991392Y409230D03*
X985303Y464652D03*
Y462152D03*
Y459652D03*
X987803Y464652D03*
Y462152D03*
Y459652D03*
X981843Y464818D03*
X992206Y491133D03*
Y498633D03*
X988134Y495151D03*
X985634D03*
X980576Y492987D03*
X985334Y498151D03*
X980576Y495487D03*
X988134Y498151D03*
X992206Y493633D03*
Y496133D03*
X982375Y537877D03*
X992306Y555897D03*
Y553297D03*
X989888Y548366D03*
X987388D03*
X982388D03*
X984888D03*
X982375Y542877D03*
Y545377D03*
Y540377D03*
X992306Y561097D03*
Y563697D03*
Y566797D03*
Y558497D03*
X986301Y570686D03*
X989096Y570478D03*
X989513Y576484D03*
X989156Y573689D03*
X986510Y573303D03*
X992906Y578405D03*
X981857Y597232D03*
X991907Y596782D03*
X986688Y596089D03*
X983843Y619513D03*
Y616713D03*
Y613913D03*
X993857Y605443D03*
X981857Y605637D03*
X980703Y625013D03*
X986600Y717641D03*
X987461Y745796D03*
X981876Y745179D03*
X988371Y764143D03*
X983786Y765647D03*
X984357Y777555D03*
X997051Y778833D03*
X990699Y778630D03*
X987990Y774005D03*
X987394Y787490D03*
X987501Y812573D03*
X985921Y805135D03*
X994051Y810871D03*
X996385Y816141D03*
X979203Y829159D03*
X994094Y829000D03*
X982300Y821200D03*
X987702Y829159D03*
X989700Y846500D03*
X987202Y846395D03*
X987319Y843589D03*
X979203Y833159D03*
X989800Y843900D03*
X987200Y848940D03*
X987703Y837159D03*
X990457Y852043D03*
X983269Y853883D03*
X981700Y856300D03*
X979891Y876589D03*
X992441Y870398D03*
X988054Y888283D03*
X990300Y897500D03*
X979592Y902849D03*
X982783Y909995D03*
X979498Y907500D03*
X989311Y920364D03*
X983227Y968565D03*
X988240Y1020015D03*
Y1016923D03*
Y1023968D03*
X984909Y1081071D03*
X983751Y1078675D03*
X980969Y1076659D03*
X980726Y1084659D03*
X980852Y1098643D03*
X980726Y1104659D03*
Y1092664D03*
X986645Y1108465D03*
X989513Y1097683D03*
X995009Y1131223D03*
X991763Y1140378D03*
Y1128378D03*
Y1134378D03*
X984558Y1140774D03*
X988112Y1137774D03*
X984558Y1128774D03*
Y1134774D03*
X987804Y1131619D03*
X984817Y1303297D03*
X979001Y1288925D03*
X990613Y1324248D03*
Y1327048D03*
X993413Y1324248D03*
Y1327048D03*
X990501Y1320756D03*
X988784Y1361974D03*
X980139Y1381496D03*
X980166Y1373622D03*
X980203Y1377559D03*
X980047Y1397245D03*
X985448Y1398271D03*
X980092Y1389370D03*
X980139Y1393308D03*
X984136Y1401636D03*
X987136D03*
X986949Y1430997D03*
Y1427997D03*
X983949D03*
X989949Y1430997D03*
Y1427997D03*
X983949Y1430997D03*
X992949Y1427997D03*
Y1430997D03*
X986949Y1433997D03*
X983949D03*
X989949D03*
X992949D03*
X986949Y1436997D03*
X983949D03*
X986949Y1439997D03*
X983949D03*
X989949Y1436997D03*
Y1439997D03*
X992949Y1436997D03*
Y1439997D03*
X978934Y1444392D03*
X978987Y1489832D03*
X982241Y1489637D03*
X986773Y1546081D03*
X983773D03*
X980773D03*
X1011284Y68581D03*
X1011297Y80581D03*
X1003379Y72615D03*
Y76587D03*
X1004818Y100625D03*
X997837Y97475D03*
X1013480Y103621D03*
X997768Y106186D03*
X1009191Y112083D03*
X1000580Y121735D03*
Y118335D03*
Y132509D03*
Y135909D03*
X1005397Y141247D03*
X1009884Y143518D03*
X1008984Y152373D03*
X1012936Y178560D03*
X997929Y168697D03*
X1012826Y183834D03*
X1012999Y172665D03*
X999017Y191941D03*
X1003029Y192300D03*
X1012346Y190185D03*
X1007071Y192490D03*
X1013116Y200864D03*
X1003526Y206767D03*
X1006026D03*
X1001026D03*
X1010291Y199582D03*
X1013139Y207037D03*
X1013205Y212455D03*
X1002271Y228221D03*
Y231021D03*
X1010506Y221642D03*
X1003656Y221708D03*
X1006156D03*
X1000571Y224421D03*
X1001156Y221708D03*
X1002822Y236189D03*
X1005322D03*
X1007822D03*
X1002763Y248765D03*
X1005263D03*
X1007763D03*
X999714Y266114D03*
X1008260Y268195D03*
X1005460D03*
X1002960D03*
X1008260Y270695D03*
X1002960D03*
X1005460D03*
X1000698Y300276D03*
X1002580Y309619D03*
X1010499Y309062D03*
X1003181Y323057D03*
X1001105Y318006D03*
X1009770Y344486D03*
X997020Y345354D03*
X1003076Y332496D03*
X1000420Y353954D03*
X996024Y352132D03*
X1001825Y581659D03*
X998332Y578986D03*
X997857Y596729D03*
X995913Y619758D03*
Y616958D03*
Y614158D03*
X1001857Y605443D03*
X1003900Y628700D03*
X1001605Y627605D03*
X1005800Y637600D03*
X1002883Y622521D03*
X1001676Y678015D03*
X1011185Y724519D03*
X1009562Y722438D03*
X1003990Y765899D03*
X1007990D03*
X1002751Y757169D03*
X999990Y764566D03*
X1013151Y756726D03*
X1012695Y776728D03*
X999990Y774671D03*
X1013319Y785929D03*
X1007027Y792973D03*
X998376Y810970D03*
X1006054Y810969D03*
X1010699Y803454D03*
X1002699Y819475D03*
X1011144Y844340D03*
X1010977Y841737D03*
X1012703Y837659D03*
X1001187Y850084D03*
X1004577Y853679D03*
X1004713Y871389D03*
X998313Y888295D03*
X1005413Y905295D03*
X1004953Y923995D03*
X1008935Y924007D03*
X1004994Y955372D03*
X1007919Y948822D03*
X1011019D03*
X1004719D03*
X1012219Y954222D03*
X1006222Y980337D03*
X1009564Y988874D03*
X999879Y998507D03*
X1001805Y1007522D03*
X1008571Y1006648D03*
X1008759Y1023900D03*
X1002180Y1013678D03*
X1002652Y1023731D03*
X1005938Y1018307D03*
X995317Y1137378D03*
X996213Y1324248D03*
Y1327048D03*
X1009333Y1346693D03*
Y1343293D03*
X998600Y1369200D03*
X1008387Y1380797D03*
X998600Y1373400D03*
X997401Y1381200D03*
X999283Y1377400D03*
X1007850Y1368835D03*
X998643Y1398271D03*
X1008138Y1407186D03*
Y1409986D03*
X1005338Y1407186D03*
Y1409986D03*
X1008138Y1415586D03*
Y1412786D03*
X1005338Y1415586D03*
Y1412786D03*
X1008138Y1418386D03*
X1005338D03*
X998949Y1427997D03*
Y1430997D03*
X995949D03*
Y1427997D03*
X1009981Y1431097D03*
Y1428097D03*
X1006981D03*
Y1431097D03*
X998949Y1433997D03*
X995949D03*
X998949Y1436997D03*
X995949D03*
X998949Y1439997D03*
X995949D03*
X1009981Y1434097D03*
X1006981D03*
X1009981Y1437097D03*
X1006981D03*
X1009981Y1440097D03*
X1006981D03*
X1002194Y1444392D03*
X1015059Y55513D03*
X1020519Y60438D03*
X1017659Y60513D03*
X1026200Y86012D03*
X1017787Y85731D03*
X1026200Y94374D03*
X1015427Y88801D03*
X1022293Y94279D03*
X1018344Y94351D03*
X1021341Y86046D03*
X1021537Y116594D03*
X1027480Y110784D03*
X1021537Y119594D03*
X1021971Y124283D03*
X1027037Y124879D03*
X1020378Y161306D03*
X1012134Y152562D03*
X1017629Y157370D03*
X1021713Y176665D03*
Y168665D03*
X1013812Y186629D03*
X1021713Y196665D03*
X1021826Y186778D03*
X1021713Y192665D03*
X1021745Y204864D03*
Y208864D03*
X1026794Y218085D03*
X1017386Y219379D03*
X1018014Y228631D03*
X1023502Y248371D03*
X1014420Y265897D03*
X1011920D03*
X1027216Y289440D03*
X1022604Y290262D03*
X1016635Y300276D03*
X1012635D03*
X1025749D03*
X1020635D03*
X1022435Y312865D03*
X1021848Y310396D03*
X1020406Y350772D03*
X1012188Y443421D03*
X1015659Y679654D03*
Y683054D03*
X1021885Y698974D03*
X1022937Y691421D03*
X1014641Y724436D03*
X1012851Y722417D03*
X1026916Y719769D03*
X1018015Y751565D03*
X1013486Y750773D03*
X1024684Y756485D03*
X1017664Y779101D03*
X1014064Y793660D03*
X1018071Y798490D03*
X1013821Y813520D03*
X1014781Y810319D03*
X1017955Y812097D03*
X1021895Y818974D03*
X1020703Y837659D03*
X1013918Y851306D03*
X1017800Y867065D03*
X1016973Y877196D03*
X1016574Y874537D03*
X1016798Y890299D03*
X1021408Y895008D03*
X1024913Y884000D03*
X1012842Y910685D03*
X1022346Y917669D03*
X1029570Y917718D03*
X1018419Y917575D03*
X1014719Y938322D03*
X1027319D03*
X1027719Y958822D03*
X1014009Y980356D03*
X1018009D03*
X1014009Y988813D03*
X1018009D03*
X1021924Y980456D03*
X1026009Y988813D03*
X1022009D03*
X1017998Y1009655D03*
X1015198D03*
X1024570Y1024003D03*
X1011782Y1016591D03*
X1022143Y1030672D03*
X1019143D03*
X1016143D03*
X1025143D03*
X1023144Y1109564D03*
X1017297D03*
X1023144Y1122164D03*
X1017297D03*
X1023144Y1134764D03*
X1017297D03*
X1023144Y1147364D03*
X1017297D03*
X1023144Y1159964D03*
X1017297D03*
Y1172564D03*
X1023162Y1174445D03*
X1023139Y1184856D03*
X1017297Y1185164D03*
X1026221Y1214372D03*
X1021976Y1218169D03*
X1023358Y1363921D03*
X1013991Y1360842D03*
X1019391Y1377061D03*
X1012981Y1431097D03*
Y1428097D03*
X1015981D03*
Y1431097D03*
X1021981Y1428097D03*
Y1431097D03*
X1018981D03*
Y1428097D03*
X1012981Y1434097D03*
X1015981D03*
X1012981Y1437097D03*
Y1440097D03*
X1015981Y1437097D03*
Y1440097D03*
X1021981Y1434097D03*
X1018981D03*
X1021981Y1437097D03*
X1018981D03*
X1021981Y1440097D03*
X1018981D03*
X1025615Y1444492D03*
X1020023Y1489637D03*
X1016769Y1489832D03*
X1043123Y97667D03*
X1033506Y116594D03*
X1038779Y102495D03*
X1032480Y110784D03*
X1033506Y119594D03*
X1037040Y125107D03*
X1032059Y124663D03*
X1038513Y142862D03*
X1045654Y143762D03*
X1039554Y148717D03*
X1033403Y138838D03*
X1042102Y195176D03*
X1042183Y210509D03*
X1029594Y218085D03*
X1036107Y221970D03*
X1036173Y226320D03*
X1036107Y219470D03*
Y216970D03*
X1033394Y216385D03*
X1043875Y230556D03*
X1039134Y228646D03*
X1042860Y242078D03*
X1038091Y232971D03*
X1034741Y244571D03*
X1032121Y249108D03*
X1042084Y256394D03*
X1037290Y296293D03*
X1033890D03*
X1045650Y300093D03*
X1029639Y300141D03*
X1041783Y321114D03*
X1030220Y313554D03*
X1042948Y333696D03*
X1043106Y340230D03*
X1031259Y350427D03*
X1029885Y711762D03*
X1033200Y731700D03*
X1035619Y755809D03*
X1038344Y756476D03*
X1043016Y782161D03*
X1038678Y776750D03*
X1039251Y812340D03*
X1042414Y801443D03*
X1043425Y830800D03*
X1043626Y836563D03*
X1041100Y838500D03*
X1037527Y836486D03*
X1031813Y850273D03*
X1046045Y841217D03*
X1040822Y841339D03*
X1044390Y861210D03*
X1035185Y862793D03*
X1037685Y862789D03*
X1038363Y875288D03*
X1037709Y886209D03*
X1038010Y902565D03*
X1033019Y933022D03*
Y935822D03*
X1030819Y938422D03*
X1033370Y953994D03*
X1038009Y988813D03*
X1030009D03*
X1042009D03*
X1034009D03*
X1028943Y1016827D03*
X1034790D03*
X1028943Y1029427D03*
X1034790D03*
X1039499Y1098758D03*
X1039053Y1105091D03*
X1044553D03*
X1039098Y1102091D03*
X1039053Y1117691D03*
X1044553D03*
X1039098Y1114691D03*
Y1127291D03*
X1039053Y1130291D03*
X1044553D03*
Y1142891D03*
X1039098Y1139891D03*
X1039053Y1142891D03*
Y1155491D03*
X1044553D03*
X1039098Y1152491D03*
X1044553Y1168091D03*
X1039053D03*
X1039098Y1165091D03*
X1044553Y1180691D03*
X1039053D03*
X1039098Y1177691D03*
X1032831Y1207950D03*
X1029797Y1220921D03*
X1040606Y1230407D03*
X1043588Y1227300D03*
X1032867Y1431213D03*
Y1428213D03*
X1029867D03*
X1035867Y1431213D03*
Y1428213D03*
X1029867Y1431213D03*
X1038867Y1428213D03*
Y1431213D03*
X1041867D03*
Y1428213D03*
X1032867Y1434213D03*
X1029867D03*
X1035867D03*
X1038867D03*
X1032867Y1437213D03*
X1029867D03*
X1032867Y1440213D03*
X1029867D03*
X1035867Y1437213D03*
Y1440213D03*
X1038867Y1437213D03*
Y1440213D03*
X1041867Y1434213D03*
Y1437213D03*
Y1440213D03*
X1051583Y103411D03*
X1051977Y97667D03*
X1047373Y95111D03*
X1051742Y106561D03*
X1047102Y195176D03*
X1046120Y199248D03*
X1044602Y195176D03*
X1049120Y199248D03*
X1049602Y195176D03*
X1046120Y201748D03*
X1049120Y202048D03*
X1044683Y210509D03*
X1046456Y206806D03*
X1043956D03*
X1052720Y230117D03*
X1048130Y227824D03*
X1048736Y238714D03*
X1048217Y246874D03*
X1050437Y244297D03*
X1045364Y279895D03*
X1051796Y279965D03*
X1050164Y302748D03*
X1050076Y305512D03*
X1061387Y343509D03*
X1060679Y356151D03*
X1054863Y401513D03*
Y398113D03*
X1052463Y412287D03*
Y415687D03*
Y426460D03*
Y440633D03*
Y429860D03*
Y444033D03*
X1059549Y458711D03*
X1052463Y469387D03*
Y472787D03*
Y486960D03*
Y483560D03*
Y513521D03*
Y516921D03*
Y531094D03*
Y527694D03*
X1055885Y554555D03*
X1046068Y792742D03*
X1046930Y796557D03*
X1048314Y833102D03*
X1053392Y832788D03*
X1051550Y823146D03*
X1055700Y840900D03*
X1053913Y837718D03*
X1050358Y837793D03*
X1052500Y841200D03*
X1049087Y856033D03*
X1053909Y855472D03*
X1045300Y872352D03*
X1054900Y879321D03*
X1058155Y887635D03*
X1050295Y891100D03*
X1054009Y988813D03*
X1046009D03*
X1050009D03*
X1058009D03*
X1056199Y1012354D03*
X1050744Y1009354D03*
X1056199Y1024954D03*
X1050699D03*
Y1012354D03*
X1050744Y1021954D03*
X1046485Y1034538D03*
X1057212Y1040356D03*
X1049930Y1221407D03*
X1050605Y1224472D03*
X1049770Y1229402D03*
X1049720Y1234921D03*
X1052660Y1293257D03*
X1050002Y1293283D03*
X1049204Y1337377D03*
X1049670Y1347462D03*
X1046075Y1350650D03*
X1049493Y1350694D03*
X1044867Y1428213D03*
Y1431213D03*
Y1434213D03*
Y1437213D03*
Y1440213D03*
X1048403Y1444608D03*
X1062773Y90650D03*
X1068085Y90615D03*
X1072456Y95236D03*
X1072406Y99961D03*
X1062523Y95236D03*
X1071268Y207978D03*
Y212978D03*
Y215478D03*
Y210478D03*
X1074597Y264180D03*
X1074522Y258880D03*
X1076571Y310574D03*
X1060679Y368276D03*
X1062865Y391001D03*
X1062234Y378600D03*
Y382600D03*
X1062865Y408574D03*
Y405174D03*
Y394401D03*
Y422747D03*
Y419347D03*
Y436921D03*
Y433521D03*
X1062349Y458711D03*
X1064876Y453682D03*
X1063113Y455921D03*
X1061693Y463600D03*
X1062865Y476499D03*
Y479899D03*
Y490673D03*
Y494073D03*
Y520633D03*
Y524033D03*
Y534806D03*
Y538206D03*
X1062098Y603600D03*
X1061342Y610269D03*
X1061496Y612786D03*
X1062098Y619600D03*
X1063642Y634190D03*
X1062098Y623600D03*
X1066931Y645389D03*
X1060698Y931619D03*
X1069685Y933391D03*
X1066878Y931909D03*
X1070009Y988813D03*
X1069607Y980131D03*
X1066009Y980330D03*
X1062009Y988813D03*
X1065823Y988773D03*
X1074009Y988813D03*
X1070009Y997860D03*
X1073525Y1012428D03*
X1076110Y1029535D03*
X1065079Y1036920D03*
X1076577Y1041332D03*
X1074232Y1055836D03*
X1067866Y1051037D03*
X1060768Y1053457D03*
X1074650Y1070006D03*
X1069642Y1445541D03*
X1068861Y1451311D03*
X1081320Y85193D03*
Y82593D03*
Y79993D03*
Y77393D03*
Y74793D03*
X1089645Y98551D03*
X1081364Y92874D03*
X1092540Y111223D03*
Y114623D03*
X1083391Y104249D03*
Y107649D03*
X1092540Y128796D03*
Y125396D03*
X1087957Y147540D03*
X1091729Y141247D03*
X1083013Y162368D03*
X1090113Y165393D03*
Y162793D03*
X1080413Y162368D03*
X1090113Y170493D03*
Y167993D03*
X1092321Y181366D03*
X1089110Y181426D03*
X1091935Y184012D03*
X1089318Y184221D03*
X1081724Y208213D03*
X1085796Y208695D03*
Y211695D03*
X1081724Y210713D03*
Y213213D03*
X1088596Y208695D03*
X1088296Y211695D03*
X1081724Y215713D03*
X1077097Y264180D03*
X1091973Y265701D03*
X1083491Y267526D03*
X1088791D03*
X1086291D03*
X1083491Y270026D03*
X1086291D03*
X1088791D03*
X1093608Y281716D03*
X1080351Y328256D03*
X1079748Y322743D03*
Y319343D03*
X1080351Y331656D03*
X1082297Y340770D03*
X1092554Y340318D03*
X1085615Y339815D03*
X1092561Y353374D03*
X1082787Y348501D03*
X1091031Y374810D03*
X1089788Y550907D03*
X1087288D03*
X1089788Y553407D03*
X1087288D03*
X1089096Y541863D03*
Y545263D03*
X1091558Y566929D03*
X1091272Y569426D03*
X1088949Y568475D03*
X1089206Y570962D03*
X1086859Y569928D03*
X1085512Y572070D03*
X1078920Y856700D03*
X1090375Y899047D03*
X1076800Y1012900D03*
X1078755Y1031518D03*
X1079178Y1037884D03*
X1076868Y1047293D03*
X1079910Y1045264D03*
X1079822Y1151870D03*
X1083562Y1155610D03*
X1079822Y1159350D03*
X1083283Y1526583D03*
X1084000Y1529600D03*
X1091529Y1528718D03*
X1091525Y1546300D03*
X1090876Y1554183D03*
X1091569Y1561300D03*
X1092527Y1579422D03*
X1086469Y1588435D03*
X1090469D03*
X1083900Y1593206D03*
X1082176Y1600598D03*
X1090904Y1599047D03*
X1088021Y1606949D03*
X1093778Y1599574D03*
X1086904Y1599004D03*
X1090093Y1628297D03*
X1085474Y1629028D03*
X1089474Y1638213D03*
X1105741Y76587D03*
Y72615D03*
X1100199Y97475D03*
X1107180Y100625D03*
X1100130Y106186D03*
X1093195Y103783D03*
X1102942Y118335D03*
Y132509D03*
Y121735D03*
Y135909D03*
X1107759Y141247D03*
X1099196Y143740D03*
X1096576Y148277D03*
X1095116Y181009D03*
X1100291Y168697D03*
X1097618Y172190D03*
X1109903Y171523D03*
X1097037Y177616D03*
X1101379Y191941D03*
X1109433Y192490D03*
X1105888Y206767D03*
X1108388D03*
X1103388D03*
X1093354Y213859D03*
Y211359D03*
X1097057Y213132D03*
X1104633Y228221D03*
X1106018Y221708D03*
X1108518D03*
X1102933Y224421D03*
X1103518Y221708D03*
X1104633Y231021D03*
X1097057Y215632D03*
X1105184Y236189D03*
X1107684D03*
X1105125Y248765D03*
X1107625D03*
X1097301Y256303D03*
X1102076Y266114D03*
X1097060Y265896D03*
X1107822Y268195D03*
X1105322D03*
Y270695D03*
X1107822D03*
X1099549Y281982D03*
X1093478Y310305D03*
X1108779Y327705D03*
X1103432Y340544D03*
X1097976Y340477D03*
X1105012Y353504D03*
X1098845Y353404D03*
X1093841Y371335D03*
X1099501Y545528D03*
X1108236Y577716D03*
X1105298Y610400D03*
X1108045Y668153D03*
X1092769Y936975D03*
X1095080Y1513398D03*
X1096780Y1526700D03*
X1101402Y1531702D03*
X1095250Y1531600D03*
X1098617Y1546183D03*
X1096780Y1535400D03*
X1100876Y1554183D03*
X1099371Y1561153D03*
X1100476Y1579318D03*
X1102904Y1566668D03*
X1093682Y1582433D03*
X1098498Y1590435D03*
X1104233Y1587983D03*
X1100233Y1588000D03*
X1107620Y1603602D03*
X1098904Y1602138D03*
X1101946Y1614709D03*
X1096941Y1627905D03*
X1105474Y1629450D03*
X1101474Y1637820D03*
X1093474Y1638213D03*
X1105474Y1638426D03*
X1097474Y1637753D03*
X1114781Y58013D03*
X1113646Y68581D03*
X1120021Y60513D03*
X1122881Y60438D03*
X1113659Y80581D03*
X1120149Y85731D03*
X1117789Y88801D03*
X1123703Y86046D03*
X1120706Y94351D03*
X1124655Y94279D03*
X1115842Y103621D03*
X1123899Y116594D03*
X1111553Y112083D03*
X1123899Y119594D03*
X1124333Y124283D03*
X1112246Y143518D03*
X1111346Y152373D03*
X1122740Y161306D03*
X1114496Y152562D03*
X1119991Y157370D03*
X1124075Y168665D03*
Y176665D03*
X1115188Y183834D03*
X1115298Y178560D03*
X1115361Y172665D03*
X1116174Y186629D03*
X1124075Y192665D03*
Y196665D03*
X1115478Y200864D03*
X1114708Y190185D03*
X1124188Y186778D03*
X1124107Y204864D03*
X1115501Y207037D03*
X1115567Y212455D03*
X1124107Y208864D03*
X1112868Y221642D03*
X1119748Y219379D03*
X1120376Y228631D03*
X1110184Y236189D03*
X1110125Y248765D03*
X1116782Y265897D03*
X1114282D03*
X1110622Y268195D03*
Y270695D03*
X1115000Y329000D03*
Y334000D03*
Y339000D03*
X1118848Y382109D03*
X1118847Y551683D03*
Y561420D03*
Y558917D03*
X1122705Y588515D03*
X1114668Y577937D03*
X1117673Y606929D03*
X1122673Y595500D03*
X1122173Y604567D03*
X1122705Y591015D03*
X1123331Y610072D03*
X1123267Y616317D03*
X1117633Y618400D03*
X1117914Y612592D03*
X1115151Y650119D03*
X1115320Y646449D03*
X1115054Y662981D03*
X1116296Y691851D03*
X1111785Y686971D03*
X1118105Y707592D03*
X1128562Y86012D03*
Y94374D03*
X1135868Y116594D03*
X1141141Y102495D03*
X1129842Y110784D03*
X1134842D03*
X1135868Y119594D03*
X1139402Y125107D03*
X1129399Y124879D03*
X1134421Y124663D03*
X1140875Y142862D03*
X1141916Y148717D03*
X1135765Y138838D03*
X1129156Y218085D03*
X1131956D03*
X1138469Y221970D03*
X1138535Y226320D03*
X1138469Y219470D03*
Y216970D03*
X1135756Y216385D03*
X1141496Y228646D03*
X1140453Y232971D03*
X1137103Y244571D03*
X1134483Y249108D03*
X1125864Y248371D03*
X1137830Y336230D03*
X1135548Y455804D03*
X1134629Y465551D03*
X1126622Y506256D03*
X1139673Y530000D03*
X1139173Y540500D03*
X1138373Y549800D03*
X1138173Y547075D03*
X1137673Y568000D03*
X1138213Y558800D03*
X1138277Y562800D03*
X1129471Y732571D03*
X1153945Y103411D03*
X1145485Y97667D03*
X1154339D03*
X1149735Y95111D03*
X1154104Y106561D03*
X1148016Y143762D03*
X1149464Y195176D03*
X1148482Y199248D03*
X1151482D03*
X1144464Y195176D03*
X1146964D03*
X1151964D03*
X1151482Y202048D03*
X1146318Y206806D03*
X1144545Y210509D03*
X1147045D03*
X1148818Y206806D03*
X1148482Y201748D03*
X1146237Y230556D03*
X1155082Y230117D03*
X1150492Y227824D03*
X1151098Y238714D03*
X1145222Y242078D03*
X1150579Y246874D03*
X1152799Y244297D03*
X1147590Y253198D03*
X1145587Y339148D03*
X1142440Y396718D03*
X1157451Y618288D03*
X1156275Y656321D03*
X1155146Y699491D03*
X1152512Y728543D03*
X1148962Y747253D03*
X1152485Y764552D03*
X1147468Y766093D03*
X1154652Y791056D03*
X1145910Y803642D03*
X1153485Y813142D03*
X1154985Y802897D03*
X1153229Y848581D03*
X1170447Y90615D03*
X1165135Y90650D03*
X1174768Y99961D03*
X1164885Y95236D03*
X1173630Y207978D03*
Y210478D03*
Y212978D03*
Y215478D03*
X1173559Y304948D03*
X1171445Y422088D03*
X1166868Y442956D03*
X1168685Y438323D03*
X1168398Y456309D03*
X1168851Y445873D03*
X1163298Y465874D03*
X1159535Y546712D03*
Y542712D03*
X1165400Y553300D03*
X1167900D03*
X1161451Y618288D03*
X1160275Y656321D03*
X1164275D03*
X1162863Y678519D03*
X1159173Y678462D03*
X1170465Y677836D03*
X1157646Y699491D03*
X1162646D03*
X1160146D03*
X1169256Y694983D03*
X1163774Y713347D03*
X1166115Y718469D03*
X1171934Y733857D03*
X1173034Y765060D03*
X1169697Y791935D03*
X1164925Y791607D03*
X1164732Y802269D03*
X1173122Y802759D03*
X1163579Y850774D03*
X1161535Y844167D03*
X1159887Y869106D03*
X1174461Y914515D03*
X1183682Y85193D03*
Y82593D03*
Y74793D03*
Y79993D03*
Y77393D03*
X1183726Y92874D03*
X1174818Y95236D03*
X1185753Y107649D03*
Y104249D03*
X1182775Y162368D03*
X1185375D03*
X1188158Y211695D03*
X1184086Y210713D03*
Y213213D03*
Y208213D03*
X1190958Y208695D03*
X1188158D03*
X1184086Y215713D03*
X1176959Y264180D03*
X1179459D03*
X1177035Y257919D03*
X1185853Y267526D03*
X1188653D03*
X1185853Y270026D03*
X1188653D03*
X1179901Y306366D03*
X1181706Y310131D03*
X1178045Y312193D03*
X1181379Y316049D03*
X1174929Y319167D03*
X1179761Y336380D03*
X1187996Y331992D03*
X1191748Y392676D03*
X1188598Y381500D03*
X1178083Y442856D03*
X1189122Y442606D03*
X1176699Y451108D03*
X1176138Y458455D03*
X1179184Y453881D03*
Y446595D03*
X1188739Y446606D03*
X1190046Y463479D03*
X1174595Y771744D03*
X1176500Y784933D03*
X1185516Y844248D03*
X1190968Y848703D03*
X1184340Y851072D03*
X1183012Y856553D03*
X1190213Y856816D03*
X1187431Y868340D03*
X1180239Y868430D03*
X1179858Y883455D03*
X1179727Y886197D03*
X1181654Y894671D03*
X1185058Y883475D03*
X1187151Y921000D03*
X1182000Y936500D03*
X1189219Y940703D03*
X1192007Y98551D03*
X1202561Y97475D03*
X1194902Y114623D03*
Y111223D03*
X1195557Y103783D03*
X1202492Y106186D03*
X1205304Y118335D03*
Y121735D03*
X1194902Y128796D03*
X1205304Y132509D03*
X1194902Y125396D03*
X1205304Y135909D03*
X1190319Y147540D03*
X1194091Y141247D03*
X1201558Y143740D03*
X1198938Y148277D03*
X1192475Y165393D03*
Y162793D03*
Y167993D03*
Y170493D03*
X1199980Y172190D03*
X1194683Y181366D03*
X1191472Y181426D03*
X1197478Y181009D03*
X1202653Y168697D03*
X1199399Y177616D03*
X1203741Y191941D03*
X1194297Y184012D03*
X1191680Y184221D03*
X1205750Y206767D03*
X1195716Y211359D03*
Y213859D03*
X1199419Y213132D03*
X1190658Y211695D03*
X1205295Y224421D03*
X1205880Y221708D03*
X1199419Y215632D03*
X1199663Y256303D03*
X1199422Y265896D03*
X1204438Y266114D03*
X1194335Y265701D03*
X1191153Y267526D03*
Y270026D03*
X1201911Y281982D03*
X1195970Y281716D03*
X1201113Y315039D03*
X1190127Y324142D03*
X1195800Y324000D03*
X1206531Y393858D03*
X1208173Y398583D03*
X1192702Y440489D03*
X1192957Y435158D03*
X1193000Y444841D03*
X1192686Y449961D03*
X1196403Y458572D03*
X1192431Y868620D03*
X1192152Y884399D03*
X1192367Y903785D03*
X1190210Y900909D03*
X1191151Y936296D03*
X1193219Y940703D03*
X1197173Y940645D03*
X1196352Y951033D03*
X1191219Y967757D03*
X1191928Y987314D03*
X1198644Y985289D03*
X1195757Y988131D03*
X1203419Y1011161D03*
X1200008D03*
X1196300Y998600D03*
X1202028Y998349D03*
X1199700Y1013661D03*
X1201800Y1019431D03*
X1219783Y55513D03*
X1216008Y68581D03*
X1222383Y60513D03*
X1216021Y80581D03*
X1208103Y72615D03*
Y76587D03*
X1222511Y85731D03*
X1220151Y88801D03*
X1218204Y103621D03*
X1209542Y100625D03*
X1213915Y112083D03*
X1210121Y141247D03*
X1214608Y143518D03*
X1213708Y152373D03*
X1216858Y152562D03*
X1222353Y157370D03*
X1217550Y183834D03*
X1212265Y171523D03*
X1217723Y172665D03*
X1217660Y178560D03*
X1218536Y186629D03*
X1211795Y192490D03*
X1210268Y198671D03*
X1217840Y200864D03*
X1217070Y190185D03*
X1207753Y192300D03*
X1208250Y206767D03*
X1210750D03*
X1217863Y207037D03*
X1217929Y212455D03*
X1215230Y221642D03*
X1206995Y228221D03*
X1208380Y221708D03*
X1210880D03*
X1206995Y231021D03*
X1222110Y219379D03*
X1222738Y228631D03*
X1207546Y236189D03*
X1210046D03*
X1212546D03*
X1207487Y248765D03*
X1209987D03*
X1212487D03*
X1219144Y265897D03*
X1216644D03*
X1212984Y268195D03*
X1210184D03*
X1207684D03*
X1212984Y270695D03*
X1207684D03*
X1210184D03*
X1220723Y324466D03*
X1211892Y339559D03*
X1215776Y331072D03*
X1213173Y377912D03*
X1217177Y369925D03*
X1206693Y384410D03*
X1213173Y386500D03*
X1209872Y382047D03*
X1212173Y391496D03*
X1213261Y397912D03*
X1210173Y403500D03*
X1212173Y409000D03*
X1209426Y433069D03*
Y430469D03*
Y435669D03*
Y440869D03*
Y438269D03*
X1206626Y433069D03*
Y430469D03*
Y435669D03*
Y440869D03*
Y438269D03*
X1209980Y451677D03*
X1207480Y454177D03*
X1209980D03*
X1207480Y451677D03*
X1209184Y463618D03*
Y460218D03*
X1225243Y60438D03*
X1230924Y86012D03*
Y94374D03*
X1226065Y86046D03*
X1227017Y94279D03*
X1223068Y94351D03*
X1238230Y116594D03*
X1226261D03*
X1232204Y110784D03*
X1237204D03*
X1238230Y119594D03*
X1226261D03*
X1236783Y124663D03*
X1226695Y124283D03*
X1231761Y124879D03*
X1238127Y138838D03*
X1225102Y161306D03*
X1226437Y176665D03*
Y168665D03*
Y192665D03*
X1226550Y186778D03*
X1226469Y204864D03*
Y208864D03*
X1231518Y218085D03*
X1234318D03*
X1238118Y216385D03*
X1239465Y244571D03*
X1236845Y249108D03*
X1228226Y248371D03*
X1229252Y314890D03*
X1229028Y311740D03*
X1226436Y324518D03*
X1229922Y324550D03*
X1234904Y316942D03*
X1232197Y316964D03*
X1238293Y317296D03*
X1229438Y332584D03*
X1235589Y348015D03*
X1229942Y347937D03*
X1231506Y353470D03*
X1223431Y377912D03*
X1225755Y369391D03*
X1229122Y369355D03*
X1222601Y369251D03*
X1223431Y381912D03*
Y397912D03*
X1235166Y470706D03*
Y467306D03*
Y484879D03*
Y481479D03*
Y514839D03*
Y511439D03*
Y529013D03*
Y525613D03*
X1232833Y539315D03*
X1232149Y550137D03*
X1234941D03*
X1235166Y564879D03*
Y561479D03*
Y575652D03*
Y579052D03*
Y593225D03*
Y603999D03*
Y589825D03*
Y607399D03*
X1235930Y626229D03*
X1235292Y622912D03*
X1237500Y632405D03*
X1238034Y629961D03*
X1238695Y627313D03*
X1256307Y103411D03*
X1247847Y97667D03*
X1256701D03*
X1252097Y95111D03*
X1243503Y102495D03*
X1241764Y125107D03*
X1243237Y142862D03*
X1250378Y143762D03*
X1244278Y148717D03*
X1251826Y195176D03*
X1254326D03*
X1253844Y199248D03*
X1249326Y195176D03*
X1250844Y199248D03*
X1246826Y195176D03*
X1249407Y210509D03*
X1253844Y202048D03*
X1250844Y201748D03*
X1251180Y206806D03*
X1248680D03*
X1246907Y210509D03*
X1240831Y221970D03*
X1240897Y226320D03*
X1240831Y219470D03*
Y216970D03*
X1248599Y230556D03*
X1252854Y227824D03*
X1243858Y228646D03*
X1253460Y238714D03*
X1247584Y242078D03*
X1252941Y246874D03*
X1242815Y232971D03*
X1246808Y256394D03*
X1241205Y303962D03*
X1253245Y416888D03*
Y419488D03*
Y422088D03*
X1245568Y474418D03*
Y488591D03*
Y477818D03*
Y491991D03*
Y521952D03*
Y518552D03*
Y536125D03*
Y532725D03*
X1253087Y553101D03*
X1241629Y550065D03*
X1245568Y568591D03*
Y571991D03*
Y582765D03*
Y586165D03*
Y596938D03*
Y600338D03*
Y611111D03*
Y614511D03*
X1248106Y1004700D03*
X1245400Y1003700D03*
X1246000Y1014800D03*
X1252148Y1026223D03*
X1252500Y1014288D03*
X1246300Y1027800D03*
X1253424Y1138130D03*
X1250928Y1142828D03*
X1254200Y1146600D03*
X1249363Y1173065D03*
X1256218Y1175987D03*
X1249363Y1166065D03*
X1255439Y1172008D03*
X1255628Y1188345D03*
X1253056Y1194917D03*
X1254275Y1531334D03*
X1249894Y1527805D03*
X1253904Y1519645D03*
X1254275Y1539334D03*
X1250434Y1535334D03*
X1267497Y90650D03*
X1267247Y95236D03*
X1256466Y106561D03*
X1257444Y230117D03*
X1255161Y244297D03*
X1266962Y302167D03*
X1262665Y302730D03*
X1263328Y309003D03*
X1262075Y324075D03*
X1261659Y318258D03*
X1264088Y320382D03*
X1266616Y322456D03*
X1257000Y333500D03*
X1264215Y333215D03*
X1262500Y330655D03*
X1256000Y338000D03*
X1259991Y340691D03*
X1256000Y340500D03*
X1263500Y336000D03*
X1264659Y377173D03*
X1267944Y371767D03*
X1261764Y391533D03*
X1263484Y385644D03*
X1268659Y385123D03*
X1268067Y406060D03*
X1261231Y399918D03*
X1264336Y412106D03*
X1268328Y421489D03*
Y418889D03*
Y416289D03*
X1270397Y447081D03*
X1259223Y454334D03*
X1267540Y459330D03*
X1267493Y454214D03*
X1267836Y449045D03*
X1267843Y473571D03*
Y481071D03*
Y478571D03*
Y476071D03*
X1269629Y848124D03*
X1270892Y856343D03*
X1271121Y892513D03*
X1270276Y897062D03*
X1269221Y894760D03*
X1270586Y905324D03*
X1272661Y929858D03*
X1260539Y1134729D03*
X1267921D03*
X1266718Y1142666D03*
X1263921Y1134729D03*
X1268593Y1157544D03*
X1267104Y1167768D03*
X1272123D03*
X1271246Y1178240D03*
X1271256Y1185205D03*
X1262605Y1187215D03*
X1262298Y1180175D03*
X1260800Y1191096D03*
X1268571Y1201043D03*
X1264575D03*
X1261538Y1199814D03*
X1255296Y1196056D03*
X1263449Y1217228D03*
X1266113Y1219895D03*
X1269388Y1223170D03*
X1267333Y1531334D03*
X1262891Y1527334D03*
X1267183Y1539334D03*
X1262891Y1535334D03*
X1286044Y85539D03*
Y82939D03*
Y75139D03*
Y80339D03*
Y77739D03*
X1286088Y92874D03*
X1272809Y90615D03*
X1277130Y99961D03*
X1277180Y95236D03*
X1285137Y162368D03*
X1275992Y215478D03*
Y212978D03*
Y210478D03*
Y207978D03*
X1286448Y213213D03*
Y210713D03*
Y208213D03*
Y215713D03*
X1281821Y264180D03*
X1279321D03*
X1279246Y258880D03*
X1271571Y281185D03*
X1289345Y330655D03*
X1284419Y359377D03*
X1287437Y379429D03*
X1280699Y377173D03*
X1284659D03*
X1274436Y377350D03*
X1276659Y385123D03*
X1273659D03*
X1280659D03*
X1284333Y391569D03*
X1282760Y401066D03*
X1272421Y403300D03*
X1271828Y405889D03*
Y408489D03*
Y413689D03*
Y411089D03*
Y416289D03*
Y421489D03*
Y418889D03*
Y424089D03*
X1272215Y432718D03*
Y435518D03*
X1282092Y442118D03*
Y439318D03*
X1271828Y426689D03*
X1272927Y450091D03*
X1275927D03*
X1273397Y447081D03*
X1281737Y461034D03*
Y456034D03*
X1272927Y462060D03*
X1275927D03*
X1286005Y485580D03*
X1280631Y480194D03*
Y477694D03*
X1277897Y478876D03*
Y476376D03*
X1274415Y477053D03*
X1271915D03*
X1284900Y678800D03*
X1283400Y715500D03*
X1278255Y722241D03*
X1283400Y719700D03*
X1282539Y746076D03*
X1279539Y748576D03*
X1282539Y751076D03*
X1279539Y763576D03*
X1282539Y766076D03*
X1279539Y758576D03*
X1282539Y756076D03*
Y761076D03*
X1279539Y753576D03*
Y768576D03*
Y780576D03*
Y784576D03*
X1285092Y819500D03*
X1285500Y827500D03*
X1281388Y827388D03*
X1281777Y823500D03*
X1285500Y843500D03*
X1281331Y843331D03*
X1281269Y835492D03*
X1285500Y835500D03*
X1283025Y848305D03*
X1271438Y861846D03*
X1285500Y863500D03*
Y859500D03*
Y855500D03*
Y851500D03*
X1279460Y854487D03*
Y859487D03*
Y864487D03*
X1274396Y866896D03*
X1285500Y867500D03*
X1279460Y874487D03*
Y869487D03*
Y879487D03*
X1285302Y877283D03*
X1282285Y865602D03*
X1274264Y898591D03*
X1279460Y884487D03*
X1285302Y885783D03*
X1279299Y898813D03*
X1279460Y889487D03*
X1285302Y881783D03*
X1281075Y911075D03*
X1282184Y898854D03*
X1274400Y914123D03*
X1283494Y907176D03*
X1275493Y929858D03*
X1279493D03*
X1283493D03*
X1279693Y919800D03*
X1274670Y919808D03*
X1281400Y940256D03*
X1289547Y941000D03*
X1281733Y949475D03*
X1275788Y1124088D03*
X1282421Y1137129D03*
X1271921Y1134729D03*
X1275794D03*
X1282830Y1150087D03*
X1275050Y1157404D03*
X1280306Y1170767D03*
X1275965Y1187232D03*
X1280602Y1185238D03*
X1280395Y1180235D03*
X1272541Y1201043D03*
X1276575Y1201039D03*
X1280575Y1200969D03*
X1280694Y1208993D03*
X1274446Y1228226D03*
X1272235Y1226016D03*
X1297785Y33768D03*
X1302139Y26325D03*
X1302785Y31168D03*
X1294369Y98551D03*
X1304923Y97475D03*
X1297264Y114623D03*
Y111223D03*
X1297919Y103783D03*
X1288115Y104249D03*
Y107649D03*
X1297264Y128796D03*
Y125396D03*
X1294837Y162793D03*
X1287737Y162368D03*
X1294837Y165393D03*
Y167993D03*
Y170493D03*
X1301761Y177616D03*
X1302342Y172190D03*
X1299840Y181009D03*
X1293834Y181426D03*
X1297045Y181366D03*
X1294042Y184221D03*
X1296659Y184012D03*
X1301781Y213132D03*
X1298078Y211359D03*
Y213859D03*
X1290520Y211695D03*
X1293020D03*
X1290520Y208695D03*
X1293320D03*
X1301781Y215632D03*
X1302025Y256303D03*
X1296697Y265701D03*
X1301784Y265896D03*
X1293515Y270026D03*
X1291015D03*
X1288215D03*
Y267526D03*
X1293515D03*
X1291015D03*
X1304273Y281982D03*
X1298332Y281716D03*
X1294000Y324000D03*
X1303000Y326692D03*
X1293000Y338500D03*
X1303000Y331000D03*
X1302896Y343797D03*
Y340397D03*
X1292500Y335000D03*
X1299959Y356954D03*
X1294080Y349820D03*
X1291410Y371060D03*
X1295410Y371076D03*
X1293048Y379088D03*
X1298346Y379028D03*
X1293100Y409539D03*
X1296100D03*
X1293100Y406739D03*
X1296100Y407039D03*
X1295764Y401981D03*
X1298264D03*
X1300037Y398278D03*
X1297537D03*
X1292618Y413611D03*
X1295118D03*
X1300118D03*
X1297618D03*
X1292383Y424067D03*
X1294883D03*
X1299883D03*
X1297383D03*
X1299757Y438293D03*
Y441093D03*
X1290092Y442118D03*
Y439318D03*
X1299757Y443893D03*
X1287719Y470001D03*
X1290219D03*
X1299867Y477318D03*
X1299466Y466409D03*
X1299807Y472020D03*
X1288144Y489036D03*
X1291005Y485580D03*
X1288505D03*
X1301314Y484882D03*
X1299304Y487382D03*
X1290380Y495636D03*
Y492836D03*
X1300817Y568635D03*
X1301194Y565518D03*
X1305836Y660009D03*
X1298963Y659609D03*
X1289811Y677612D03*
X1289317Y706932D03*
X1291604Y781576D03*
Y776576D03*
Y771435D03*
X1295491Y798821D03*
X1298720Y798975D03*
X1289730Y806845D03*
X1302140Y812625D03*
X1302501Y824747D03*
X1297667Y832150D03*
X1293500Y827500D03*
X1296770Y828775D03*
X1293500Y843500D03*
Y835500D03*
X1296687Y839500D03*
X1293500Y851500D03*
X1294000Y863500D03*
X1293500Y879800D03*
Y871800D03*
Y875800D03*
X1288164Y892354D03*
X1296866Y894993D03*
X1305250Y889250D03*
X1293272Y887800D03*
X1293500Y883800D03*
X1291129Y892267D03*
X1294264Y905595D03*
X1301657Y899129D03*
X1288500Y901254D03*
X1298966Y899610D03*
X1296466D03*
X1298000Y917000D03*
X1294075D03*
X1304949Y928546D03*
X1292500Y928000D03*
X1295453Y928047D03*
X1291059Y917000D03*
X1302000D03*
X1302500Y939500D03*
X1300882Y937144D03*
X1296500Y961500D03*
X1289500Y949500D03*
X1300500Y960000D03*
X1290792Y961363D03*
X1300500Y970187D03*
X1297558Y970216D03*
X1292836Y975244D03*
X1292631Y979845D03*
X1299717Y1024136D03*
X1297852Y1014475D03*
X1295815Y1124943D03*
X1295893Y1122182D03*
X1310853Y37543D03*
X1314887Y45448D03*
X1318859D03*
X1311904Y100625D03*
X1320566Y103621D03*
X1304854Y106186D03*
X1316277Y112083D03*
X1307666Y118335D03*
Y132509D03*
Y121735D03*
Y135909D03*
X1305015Y168697D03*
X1319912Y183834D03*
X1314627Y171523D03*
X1320085Y172665D03*
X1320022Y178560D03*
X1306103Y191941D03*
X1319432Y190185D03*
X1314157Y192490D03*
X1320202Y200864D03*
X1310115Y192300D03*
X1308112Y206767D03*
X1313112D03*
X1310612D03*
X1320225Y207037D03*
X1320291Y212455D03*
X1313242Y221708D03*
X1310742D03*
X1309357Y231021D03*
Y228221D03*
X1317592Y221642D03*
X1308242Y221708D03*
X1307657Y224421D03*
X1309908Y236189D03*
X1314908D03*
X1312408D03*
X1312349Y248765D03*
X1309849D03*
X1314849D03*
X1306800Y266114D03*
X1310046Y268195D03*
X1312546D03*
X1315346D03*
X1319006Y265897D03*
X1312546Y270695D03*
X1310046D03*
X1315346D03*
X1318362Y310562D03*
X1305928Y318250D03*
X1308428D03*
X1315256Y336510D03*
X1313103Y339606D03*
X1312240Y334681D03*
X1315397Y333709D03*
X1308012Y348109D03*
X1305910Y377581D03*
X1310172Y367956D03*
X1308410Y379591D03*
X1311283Y370801D03*
X1308826Y389402D03*
X1306113Y383817D03*
X1312626Y387702D03*
X1315426D03*
X1306113Y386317D03*
Y388817D03*
X1309750Y438293D03*
Y441093D03*
Y443893D03*
X1311488Y471560D03*
X1307819Y474382D03*
X1307835Y470382D03*
X1319474Y467560D03*
X1319974Y475560D03*
X1311488D03*
X1318160Y520053D03*
X1317945Y523058D03*
X1319000Y562500D03*
Y558500D03*
Y586500D03*
Y574500D03*
Y578500D03*
Y605000D03*
Y590500D03*
X1319323Y598454D03*
X1319000Y621000D03*
Y609000D03*
Y633000D03*
Y625000D03*
Y637000D03*
Y653500D03*
Y649500D03*
Y641000D03*
Y669500D03*
Y665500D03*
Y681500D03*
Y677500D03*
X1313979Y677726D03*
X1319000Y685500D03*
Y696500D03*
Y700500D03*
Y712500D03*
Y716500D03*
Y724500D03*
Y728500D03*
Y732500D03*
X1321000Y796000D03*
X1313000D03*
X1317000Y799000D03*
Y788000D03*
X1313000D03*
X1315000Y811620D03*
X1319000D03*
X1317000Y804000D03*
X1313000D03*
X1321000D03*
X1310715Y820491D03*
Y822991D03*
Y817991D03*
X1310687Y830206D03*
Y832706D03*
Y827706D03*
X1310971Y842319D03*
X1305786Y867704D03*
X1310994Y866859D03*
X1309753Y877589D03*
X1305740Y877534D03*
X1310535Y870775D03*
X1308220Y889253D03*
X1311061Y889361D03*
X1314500Y911500D03*
X1319500Y901500D03*
X1314500Y905000D03*
X1305356Y902597D03*
X1319500Y905000D03*
X1309103Y917000D03*
X1313867Y925605D03*
X1311325Y928918D03*
X1319554Y925585D03*
X1309103Y936559D03*
X1306500Y936500D03*
X1315779Y943743D03*
X1313152Y936605D03*
X1312575Y943974D03*
X1321256Y943815D03*
X1311000Y961500D03*
X1307000Y960500D03*
X1315441Y960000D03*
X1307000Y970000D03*
X1311000Y970124D03*
X1307707Y979870D03*
X1317254Y990777D03*
X1317053Y988111D03*
X1319874Y989856D03*
X1307561Y986951D03*
X1315606Y1042825D03*
X1315756Y1039344D03*
X1312873Y1036543D03*
X1306385Y1036646D03*
X1319221Y1058097D03*
Y1060697D03*
X1316869Y1107997D03*
X1319069Y1112397D03*
X1318969Y1109397D03*
X1316869Y1113797D03*
Y1110897D03*
X1317437Y1160834D03*
X1318178Y1192621D03*
Y1190121D03*
X1319237Y1221428D03*
X1311237D03*
X1315237D03*
X1311237Y1233428D03*
Y1229428D03*
Y1225428D03*
X1315237Y1237428D03*
Y1233428D03*
Y1229428D03*
Y1225428D03*
X1319237Y1237428D03*
Y1233428D03*
Y1229428D03*
Y1225428D03*
X1315237Y1241428D03*
X1319237D03*
X1308107Y1283395D03*
X1310773Y1282411D03*
X1303900Y1288000D03*
X1318287Y1295381D03*
Y1291381D03*
X1324120Y22742D03*
X1331073Y33400D03*
X1328003Y32403D03*
X1328318Y27333D03*
X1336623Y30483D03*
X1322853Y37530D03*
X1328799Y168665D03*
Y176665D03*
X1320898Y186629D03*
X1328799Y192665D03*
Y196665D03*
X1328912Y186778D03*
X1328831Y204864D03*
Y208864D03*
X1324472Y219379D03*
X1325100Y228631D03*
X1321506Y265897D03*
X1334110Y310562D03*
X1321762D03*
X1329636Y307562D03*
X1326236D03*
X1332563Y326356D03*
X1325573Y326719D03*
X1332359Y322685D03*
X1326489Y356945D03*
X1331005Y356670D03*
X1331922Y359836D03*
X1325007Y370951D03*
X1334109Y373401D03*
X1334285Y386567D03*
X1331606D03*
X1328896D03*
X1320594Y387151D03*
Y382151D03*
Y384651D03*
X1329097Y435321D03*
Y438121D03*
X1326297Y435321D03*
Y438121D03*
X1329097Y440921D03*
X1326297D03*
X1329097Y443721D03*
X1326297D03*
X1335440Y452799D03*
X1329083Y448931D03*
X1329606Y459170D03*
X1332974Y474513D03*
X1321450Y520268D03*
X1321164Y523130D03*
X1326993Y556788D03*
X1331096Y549931D03*
X1327043Y573346D03*
X1327000Y562500D03*
X1326946Y567906D03*
X1338000Y562500D03*
X1327000Y578500D03*
Y583826D03*
X1335000Y594500D03*
X1327000Y605000D03*
Y594500D03*
Y609000D03*
X1333224Y615484D03*
X1327000Y613000D03*
Y621000D03*
X1335532Y622260D03*
X1338000Y609000D03*
X1327000Y629000D03*
X1327003Y623940D03*
X1335000Y641000D03*
X1338000Y653500D03*
X1327000Y641000D03*
X1327011Y646064D03*
X1327000Y657500D03*
X1335000Y685500D03*
X1327000D03*
Y695500D03*
Y700500D03*
X1338000D03*
X1327000Y711500D03*
Y716500D03*
X1335000Y732500D03*
X1327000D03*
X1330295Y746328D03*
X1326970Y736464D03*
X1336661Y753675D03*
Y745675D03*
Y737675D03*
X1330295Y751328D03*
X1330086Y763758D03*
X1330324Y779030D03*
X1336746Y781675D03*
X1329000Y796000D03*
X1325000Y799000D03*
X1337000Y796000D03*
X1333000Y799000D03*
Y788000D03*
X1329000D03*
X1321000D03*
X1325000D03*
X1331000Y811620D03*
X1327000D03*
X1329000Y804000D03*
X1325000D03*
X1333000D03*
X1323000Y811620D03*
X1335000D03*
X1335803Y826500D03*
X1331056Y904557D03*
X1336096Y905042D03*
X1336000Y900500D03*
X1324000Y901000D03*
X1331078Y900500D03*
X1330500Y925500D03*
X1334500D03*
X1326500D03*
X1333425Y930925D03*
X1324000D03*
X1333132Y933781D03*
X1336000Y943500D03*
X1329199Y933825D03*
X1323000Y934075D03*
X1326500Y943500D03*
X1335343Y961727D03*
X1321028Y961749D03*
X1332500Y961500D03*
X1325550Y960445D03*
X1332000Y969500D03*
X1327000D03*
X1329503Y991088D03*
X1334909Y990340D03*
X1332404Y988215D03*
X1329834Y988132D03*
X1324735Y989966D03*
X1327267Y988271D03*
X1322427Y988221D03*
X1333974Y1033483D03*
X1320549Y1037876D03*
X1322773Y1040599D03*
X1329221Y1058097D03*
X1321721D03*
X1324221D03*
X1326721D03*
Y1060697D03*
X1329221D03*
X1321721D03*
X1324221D03*
X1326163Y1082501D03*
X1326189Y1085205D03*
X1329163Y1082501D03*
X1329189Y1085205D03*
X1326189Y1088205D03*
X1326471Y1091227D03*
X1329189Y1088205D03*
X1323189Y1085205D03*
Y1087705D03*
X1323163Y1082501D03*
X1323021Y1090956D03*
X1337514Y1104335D03*
X1334956Y1105552D03*
X1321069Y1107997D03*
X1323021Y1093956D03*
X1331162Y1104792D03*
X1332669Y1106867D03*
X1321169Y1110597D03*
X1321954Y1113648D03*
X1326254D03*
X1328754D03*
X1323405Y1118801D03*
Y1116101D03*
X1325635Y1172384D03*
Y1162384D03*
Y1164884D03*
Y1167384D03*
Y1169884D03*
X1323135Y1172384D03*
Y1162384D03*
Y1164884D03*
Y1167384D03*
Y1169884D03*
X1334793Y1179421D03*
Y1181921D03*
Y1184421D03*
Y1186921D03*
X1320493Y1186709D03*
Y1184209D03*
Y1181709D03*
Y1179209D03*
X1325635Y1174884D03*
X1323135D03*
X1331643Y1192621D03*
Y1190121D03*
X1327237Y1221428D03*
X1331237D03*
X1335237D03*
X1323237D03*
X1327237Y1237428D03*
Y1233428D03*
Y1229428D03*
Y1225428D03*
X1331237Y1237428D03*
Y1233428D03*
Y1229428D03*
Y1225428D03*
X1335237Y1237428D03*
Y1233428D03*
Y1229428D03*
Y1225428D03*
X1323237Y1237428D03*
Y1233428D03*
Y1229428D03*
Y1225428D03*
X1335237Y1241428D03*
X1323237Y1245428D03*
Y1241428D03*
X1327237Y1245428D03*
Y1241428D03*
X1331237Y1245428D03*
Y1241428D03*
X1335237Y1245428D03*
X1333876Y1257160D03*
Y1260160D03*
X1336646Y22627D03*
X1336551Y26534D03*
X1340320Y147540D03*
X1344092Y141247D03*
X1351559Y143740D03*
X1348939Y148277D03*
X1348419Y265222D03*
X1340104Y279117D03*
X1344007Y279054D03*
X1337510Y310562D03*
X1347990Y322539D03*
X1341169Y325926D03*
X1346009Y336080D03*
X1346093Y340805D03*
X1349636Y340862D03*
X1346065Y347106D03*
X1338471Y356959D03*
X1337509Y373401D03*
X1349763Y371908D03*
X1342810Y408104D03*
X1345610D03*
X1348410D03*
X1336388Y424939D03*
X1342527Y420375D03*
X1345327D03*
X1348127D03*
X1336388Y427439D03*
X1346443Y431112D03*
X1352008Y435101D03*
X1352271Y442114D03*
X1346613Y440101D03*
X1352251Y447121D03*
X1346248Y452718D03*
X1340820Y452987D03*
X1352259Y452601D03*
X1347846Y461607D03*
X1339846D03*
X1339049Y471334D03*
X1343846Y461607D03*
X1346738Y564492D03*
X1339289Y568461D03*
X1342053Y579339D03*
X1346533Y576780D03*
X1340522Y586133D03*
X1343000Y590458D03*
X1346533Y581898D03*
X1344129Y606914D03*
X1344433Y601201D03*
X1339289Y614961D03*
X1344680Y619085D03*
X1346738Y611192D03*
X1346533Y628398D03*
X1346378Y623734D03*
X1342053Y625839D03*
X1340522Y632633D03*
X1343000Y636958D03*
X1346738Y655492D03*
X1339289Y659461D03*
X1346533Y667780D03*
X1342053Y670339D03*
X1346533Y672898D03*
X1340522Y677133D03*
X1343000Y681458D03*
X1350929Y687043D03*
X1340299Y686243D03*
X1346738Y702492D03*
X1346533Y719898D03*
X1339289Y706461D03*
X1342053Y717339D03*
X1346533Y714780D03*
X1340522Y724133D03*
X1343000Y728458D03*
X1344768Y737675D03*
Y741675D03*
Y745675D03*
Y749675D03*
Y753675D03*
Y761675D03*
Y757675D03*
X1336450Y765675D03*
X1344768Y773675D03*
Y781350D03*
X1345226Y777675D03*
X1341000Y799000D03*
X1345000Y796000D03*
X1341000Y788000D03*
X1345000D03*
X1337000D03*
X1348917Y796000D03*
Y788000D03*
X1352817Y796000D03*
X1349000Y804000D03*
X1351000Y811620D03*
X1347000D03*
X1343000D03*
X1337000Y804000D03*
X1345000D03*
X1341000D03*
X1349976Y829000D03*
X1350000Y825500D03*
X1340000Y900000D03*
X1351500Y903000D03*
Y906500D03*
X1340000Y906000D03*
Y903000D03*
X1351511Y900000D03*
X1350500Y925500D03*
X1338500D03*
X1342500D03*
X1346500D03*
X1353948Y943603D03*
X1345948D03*
X1349848Y936755D03*
X1338500Y930500D03*
X1350500D03*
X1342500D03*
X1346500D03*
X1337514Y988259D03*
X1343465Y1026123D03*
X1340665D03*
X1343465Y1028923D03*
X1340665D03*
X1347552Y1091816D03*
Y1089316D03*
X1345052Y1081816D03*
Y1084316D03*
Y1086816D03*
X1347552D03*
Y1084316D03*
X1350418Y1090288D03*
X1347552Y1081816D03*
X1344241Y1106298D03*
X1348997Y1107997D03*
X1350418Y1093088D03*
X1339234Y1101917D03*
X1339169Y1106897D03*
X1341984Y1110092D03*
X1345650Y1115896D03*
X1348997Y1113797D03*
Y1110897D03*
X1351197Y1112397D03*
X1351097Y1109397D03*
X1345650Y1118396D03*
X1347300Y1128332D03*
X1343725Y1128738D03*
X1343905Y1162384D03*
Y1164884D03*
Y1167384D03*
Y1169884D03*
Y1172384D03*
X1341405D03*
Y1169884D03*
Y1167384D03*
Y1164884D03*
Y1162384D03*
X1350963Y1172384D03*
Y1169884D03*
Y1167384D03*
Y1164884D03*
Y1162384D03*
X1351149Y1158200D03*
X1347423Y1186709D03*
Y1184209D03*
Y1181709D03*
Y1179209D03*
X1343905Y1174884D03*
X1341405D03*
X1350963D03*
X1337108Y1192621D03*
Y1190121D03*
X1345108D03*
Y1192621D03*
X1347237Y1221428D03*
X1343237D03*
X1339237D03*
X1347237Y1237428D03*
Y1233428D03*
Y1229428D03*
X1343237D03*
Y1233428D03*
Y1237428D03*
X1339237D03*
Y1233428D03*
Y1229428D03*
Y1225428D03*
X1347237Y1245428D03*
Y1241428D03*
X1343237D03*
Y1245428D03*
X1339237D03*
Y1241428D03*
X1339876Y1257160D03*
X1342876D03*
X1345876Y1260160D03*
Y1257160D03*
X1348876Y1260160D03*
Y1257160D03*
X1351876Y1260160D03*
Y1257160D03*
X1336876Y1260160D03*
Y1257160D03*
X1342876Y1260160D03*
X1339876D03*
X1360122Y141247D03*
X1364609Y143518D03*
X1363709Y152373D03*
X1366859Y152562D03*
X1363535Y327877D03*
X1366535Y335751D03*
Y339151D03*
X1363535Y331277D03*
Y343625D03*
X1366535Y354899D03*
Y351499D03*
X1363535Y347025D03*
X1360719Y424601D03*
X1352817Y788000D03*
X1367000Y811620D03*
X1365000Y804000D03*
X1355000Y811620D03*
X1363000D03*
X1353000Y804000D03*
X1359000Y811620D03*
X1357000Y804000D03*
X1361000D03*
X1354185Y906498D03*
X1367000Y904500D03*
X1363000Y900500D03*
X1367000D03*
X1354500Y925500D03*
X1366500D03*
X1358500D03*
X1362500D03*
X1365948Y939475D03*
X1357948Y938842D03*
X1361948Y943603D03*
X1369948D03*
X1362500Y930500D03*
X1366500D03*
X1354500D03*
X1358500D03*
X1364765Y1004766D03*
X1367444Y1003763D03*
X1357765Y1019766D03*
X1361265D03*
X1365049Y1028416D03*
X1365314Y1021793D03*
X1357265Y1026266D03*
Y1034266D03*
X1366265Y1039880D03*
X1369642Y1104335D03*
X1367084Y1105552D03*
X1353197Y1107997D03*
X1363290Y1104792D03*
X1364797Y1106867D03*
X1353297Y1110597D03*
X1354082Y1113648D03*
X1355533Y1116101D03*
Y1118801D03*
X1360882Y1113648D03*
X1358382D03*
X1353463Y1172384D03*
Y1169884D03*
Y1167384D03*
Y1164884D03*
Y1162384D03*
X1361723Y1179421D03*
Y1181921D03*
Y1184421D03*
Y1186921D03*
X1353463Y1174884D03*
X1364038Y1190121D03*
Y1192621D03*
X1363876Y1260160D03*
Y1257160D03*
X1354876Y1260160D03*
X1357876D03*
X1360876D03*
Y1257160D03*
X1357876D03*
X1354876D03*
X1366876Y1260160D03*
Y1257160D03*
X1376262Y116594D03*
X1382205Y110784D03*
X1387205D03*
X1376262Y119594D03*
X1386784Y124663D03*
X1376696Y124283D03*
X1381762Y124879D03*
X1375103Y161306D03*
X1372354Y157370D03*
X1384319Y218085D03*
X1381519D03*
X1386846Y249108D03*
X1378227Y248371D03*
X1384265Y320871D03*
Y325371D03*
X1383551Y337808D03*
X1384265Y329871D03*
X1383634Y342766D03*
X1384265Y334371D03*
X1375073Y356871D03*
Y361371D03*
X1383505Y349437D03*
X1384265Y352371D03*
X1372232Y361298D03*
X1383963Y366675D03*
X1377024Y397713D03*
X1375108Y420838D03*
X1375171Y424741D03*
X1375400Y435192D03*
X1375360Y432234D03*
X1383343Y508228D03*
X1383907Y516591D03*
X1383556Y554388D03*
X1378415Y558795D03*
X1383608Y571927D03*
X1378415Y563984D03*
Y569776D03*
X1378957Y584457D03*
X1383000Y584500D03*
X1382997Y581317D03*
X1383425Y590425D03*
X1378415Y605295D03*
X1383608Y618427D03*
X1378415Y610484D03*
Y616276D03*
X1383425Y636925D03*
X1378957Y630957D03*
X1384657Y631620D03*
X1378957Y627988D03*
X1378415Y649795D03*
Y654984D03*
Y660776D03*
X1386289Y672488D03*
X1383425Y681425D03*
X1378957Y675457D03*
X1383000Y675500D03*
X1378415Y696795D03*
Y701984D03*
X1378957Y719488D03*
X1378415Y707776D03*
X1383425Y728425D03*
X1378957Y722457D03*
X1385290Y722400D03*
X1371000Y811620D03*
X1381000Y804000D03*
X1373000D03*
X1369000D03*
X1385360Y811757D03*
X1381428Y812287D03*
X1375193Y811724D03*
X1376708Y901000D03*
X1378500Y925500D03*
X1374369Y925499D03*
X1370500Y925500D03*
X1382500D03*
X1382775Y930281D03*
X1373948Y940103D03*
X1374500Y930500D03*
X1370500D03*
X1378500D03*
X1381519Y996280D03*
X1383162Y991829D03*
X1373534Y1012325D03*
Y1004680D03*
X1378938Y1000586D03*
X1374034Y1015825D03*
X1374059Y1018860D03*
X1376359Y1016825D03*
X1378559Y1038534D03*
X1384784Y1033783D03*
X1385929Y1038665D03*
X1373874Y1032266D03*
Y1035716D03*
X1385152Y1046591D03*
X1377087Y1106365D03*
X1371362Y1101917D03*
X1371297Y1106897D03*
X1382456Y1107997D03*
X1374112Y1110092D03*
X1377778Y1115896D03*
X1384656Y1112397D03*
X1382456Y1110897D03*
Y1113797D03*
X1384556Y1109397D03*
X1377778Y1118396D03*
X1369233Y1169884D03*
Y1172384D03*
X1371733D03*
Y1169884D03*
Y1167384D03*
Y1164884D03*
Y1162384D03*
X1369233D03*
Y1164884D03*
Y1167384D03*
X1376861Y1160834D03*
X1383024D03*
X1369233Y1174884D03*
X1371733D03*
X1375459Y1197471D03*
Y1193471D03*
X1379959Y1197471D03*
Y1193471D03*
X1397848Y97667D03*
X1388231Y116594D03*
X1393504Y102495D03*
X1388231Y119594D03*
X1391765Y125107D03*
X1393238Y142862D03*
X1400379Y143762D03*
X1394279Y148717D03*
X1388128Y138838D03*
X1399327Y195176D03*
X1396827D03*
X1400845Y199248D03*
Y201748D03*
X1398681Y206806D03*
X1401181D03*
X1399408Y210509D03*
X1396908D03*
X1390832Y216970D03*
Y219470D03*
X1390898Y226320D03*
X1390832Y221970D03*
X1388119Y216385D03*
X1402855Y227824D03*
X1398600Y230556D03*
X1393859Y228646D03*
X1397585Y242078D03*
X1392816Y232971D03*
X1389466Y244571D03*
X1396809Y256394D03*
X1395726Y320529D03*
X1395568Y325529D03*
X1395726Y330529D03*
X1395736Y335529D03*
X1395726Y340529D03*
Y345529D03*
Y360529D03*
Y350529D03*
Y355529D03*
X1391896Y365529D03*
X1399884Y367165D03*
X1387847Y366710D03*
X1400231Y390256D03*
X1396528Y397454D03*
X1399571Y397418D03*
X1393575Y397310D03*
X1390553Y397436D03*
X1391623Y409900D03*
X1387125Y417312D03*
X1393177Y424804D03*
X1389557Y424678D03*
X1389431Y421593D03*
X1390271Y417578D03*
X1393208Y428109D03*
X1393336Y431100D03*
X1403085Y460565D03*
X1393944Y507856D03*
X1394044Y510990D03*
X1397079Y527726D03*
Y548726D03*
Y544726D03*
X1395605Y556217D03*
X1390741Y561000D03*
Y569000D03*
Y565000D03*
X1391087Y581317D03*
X1398946Y621311D03*
X1390741Y611500D03*
Y607500D03*
Y615500D03*
X1391586Y623692D03*
X1398946Y629311D03*
Y625311D03*
X1397000Y652000D03*
Y656000D03*
Y660000D03*
Y699000D03*
Y707000D03*
Y703000D03*
X1391040Y812027D03*
X1386335Y803704D03*
X1390537Y803679D03*
X1394537Y803653D03*
X1398530Y811717D03*
X1402417Y811692D03*
X1400069Y827515D03*
X1401300Y820485D03*
X1395955Y832697D03*
X1402000Y840000D03*
Y848000D03*
X1399872Y845109D03*
X1402000Y864000D03*
X1391316Y857849D03*
X1388488Y857822D03*
X1402000Y876000D03*
X1390182Y873460D03*
X1387582Y873487D03*
X1402000Y884000D03*
Y892000D03*
X1388479Y892923D03*
X1385979D03*
X1390979D03*
X1402000Y900000D03*
X1387520Y905307D03*
X1387753Y912629D03*
X1394891Y914783D03*
X1402187Y908270D03*
X1387504Y899931D03*
X1390541Y900086D03*
X1388980Y921075D03*
X1401000Y925789D03*
X1396869Y958707D03*
X1402064Y965913D03*
X1389192Y992568D03*
X1398854Y987277D03*
X1394885Y999941D03*
X1392031Y1004375D03*
X1385732Y1029482D03*
X1389762Y1043055D03*
X1387813Y1030952D03*
X1399807Y1036155D03*
X1399852Y1039779D03*
X1388523Y1090090D03*
X1392691Y1089224D03*
X1392086Y1092743D03*
X1392691Y1086724D03*
Y1084224D03*
Y1081724D03*
X1390191D03*
Y1084224D03*
Y1086724D03*
X1403101Y1104335D03*
X1400543Y1105552D03*
X1396749Y1104792D03*
X1388451Y1093048D03*
X1386656Y1107997D03*
X1398256Y1106867D03*
X1386756Y1110597D03*
X1394341Y1113648D03*
X1388992Y1118801D03*
Y1116101D03*
X1387541Y1113648D03*
X1391841D03*
X1388722Y1162384D03*
Y1164884D03*
Y1167384D03*
Y1169884D03*
Y1172384D03*
X1391222Y1162384D03*
Y1164884D03*
Y1167384D03*
Y1169884D03*
Y1172384D03*
X1388722Y1174884D03*
X1391222D03*
X1393695Y1186709D03*
Y1184209D03*
Y1181709D03*
Y1179209D03*
X1391380Y1190121D03*
Y1192621D03*
X1385821Y1260160D03*
X1391821Y1257160D03*
X1394821D03*
X1385821D03*
X1388821D03*
X1397821Y1260160D03*
Y1257160D03*
X1400821Y1260160D03*
Y1257160D03*
X1388821Y1260160D03*
X1394821D03*
X1391821D03*
X1385052Y1303139D03*
X1389052D03*
X1406308Y103411D03*
X1406702Y97667D03*
X1417498Y90650D03*
X1417248Y95236D03*
X1402098Y95111D03*
X1406467Y106561D03*
X1403845Y199248D03*
X1401827Y195176D03*
X1404327D03*
X1403845Y202048D03*
X1407445Y230117D03*
X1403461Y238714D03*
X1402942Y246874D03*
X1405162Y244297D03*
X1402921Y322403D03*
X1409830Y347649D03*
X1404690Y362209D03*
X1416912Y386903D03*
X1408854Y381207D03*
X1416470Y381397D03*
X1402968Y390177D03*
X1414369Y398056D03*
X1408254Y398041D03*
X1407844Y411033D03*
X1415610Y417644D03*
X1415674Y421278D03*
X1417856Y448419D03*
X1414903Y469905D03*
X1410903Y470419D03*
Y461919D03*
X1418903Y461419D03*
X1411269Y481467D03*
X1415623Y492268D03*
X1415823Y482165D03*
X1416061Y504825D03*
X1413561D03*
X1411061D03*
X1415064Y500202D03*
X1406910Y495982D03*
X1416413Y495649D03*
X1406910Y491982D03*
X1416002Y517401D03*
X1413502D03*
X1411002D03*
X1416553Y522569D03*
Y525369D03*
X1415168Y531882D03*
X1412668D03*
X1409618Y531948D03*
X1401438Y534211D03*
X1405992Y534909D03*
X1405619Y541135D03*
X1405685Y546553D03*
X1405708Y552726D03*
X1415103Y555194D03*
Y563194D03*
Y571194D03*
X1416660Y581222D03*
Y591215D03*
X1401383Y611071D03*
X1416832Y610562D03*
Y607762D03*
X1411622Y610548D03*
X1407566Y622285D03*
X1407754Y616905D03*
X1418439Y633736D03*
X1407952Y633724D03*
X1413432Y633716D03*
X1407835Y627713D03*
X1405229Y652028D03*
X1405000Y660000D03*
X1410000Y685000D03*
Y681000D03*
X1404500Y675000D03*
X1410000Y701000D03*
Y697000D03*
X1418000Y696000D03*
Y701000D03*
X1410000Y709000D03*
Y713000D03*
X1405000Y707000D03*
Y703000D03*
X1418000Y717000D03*
X1410000D03*
X1404500Y722000D03*
X1410000Y729000D03*
Y725000D03*
X1418000Y724000D03*
Y729000D03*
X1404249Y735858D03*
X1410000Y745000D03*
Y741000D03*
X1418000Y740000D03*
Y745000D03*
X1407482Y750853D03*
X1410000Y757000D03*
Y753000D03*
Y761000D03*
X1418000D03*
X1406867Y783273D03*
X1409115Y773520D03*
X1414597Y792375D03*
X1406483Y811717D03*
X1413500Y832000D03*
Y828000D03*
X1413449Y823934D03*
X1405402Y819917D03*
X1405500Y844000D03*
Y836000D03*
X1413500Y848000D03*
Y840000D03*
Y836000D03*
Y844000D03*
X1405500Y860000D03*
X1413500Y864000D03*
Y860000D03*
Y856000D03*
Y852000D03*
X1405500Y880000D03*
Y868000D03*
X1413500Y876000D03*
X1417797Y879501D03*
X1413500Y872000D03*
Y868000D03*
X1405500Y888000D03*
Y896000D03*
X1417081D03*
X1413500Y892000D03*
Y884000D03*
Y888000D03*
X1413733Y911137D03*
X1412376Y907848D03*
X1414876D03*
X1417376D03*
X1409876D03*
X1405500Y904000D03*
X1404760Y915186D03*
X1413500Y904000D03*
Y900000D03*
X1417284Y911009D03*
X1416802Y936845D03*
X1416244Y942285D03*
X1419337D03*
X1405214Y965074D03*
X1419446Y977192D03*
X1416618Y992307D03*
X1401265Y989465D03*
X1407265D03*
X1414143Y985486D03*
X1412698Y997590D03*
X1412609Y1008766D03*
X1412759Y1016266D03*
X1402215Y1020440D03*
X1414851Y1058097D03*
X1412351D03*
X1407351D03*
X1409851D03*
X1417351D03*
X1414851Y1060697D03*
X1412351D03*
X1407351D03*
X1409851D03*
X1417351D03*
X1405677Y1086796D03*
X1408177D03*
X1410677D03*
X1413177D03*
X1415677D03*
Y1084296D03*
X1413177D03*
X1410677D03*
X1408177D03*
X1405677D03*
X1416005Y1090288D03*
X1410546Y1106298D03*
X1404821Y1101917D03*
X1404756Y1106897D03*
X1416005Y1093088D03*
X1414584Y1107997D03*
X1411237Y1115896D03*
X1407571Y1110092D03*
X1414584Y1113797D03*
X1416784Y1112397D03*
X1414584Y1110897D03*
X1416684Y1109397D03*
X1411237Y1118396D03*
X1409425Y1129238D03*
X1413177Y1128894D03*
X1409492Y1167384D03*
Y1169884D03*
Y1172384D03*
X1406992D03*
Y1169884D03*
X1416550Y1162384D03*
Y1164884D03*
Y1167384D03*
Y1169884D03*
Y1172384D03*
X1406992Y1167384D03*
Y1164884D03*
Y1162384D03*
X1409492D03*
Y1164884D03*
X1416736Y1158200D03*
X1416550Y1174884D03*
X1409492D03*
X1406992D03*
X1407995Y1179421D03*
Y1181921D03*
Y1184421D03*
Y1186921D03*
X1410310Y1192621D03*
Y1190121D03*
X1404845D03*
Y1192621D03*
X1408736Y1222194D03*
X1412736D03*
X1416736D03*
X1408736Y1238194D03*
Y1234194D03*
Y1230194D03*
Y1226194D03*
X1412736Y1238194D03*
Y1234194D03*
Y1230194D03*
Y1226194D03*
X1416736Y1238194D03*
Y1234194D03*
Y1230194D03*
Y1226194D03*
X1412736Y1246194D03*
Y1242194D03*
X1416736Y1246194D03*
Y1242194D03*
X1408736D03*
Y1246194D03*
X1409821Y1260160D03*
X1412821D03*
Y1257160D03*
X1409821D03*
X1406821D03*
X1403821D03*
X1415821Y1260160D03*
Y1257160D03*
X1403821Y1260160D03*
X1406821D03*
X1417711Y1301729D03*
X1410817Y1305417D03*
X1407825Y1426975D03*
X1408536Y1536570D03*
X1407747Y1549054D03*
X1408044Y1559306D03*
X1407255Y1571732D03*
X1422810Y90615D03*
X1427131Y99961D03*
X1427181Y95236D03*
X1425993Y212978D03*
Y207978D03*
Y210478D03*
Y215478D03*
X1429322Y264180D03*
X1431822D03*
X1429247Y258880D03*
X1434166Y325361D03*
X1434164Y339232D03*
X1434038Y334114D03*
X1435818Y352361D03*
X1421005Y407616D03*
X1417903Y439919D03*
X1434997Y442603D03*
X1427117Y443071D03*
X1423427Y456839D03*
X1425927D03*
X1423427Y454339D03*
X1425927D03*
X1432414Y459371D03*
X1423427Y459339D03*
X1425927D03*
X1418903Y469905D03*
X1431484Y470045D03*
X1427484Y462004D03*
X1422499Y485138D03*
X1419650Y485128D03*
X1426384Y478625D03*
X1428084Y482425D03*
X1427499Y485138D03*
X1424999D03*
X1426384Y476125D03*
X1418253Y529169D03*
X1417668Y531882D03*
X1424129Y537658D03*
X1427832Y539731D03*
X1424129Y540458D03*
X1432590Y544895D03*
X1435390D03*
X1427832Y542231D03*
X1432890Y541895D03*
X1417903Y555194D03*
Y563194D03*
Y571194D03*
X1422260Y581222D03*
X1419460D03*
X1435119Y590801D03*
X1422260Y591215D03*
X1419460D03*
X1431000Y591000D03*
X1434944Y597130D03*
X1433114Y620653D03*
Y617853D03*
X1419632Y607762D03*
X1422432D03*
X1425232Y610562D03*
Y607762D03*
X1422432Y610562D03*
X1419632D03*
X1430944Y605443D03*
X1420452Y628078D03*
X1430175Y627852D03*
X1425452Y633473D03*
X1430481Y658153D03*
X1433529Y660564D03*
X1426615Y674112D03*
X1429000Y685000D03*
X1418000D03*
Y681000D03*
X1425909Y691120D03*
X1433464Y692658D03*
X1418000Y689000D03*
X1433053Y701839D03*
X1426000Y717000D03*
X1418000Y705000D03*
X1431522Y708633D03*
X1434000Y712958D03*
X1430289Y734961D03*
X1418000Y733000D03*
X1417969Y720894D03*
X1429000Y729000D03*
X1434000Y751958D03*
X1433153Y745839D03*
X1427000Y766500D03*
X1426000Y761000D03*
X1435000Y765500D03*
X1434000Y756958D03*
X1418023Y765343D03*
X1427000Y781834D03*
Y770500D03*
X1435000D03*
X1427000Y794500D03*
X1435000Y802500D03*
X1427000Y810500D03*
Y814500D03*
X1435000D03*
Y809500D03*
X1427000Y802500D03*
Y830500D03*
Y826500D03*
X1434975Y830500D03*
X1435000Y825500D03*
X1427000Y842500D03*
Y838500D03*
X1435000Y846500D03*
X1427000D03*
X1435043Y874694D03*
X1435082Y869475D03*
X1423190Y905295D03*
X1429059Y908579D03*
X1426085Y910281D03*
X1429907Y936998D03*
X1424897Y936777D03*
X1435516Y936000D03*
X1420699Y958452D03*
X1430839Y965546D03*
X1420740Y1008766D03*
X1428740Y1000766D03*
X1420740Y996766D03*
X1428864D03*
X1420740Y1012266D03*
X1428740Y1016266D03*
X1428823Y1020266D03*
X1435229Y1104335D03*
X1432671Y1105552D03*
X1428877Y1104792D03*
X1418784Y1107997D03*
X1430384Y1106867D03*
X1418884Y1110597D03*
X1421120Y1116101D03*
Y1118801D03*
X1426469Y1113648D03*
X1423969D03*
X1419669D03*
X1419050Y1162384D03*
Y1164884D03*
Y1167384D03*
Y1169884D03*
Y1172384D03*
Y1174884D03*
X1420625Y1186709D03*
Y1184209D03*
Y1181709D03*
Y1179209D03*
X1418310Y1192621D03*
Y1190121D03*
X1420736Y1222194D03*
X1424736D03*
X1428736D03*
X1432736D03*
X1420736Y1238194D03*
Y1234194D03*
Y1230194D03*
Y1226194D03*
X1424736Y1238194D03*
Y1234194D03*
Y1230194D03*
Y1226194D03*
X1428736Y1238194D03*
Y1234194D03*
Y1230194D03*
Y1226194D03*
X1432736Y1234194D03*
Y1230194D03*
Y1226194D03*
X1420736Y1246194D03*
Y1242194D03*
X1424736Y1246194D03*
Y1242194D03*
X1428736Y1246194D03*
Y1242194D03*
X1421821Y1257160D03*
X1418821D03*
Y1260160D03*
X1421821D03*
X1431080Y1301702D03*
X1421238Y1301712D03*
X1428009Y1301760D03*
X1424732Y1301603D03*
X1432258Y1414600D03*
X1430374Y1492474D03*
X1420877Y1494706D03*
X1421964Y1502813D03*
X1423930Y1520364D03*
X1429587Y1527450D03*
X1433405Y1546001D03*
X1432913Y1568679D03*
X1449685Y34228D03*
X1436045Y77393D03*
Y74793D03*
Y85193D03*
Y82593D03*
Y79993D03*
X1444370Y98551D03*
X1436089Y92874D03*
X1447265Y111223D03*
Y114623D03*
X1447920Y103783D03*
X1438116Y107649D03*
Y104249D03*
X1447265Y125396D03*
Y128796D03*
X1442682Y147540D03*
X1446454Y141247D03*
X1451301Y148277D03*
X1435138Y162368D03*
X1437738D03*
X1444838Y162793D03*
Y165393D03*
Y170493D03*
Y167993D03*
X1451762Y177616D03*
X1449841Y181009D03*
X1447046Y181366D03*
X1443835Y181426D03*
X1444043Y184221D03*
X1446660Y184012D03*
X1448079Y211359D03*
Y213859D03*
X1436449Y213213D03*
Y210713D03*
X1440521Y211695D03*
X1443021D03*
X1440521Y208695D03*
X1443321D03*
X1436449Y208213D03*
Y215713D03*
X1451785Y265896D03*
X1446698Y265701D03*
X1441016Y267526D03*
Y270026D03*
X1443516D03*
X1438216D03*
X1443516Y267526D03*
X1438216D03*
X1448333Y281716D03*
X1449060Y329861D03*
X1448948Y326448D03*
X1449060Y320861D03*
X1438829Y329861D03*
X1437064Y320861D03*
X1448822Y345324D03*
X1448734Y332910D03*
X1448500Y340575D03*
X1439712Y336673D03*
X1440420Y346833D03*
X1449060Y356861D03*
X1441180Y354909D03*
X1448572Y349441D03*
X1449060Y352361D03*
X1447502Y360785D03*
X1434697Y347125D03*
X1439719Y350387D03*
X1443041Y363648D03*
X1434608Y362584D03*
X1438768Y371655D03*
X1442633Y371502D03*
X1445906Y366030D03*
X1440523Y382747D03*
X1435424Y430361D03*
X1440390Y456652D03*
X1442890D03*
Y459152D03*
Y461652D03*
X1440390Y459152D03*
Y461652D03*
X1436930Y461818D03*
X1433960Y491214D03*
X1449293Y491133D03*
X1442721Y495151D03*
X1437663Y492987D03*
X1442421Y498151D03*
X1433960Y493714D03*
X1437663Y495487D03*
X1445221Y498151D03*
X1449293Y493633D03*
Y496133D03*
Y498633D03*
X1445221Y495151D03*
X1439462Y537877D03*
X1449393Y553297D03*
Y555897D03*
X1446988Y548418D03*
X1439462Y540377D03*
X1435390Y541895D03*
X1444488Y548418D03*
X1439488D03*
X1441988D03*
X1439462Y542877D03*
Y545377D03*
X1449393Y558497D03*
Y566797D03*
Y563697D03*
Y561097D03*
X1443388Y570686D03*
X1446183Y570478D03*
X1435668Y582747D03*
X1446600Y576484D03*
X1446243Y573689D03*
X1443597Y573303D03*
X1449993Y578405D03*
X1438944Y597232D03*
X1443775Y596089D03*
X1448994Y596782D03*
X1440930Y613913D03*
Y616713D03*
Y619513D03*
X1434944Y605443D03*
X1438944Y605637D03*
X1437790Y625013D03*
X1435952Y642184D03*
X1446323Y673183D03*
X1437738Y686992D03*
X1448991Y694392D03*
X1451976Y693844D03*
X1437533Y704398D03*
Y699280D03*
X1438930Y716363D03*
X1446860Y730735D03*
X1446538Y719548D03*
X1437738Y730992D03*
X1446717Y735536D03*
X1437533Y743280D03*
Y748398D03*
X1447289Y776461D03*
X1446000Y770500D03*
X1451000Y793458D03*
Y798458D03*
X1450253Y787339D03*
X1443000Y802500D03*
X1447000Y810500D03*
Y818500D03*
X1435000D03*
X1448000Y834500D03*
X1443000Y846500D03*
X1435000Y834500D03*
X1449000Y844500D03*
X1435212Y854042D03*
X1448726Y864400D03*
X1439891Y873821D03*
X1445367Y891888D03*
X1441223Y891957D03*
X1435745Y901500D03*
X1443231Y899006D03*
X1439103Y898564D03*
X1447261Y898571D03*
X1446022Y927000D03*
X1448137Y949440D03*
X1439031Y957683D03*
X1441088Y976409D03*
X1433996Y981437D03*
X1440700Y981763D03*
X1435669Y1005366D03*
X1440869Y1010256D03*
X1435197Y1028372D03*
X1442674Y1106365D03*
X1436949Y1101917D03*
X1436884Y1106897D03*
X1439699Y1110092D03*
X1443365Y1115896D03*
Y1118396D03*
X1442448Y1160834D03*
X1434820Y1162384D03*
Y1164884D03*
Y1167384D03*
Y1169884D03*
Y1172384D03*
X1437320D03*
Y1169884D03*
Y1167384D03*
Y1164884D03*
Y1162384D03*
X1434925Y1179421D03*
Y1181921D03*
Y1184421D03*
Y1186921D03*
X1434820Y1174884D03*
X1437320D03*
X1437240Y1192621D03*
Y1190121D03*
X1436736Y1222194D03*
Y1226194D03*
X1443660Y1310698D03*
X1440260D03*
X1446817Y1335846D03*
X1441200Y1338700D03*
X1435900Y1340800D03*
X1439258Y1414600D03*
X1446135Y1530876D03*
X1443103Y1527201D03*
X1441145Y1540415D03*
X1440153Y1563093D03*
X1443769Y1562173D03*
X1452717Y34052D03*
X1457347Y31518D03*
X1457829Y26425D03*
X1455013Y43128D03*
X1460466Y76587D03*
Y72615D03*
X1461905Y100625D03*
X1454924Y97475D03*
X1454855Y106186D03*
X1457667Y118335D03*
Y121735D03*
Y132509D03*
Y135909D03*
X1462484Y141247D03*
X1466971Y143518D03*
X1453921Y143740D03*
X1466071Y152373D03*
X1455016Y168697D03*
X1452343Y172190D03*
X1464628Y171523D03*
X1456104Y191941D03*
X1464158Y192490D03*
X1458113Y206767D03*
X1463113D03*
X1460613D03*
X1451782Y213132D03*
X1463243Y221708D03*
X1460743D03*
X1458243D03*
X1457658Y224421D03*
X1459358Y231021D03*
Y228221D03*
X1451782Y215632D03*
X1459909Y236189D03*
X1464909D03*
X1462409D03*
X1459850Y248765D03*
X1464850D03*
X1462350D03*
X1452026Y256303D03*
X1456801Y266114D03*
X1460047Y270695D03*
Y268195D03*
X1462547Y270695D03*
Y268195D03*
X1465347Y270695D03*
Y268195D03*
X1454274Y281982D03*
X1459060Y320861D03*
Y325361D03*
Y329861D03*
Y338861D03*
Y343361D03*
Y334361D03*
Y347861D03*
Y352361D03*
X1459873Y391705D03*
X1463145Y391579D03*
X1458214Y406231D03*
X1464536Y433114D03*
X1458912Y581659D03*
X1455419Y578986D03*
X1454944Y596729D03*
X1453000Y614158D03*
Y616958D03*
Y619758D03*
X1450944Y605443D03*
X1458944D03*
X1461474Y655807D03*
X1455761Y683448D03*
X1468372Y673812D03*
X1460111Y683536D03*
X1451428Y673252D03*
X1460816Y727964D03*
X1455291Y759656D03*
X1455159Y763714D03*
X1454504Y777575D03*
X1454533Y784780D03*
X1454738Y772492D03*
X1454533Y789898D03*
X1453102Y821102D03*
X1454541Y831339D03*
X1453102Y826500D03*
X1452619Y836457D03*
X1461113Y871389D03*
X1457218Y888764D03*
X1452641Y888033D03*
X1451286Y898549D03*
X1462500Y905295D03*
X1461888Y936055D03*
X1462000Y957000D03*
X1458202Y960288D03*
X1457937Y966712D03*
X1457352Y976277D03*
X1459519Y989432D03*
X1467096Y988813D03*
X1456966Y998507D03*
X1458892Y1007522D03*
X1465658Y1006648D03*
X1465846Y1023900D03*
X1463025Y1018307D03*
X1459267Y1013678D03*
X1456280Y1023405D03*
X1459683Y1028377D03*
X1479972Y40780D03*
X1472146Y55513D03*
X1468371Y68581D03*
X1474746Y60513D03*
X1477606Y60438D03*
X1468384Y80581D03*
X1474874Y85731D03*
X1483287Y86012D03*
X1472514Y88801D03*
X1478428Y86046D03*
X1475431Y94351D03*
X1479380Y94279D03*
X1470567Y103621D03*
X1478624Y116594D03*
X1466278Y112083D03*
X1484567Y110784D03*
X1478624Y119594D03*
X1479058Y124283D03*
X1484124Y124879D03*
X1477465Y161306D03*
X1469221Y152562D03*
X1474716Y157370D03*
X1478800Y168665D03*
Y176665D03*
X1469913Y183834D03*
X1470023Y178560D03*
X1470086Y172665D03*
X1470899Y186629D03*
X1469433Y190185D03*
X1478800Y192665D03*
Y196665D03*
X1470203Y200864D03*
X1478913Y186778D03*
X1478832Y204864D03*
X1470292Y212455D03*
X1470226Y207037D03*
X1478832Y208864D03*
X1467593Y221642D03*
X1474473Y219379D03*
X1475101Y228631D03*
X1480589Y248371D03*
X1471507Y265897D03*
X1469007D03*
X1477549Y327200D03*
Y322700D03*
Y345200D03*
Y340700D03*
Y331700D03*
Y358700D03*
Y349700D03*
Y354200D03*
X1480702Y368516D03*
X1468309Y408861D03*
X1475236Y412482D03*
X1466231Y423671D03*
X1469538Y416795D03*
X1466653Y428582D03*
X1471375Y433115D03*
X1477597Y682997D03*
X1475264Y680933D03*
X1474713Y685247D03*
X1479297Y693630D03*
X1476794Y691447D03*
X1476716Y704398D03*
X1479500Y689630D03*
Y697630D03*
X1474425Y712925D03*
X1479759Y720885D03*
X1469957Y706957D03*
X1474000Y707000D03*
X1479794Y709388D03*
X1472000Y727500D03*
X1469116Y719055D03*
X1480000Y731500D03*
X1479759Y743500D03*
X1479657Y735500D03*
X1469957Y750957D03*
X1476716Y748398D03*
X1480000Y739500D03*
X1471006Y744818D03*
X1470801Y739280D03*
X1474425Y756925D03*
X1479665Y754555D03*
X1474000Y753093D03*
X1476677Y827626D03*
X1473489Y861354D03*
X1474060Y877196D03*
X1473468Y874267D03*
X1482387Y872940D03*
X1474883Y868206D03*
X1473433Y891043D03*
X1473387Y897425D03*
X1482195Y885807D03*
X1470925Y920575D03*
X1480343Y914776D03*
X1480109Y943496D03*
X1480144Y946880D03*
X1479441Y961941D03*
X1480414Y952214D03*
X1476500Y974000D03*
X1482237Y966028D03*
X1479196Y970000D03*
X1480414Y975064D03*
X1475096Y980330D03*
X1471096D03*
X1479096Y988813D03*
X1471296D03*
X1475096D03*
X1483096D03*
X1475062Y1008300D03*
Y1002453D03*
X1482535Y1024254D03*
X1468869Y1018469D03*
X1476230Y1030672D03*
X1473230D03*
X1471374Y1118654D03*
X1474384Y1109564D03*
X1480231D03*
X1474384Y1122164D03*
X1480231D03*
X1474384Y1134764D03*
X1480231D03*
X1474384Y1147364D03*
X1480231D03*
X1474384Y1172564D03*
X1480231D03*
X1474384Y1159964D03*
X1480231D03*
X1474384Y1185164D03*
X1480231D03*
X1483308Y1214372D03*
X1479063Y1218169D03*
X1498621Y19043D03*
X1489556Y17645D03*
X1498621Y31043D03*
Y23043D03*
X1489829Y29424D03*
X1490563Y23043D03*
X1500210Y97667D03*
X1483287Y94374D03*
X1490593Y116594D03*
X1495866Y102495D03*
X1489567Y110784D03*
X1490593Y119594D03*
X1494127Y125107D03*
X1489146Y124663D03*
X1495600Y142862D03*
X1496641Y148717D03*
X1490490Y138838D03*
X1493260Y226320D03*
X1493194Y221970D03*
X1490481Y216385D03*
X1493194Y216970D03*
Y219470D03*
X1486681Y218085D03*
X1483881D03*
X1496221Y228646D03*
X1495178Y232971D03*
X1491828Y244571D03*
X1489208Y249108D03*
X1499171Y256394D03*
X1497446Y295877D03*
X1486860Y327200D03*
X1500659Y330024D03*
X1495605Y322700D03*
X1487318Y318200D03*
X1486360Y322700D03*
Y345200D03*
X1500386Y344642D03*
X1486913Y340327D03*
X1487152Y331272D03*
X1495689Y332534D03*
X1495521Y340700D03*
X1486360Y349700D03*
X1495521Y349681D03*
X1495925Y358700D03*
X1499839Y354001D03*
X1486890Y368576D03*
X1494286Y372699D03*
X1488000Y731500D03*
X1495500Y750500D03*
X1488731Y739500D03*
X1496629Y765000D03*
X1496763Y777000D03*
X1493301Y776911D03*
X1496814Y773000D03*
X1497000Y781000D03*
X1496756Y785000D03*
X1491425Y798425D03*
X1499633Y787794D03*
X1493716Y789898D03*
X1486957Y792457D03*
X1495170Y796670D03*
X1487050Y809413D03*
X1496845Y809000D03*
X1496806Y817000D03*
X1496621Y829000D03*
X1496447Y821000D03*
X1486386Y825296D03*
X1493092Y820444D03*
X1493038Y833898D03*
X1495240Y825000D03*
X1491425Y842425D03*
X1486957Y836457D03*
X1492625Y837324D03*
X1488138Y878339D03*
Y872839D03*
X1482566Y882154D03*
X1494954Y895264D03*
X1484824Y927324D03*
X1487240Y924453D03*
X1497063Y934000D03*
X1496072Y940201D03*
X1483324Y939324D03*
X1482921Y931324D03*
X1485500Y932500D03*
X1497075Y961000D03*
X1487240Y952012D03*
X1496072Y953981D03*
X1495500Y972500D03*
X1489500D03*
X1487096Y988813D03*
X1491096D03*
X1495096D03*
X1499096D03*
X1490235Y1004816D03*
X1487266Y1002046D03*
X1486030Y1016827D03*
X1491877D03*
X1486030Y1029427D03*
X1491877D03*
X1496140Y1105091D03*
X1496185Y1102091D03*
X1496140Y1117691D03*
X1496185Y1114691D03*
Y1127291D03*
X1496140Y1130291D03*
X1496185Y1139891D03*
X1496140Y1155491D03*
Y1142891D03*
X1496185Y1152491D03*
X1496140Y1168091D03*
X1496185Y1165091D03*
X1496140Y1180691D03*
X1496185Y1177691D03*
X1482705Y1200001D03*
X1489793Y1207737D03*
X1497693Y1230407D03*
X1508670Y103411D03*
X1509064Y97667D03*
X1504460Y95111D03*
X1508829Y106561D03*
X1502741Y143762D03*
X1506689Y195176D03*
X1506207Y199248D03*
X1501689Y195176D03*
X1503207Y199248D03*
X1499189Y195176D03*
X1504189D03*
X1506207Y202048D03*
X1503207Y201748D03*
X1499270Y210509D03*
X1501043Y206806D03*
X1501770Y210509D03*
X1503543Y206806D03*
X1509807Y230117D03*
X1500962Y230556D03*
X1505217Y227824D03*
X1505823Y238714D03*
X1499947Y242078D03*
X1505304Y246874D03*
X1507524Y244297D03*
X1503884Y295549D03*
X1501500Y321000D03*
X1501000Y317500D03*
X1501684Y336561D03*
X1516838Y347422D03*
X1515909Y354601D03*
X1511950Y401513D03*
Y398113D03*
X1509550Y412287D03*
Y415687D03*
Y426460D03*
Y440633D03*
Y429860D03*
Y444033D03*
X1516636Y458711D03*
X1509550Y472787D03*
Y469387D03*
Y483560D03*
Y486960D03*
Y516921D03*
Y513521D03*
Y527694D03*
Y531094D03*
X1513284Y552466D03*
X1504495Y796844D03*
X1510527Y833500D03*
X1504938Y859711D03*
X1500353Y859855D03*
X1500638Y873839D03*
X1512712Y867418D03*
X1502158Y899479D03*
X1510527Y908951D03*
X1513927D03*
X1504208Y909740D03*
X1509274Y921226D03*
X1505337Y921240D03*
X1509500Y937000D03*
Y944138D03*
X1516500Y947500D03*
X1501812Y938397D03*
X1512161Y957541D03*
X1509500Y950500D03*
X1498973Y975443D03*
X1511000Y970500D03*
X1511096Y988813D03*
X1507096D03*
X1503096D03*
X1515096D03*
X1513286Y1012354D03*
X1507831Y1009354D03*
X1507786Y1012354D03*
Y1024954D03*
X1513286D03*
X1507831Y1021954D03*
X1503572Y1034538D03*
X1501640Y1105091D03*
Y1117691D03*
Y1130291D03*
Y1142891D03*
Y1155491D03*
Y1168091D03*
Y1180691D03*
X1508356Y1220068D03*
X1500675Y1227300D03*
X1506807Y1234921D03*
X1507692Y1224472D03*
X1507058Y1229402D03*
X1525172Y90615D03*
X1519860Y90650D03*
X1529493Y99961D03*
X1529543Y95236D03*
X1519610D03*
X1528355Y210478D03*
Y215478D03*
Y212978D03*
Y207978D03*
X1519321Y378600D03*
X1519952Y391001D03*
X1519321Y382600D03*
X1519952Y394401D03*
Y408574D03*
Y405174D03*
Y422747D03*
Y419347D03*
Y436921D03*
Y433521D03*
X1519436Y458711D03*
X1521963Y453682D03*
X1520200Y455921D03*
X1518780Y463600D03*
X1519952Y479899D03*
Y476499D03*
Y490673D03*
Y494073D03*
Y520633D03*
Y524033D03*
Y534806D03*
Y538206D03*
X1519185Y603600D03*
Y619600D03*
Y623600D03*
X1520729Y634190D03*
X1524200Y646098D03*
X1518517Y878898D03*
X1518452Y873780D03*
X1525022Y909558D03*
X1522881Y901034D03*
X1522954Y897951D03*
X1521085Y921094D03*
X1515179D03*
X1527267Y932647D03*
X1522209Y937846D03*
X1521500Y947500D03*
X1528500Y947612D03*
X1529128Y952978D03*
X1521085Y957340D03*
X1525583Y968500D03*
X1530767Y972981D03*
X1519863Y977637D03*
X1525005Y974323D03*
X1530594Y979952D03*
X1531096Y988813D03*
X1523096D03*
X1519096D03*
X1527096Y997860D03*
X1526810Y1025090D03*
X1522904Y1021256D03*
X1521939Y1040818D03*
X1522099Y1035521D03*
X1531993Y1056453D03*
X1531961Y1050849D03*
X1524953Y1051037D03*
X1517855Y1053457D03*
X1538407Y85539D03*
Y82939D03*
Y75139D03*
Y80339D03*
Y77739D03*
X1546732Y98551D03*
X1538451Y92874D03*
X1540478Y107649D03*
Y104249D03*
X1545044Y147540D03*
X1540100Y162368D03*
X1537500D03*
X1547200Y162793D03*
Y165393D03*
Y167993D03*
Y170493D03*
X1546197Y181426D03*
X1546405Y184221D03*
X1538811Y213213D03*
Y210713D03*
X1542883Y211695D03*
X1545383D03*
X1542883Y208695D03*
X1545683D03*
X1538811Y208213D03*
Y215713D03*
X1534184Y264180D03*
X1531684D03*
X1531609Y258880D03*
X1549060Y265701D03*
X1545878Y270026D03*
X1543378D03*
X1540578D03*
X1543378Y267526D03*
X1540578D03*
X1545878D03*
X1544736Y305156D03*
X1545583Y316363D03*
X1539140Y320863D03*
X1545636Y325363D03*
X1542797Y329863D03*
X1545846Y334363D03*
X1544951Y343363D03*
X1538133Y354553D03*
X1545434Y352363D03*
X1546183Y541863D03*
Y545263D03*
X1544375Y553407D03*
X1546875D03*
X1544375Y550907D03*
X1546875D03*
X1542704Y572162D03*
X1543946Y569928D03*
X1546293Y570962D03*
X1546036Y568475D03*
X1548080Y910757D03*
X1547644Y903060D03*
X1532067Y1041832D03*
X1531947Y1046212D03*
X1531546Y1062769D03*
X1536909Y1151870D03*
Y1159350D03*
X1540649Y1155610D03*
X1562828Y72615D03*
Y76587D03*
X1564267Y100625D03*
X1557286Y97475D03*
X1549627Y111223D03*
Y114623D03*
X1557217Y106186D03*
X1550282Y103783D03*
X1549627Y128796D03*
X1560029Y132509D03*
Y121735D03*
Y118335D03*
X1549627Y125396D03*
X1560029Y135909D03*
X1548816Y141247D03*
X1564846D03*
X1556283Y143740D03*
X1553663Y148277D03*
X1552203Y181009D03*
X1549408Y181366D03*
X1557378Y168697D03*
X1554705Y172190D03*
X1554124Y177616D03*
X1558466Y191941D03*
X1549022Y184012D03*
X1560475Y206767D03*
X1562975D03*
X1554144Y213132D03*
X1550441Y211359D03*
Y213859D03*
X1560605Y221708D03*
X1560020Y224421D03*
X1563105Y221708D03*
X1561720Y231021D03*
Y228221D03*
X1554144Y215632D03*
X1562271Y236189D03*
X1562212Y248765D03*
X1554388Y256303D03*
X1559163Y266114D03*
X1554147Y265896D03*
X1562409Y268195D03*
Y270695D03*
X1556636Y281982D03*
X1550695Y281716D03*
X1550931Y305158D03*
X1554403Y316363D03*
X1553534Y327337D03*
X1553910Y331798D03*
X1553597Y336601D03*
X1553862Y344867D03*
X1551175Y347283D03*
X1556588Y545528D03*
X1548359Y569426D03*
X1548645Y566929D03*
X1562385Y610400D03*
X1564670Y650122D03*
X1565132Y668153D03*
X1561552Y665455D03*
X1548629Y927836D03*
X1548504Y915689D03*
X1548616Y931602D03*
X1551163Y952888D03*
X1552000Y969850D03*
X1571895Y58013D03*
X1570733Y68581D03*
X1577108Y60513D03*
X1570746Y80581D03*
X1577236Y85731D03*
X1574876Y88801D03*
X1581742Y94279D03*
X1577793Y94351D03*
X1572929Y103621D03*
X1568640Y112083D03*
X1581420Y124283D03*
X1569333Y143518D03*
X1568433Y152373D03*
X1579827Y161306D03*
X1571583Y152562D03*
X1577078Y157370D03*
X1572275Y183834D03*
X1566990Y171523D03*
X1572385Y178560D03*
X1572448Y172665D03*
X1573261Y186629D03*
X1571795Y190185D03*
X1566520Y192490D03*
X1572565Y200864D03*
X1565475Y206767D03*
X1572654Y212455D03*
X1572588Y207037D03*
X1581194Y208864D03*
X1565605Y221708D03*
X1569955Y221642D03*
X1576835Y219379D03*
X1577463Y228631D03*
X1564771Y236189D03*
X1567271D03*
X1564712Y248765D03*
X1567212D03*
X1567709Y270695D03*
X1573869Y265897D03*
X1571369D03*
X1567709Y268195D03*
X1564909Y270695D03*
Y268195D03*
X1563877Y325363D03*
Y316363D03*
X1571625Y344131D03*
X1574775Y333549D03*
X1563877Y329863D03*
Y343363D03*
Y334363D03*
X1578587Y341787D03*
X1578420Y338309D03*
X1574775Y344127D03*
X1563877Y352363D03*
X1575935Y382109D03*
X1577862Y554121D03*
X1575934Y561420D03*
Y558917D03*
X1565323Y577716D03*
X1571755Y577937D03*
X1579760Y595500D03*
X1574760Y606929D03*
X1579260Y604567D03*
X1574720Y618400D03*
X1575001Y612592D03*
X1580418Y610072D03*
X1580354Y616317D03*
X1576297Y627600D03*
X1577077Y631712D03*
X1574880Y645891D03*
X1571888Y649380D03*
X1572141Y662981D03*
X1578000Y678776D03*
X1569434Y677111D03*
X1568872Y686971D03*
X1575192Y707592D03*
X1592187Y-69306D03*
Y-72706D03*
X1582187Y-33786D03*
Y-30386D03*
X1579968Y60438D03*
X1585649Y86012D03*
Y94374D03*
X1580790Y86046D03*
X1592955Y116594D03*
X1580986D03*
X1586929Y110784D03*
X1591929D03*
X1592955Y119594D03*
X1580986D03*
X1596489Y125107D03*
X1586486Y124879D03*
X1591508Y124663D03*
X1592852Y138838D03*
X1581162Y168665D03*
Y176665D03*
Y192665D03*
Y196665D03*
X1581275Y186778D03*
X1581194Y204864D03*
X1586243Y218085D03*
X1595622Y226320D03*
X1592843Y216385D03*
X1595556Y216970D03*
Y219470D03*
Y221970D03*
X1589043Y218085D03*
X1594190Y244571D03*
X1591570Y249108D03*
X1582951Y248371D03*
X1595069Y337361D03*
X1595109Y342663D03*
X1594466Y350984D03*
X1592635Y455911D03*
X1591443Y465332D03*
X1595460Y549800D03*
X1595260Y547075D03*
X1594760Y568000D03*
X1595364Y562800D03*
X1595300Y558800D03*
X1596790Y1442557D03*
X1592643Y1460707D03*
X1593019Y1457557D03*
X1591775Y1473090D03*
X1596038Y1492000D03*
X1591925Y1512075D03*
X1591333Y1501980D03*
X1590748Y1523377D03*
X1602572Y97667D03*
X1611032Y103411D03*
X1611426Y97667D03*
X1606822Y95111D03*
X1598228Y102495D03*
X1611191Y106561D03*
X1597962Y142862D03*
X1605103Y143762D03*
X1599003Y148717D03*
X1604051Y195176D03*
X1605569Y199248D03*
X1601551Y195176D03*
X1606551D03*
X1609051D03*
X1608569Y199248D03*
X1603405Y206806D03*
X1605905D03*
X1601632Y210509D03*
X1604132D03*
X1608569Y202048D03*
X1605569Y201748D03*
X1603324Y230556D03*
X1607579Y227824D03*
X1612169Y230117D03*
X1598583Y228646D03*
X1608185Y238714D03*
X1602309Y242078D03*
X1607666Y246874D03*
X1597540Y232971D03*
X1609886Y244297D03*
X1604677Y253198D03*
X1596691Y287397D03*
X1596197Y293477D03*
X1607947Y332326D03*
X1605966Y343794D03*
X1602138Y351047D03*
X1596253Y375633D03*
X1596534Y379760D03*
X1599527Y396718D03*
X1596760Y530000D03*
X1596260Y540500D03*
X1611316Y685800D03*
X1611027Y722427D03*
X1611327Y735973D03*
X1611627Y780327D03*
X1609500Y776100D03*
X1611873Y795127D03*
X1606190Y803774D03*
X1606709Y819165D03*
X1600333Y1440504D03*
X1596836Y1446488D03*
X1600333Y1449068D03*
X1601968Y1453442D03*
X1597457Y1460662D03*
X1605430Y1468023D03*
X1597039Y1475100D03*
X1599726Y1474990D03*
X1600008Y1488492D03*
X1601500Y1514500D03*
X1608500Y1506000D03*
Y1515000D03*
X1613790Y1531334D03*
X1609348Y1527334D03*
X1613790Y1523334D03*
X1604000Y1519000D03*
X1600732Y1539334D03*
X1609348Y1535334D03*
X1598574Y1543373D03*
X1622222Y90650D03*
X1627534Y90615D03*
X1621972Y95236D03*
X1626147Y351033D03*
X1628636Y422088D03*
X1623955Y442956D03*
X1625772Y438323D03*
X1621596Y456386D03*
X1625938Y445873D03*
X1620385Y465874D03*
X1616622Y546712D03*
Y542712D03*
X1618538Y618288D03*
X1614538D03*
X1627224Y643252D03*
X1613362Y656321D03*
X1621362D03*
X1617362D03*
X1616260Y678462D03*
X1619950Y678519D03*
X1615913Y692245D03*
X1628200Y711417D03*
X1612800Y705900D03*
X1620600D03*
X1620500Y723200D03*
X1628343Y747288D03*
X1616683Y744517D03*
X1620100Y738300D03*
X1624000Y760900D03*
X1612573Y761427D03*
X1628027Y801427D03*
X1613117Y828117D03*
X1640769Y85539D03*
Y82939D03*
Y75139D03*
Y80339D03*
Y77739D03*
X1640813Y92874D03*
X1631905Y95236D03*
X1631855Y99961D03*
X1642840Y104249D03*
Y107649D03*
X1639862Y162368D03*
X1642462D03*
X1641173Y213213D03*
Y210713D03*
Y208213D03*
X1630717Y210478D03*
Y215478D03*
Y212978D03*
Y207978D03*
X1641173Y215713D03*
X1634046Y264180D03*
X1636546D03*
X1633971Y258880D03*
X1642940Y267526D03*
Y270026D03*
X1629553Y329067D03*
X1629302Y334402D03*
X1640030Y335550D03*
X1636561Y343072D03*
X1629514Y331727D03*
X1630691Y347432D03*
X1640197Y374690D03*
X1638340Y379536D03*
X1641615Y379600D03*
X1635170Y442856D03*
X1632439Y452265D03*
X1633225Y458455D03*
X1636271Y453881D03*
X1635185Y446595D03*
X1635283Y728117D03*
X1630327Y774627D03*
X1629927Y787327D03*
X1644552Y871353D03*
X1635176Y886761D03*
X1644718Y909263D03*
X1635000Y919263D03*
X1644325Y942120D03*
X1637771Y952120D03*
X1640581Y1551907D03*
X1649094Y98551D03*
X1659648Y97475D03*
X1651989Y114623D03*
Y111223D03*
X1652644Y103783D03*
X1659579Y106186D03*
X1651989Y125396D03*
Y128796D03*
X1647406Y147540D03*
X1651178Y141247D03*
X1658645Y143740D03*
X1656025Y148277D03*
X1649562Y162793D03*
Y165393D03*
Y167993D03*
Y170493D03*
X1656486Y177616D03*
X1654565Y181009D03*
X1648559Y181426D03*
X1651770Y181366D03*
X1659740Y168697D03*
X1657067Y172190D03*
X1660828Y191941D03*
X1651384Y184012D03*
X1648767Y184221D03*
X1647745Y211695D03*
X1645245Y208695D03*
X1648045D03*
X1656506Y213132D03*
X1652803Y211359D03*
Y213859D03*
X1645245Y211695D03*
X1656506Y215632D03*
X1656750Y256303D03*
X1656509Y265896D03*
X1661525Y266114D03*
X1651422Y265701D03*
X1648240Y267526D03*
X1645740D03*
Y270026D03*
X1648240D03*
X1653057Y281716D03*
X1658998Y281982D03*
X1658200Y315039D03*
X1654771Y352088D03*
X1645685Y381500D03*
X1648835Y390500D03*
X1650044Y435158D03*
X1649789Y440489D03*
X1646209Y442606D03*
X1650087Y444841D03*
X1649773Y449961D03*
X1653490Y458572D03*
X1645826Y446606D03*
X1647133Y463479D03*
X1647604Y467367D03*
X1656112Y768669D03*
X1657042Y773604D03*
X1647402Y881460D03*
X1648375Y886766D03*
X1650205Y925911D03*
X1647763Y919268D03*
X1648387Y945554D03*
X1647470Y952125D03*
X1651443Y981515D03*
X1647565Y981432D03*
X1652944Y993796D03*
X1653414Y990590D03*
X1676870Y55513D03*
X1673095Y68581D03*
X1679470Y60513D03*
X1673108Y80581D03*
X1665190Y76587D03*
Y72615D03*
X1679598Y85731D03*
X1677238Y88801D03*
X1675291Y103621D03*
X1666629Y100625D03*
X1671002Y112083D03*
X1662391Y118335D03*
Y121735D03*
Y132509D03*
Y135909D03*
X1667208Y141247D03*
X1671695Y143518D03*
X1670795Y152373D03*
X1673945Y152562D03*
X1674637Y183834D03*
X1669352Y171523D03*
X1674810Y172665D03*
X1674747Y178560D03*
X1675623Y186629D03*
X1674157Y190185D03*
X1668882Y192490D03*
X1667318Y198828D03*
X1674927Y200864D03*
X1664840Y192300D03*
X1662837Y206767D03*
X1667837D03*
X1665337D03*
X1674950Y207037D03*
X1675016Y212455D03*
X1667967Y221708D03*
X1665467D03*
X1664082Y231021D03*
Y228221D03*
X1672317Y221642D03*
X1662967Y221708D03*
X1662382Y224421D03*
X1669633Y236189D03*
X1667133D03*
X1664633D03*
X1667074Y248765D03*
X1664574D03*
X1669574D03*
X1676231Y265897D03*
X1673731D03*
X1670071Y268195D03*
Y270695D03*
X1667271Y268195D03*
X1664771D03*
Y270695D03*
X1667271D03*
X1673203Y328867D03*
X1668979Y339559D03*
X1666860Y353661D03*
X1663650Y353283D03*
X1673723Y353881D03*
X1670323Y353534D03*
X1670260Y377912D03*
X1669260Y391496D03*
X1663618Y393858D03*
X1663780Y384410D03*
X1666959Y382047D03*
X1670260Y386500D03*
X1669260Y409000D03*
X1665260Y398583D03*
X1670348Y397912D03*
X1667260Y403500D03*
X1663713Y440869D03*
Y438269D03*
X1666513Y433069D03*
Y430469D03*
Y435669D03*
Y440869D03*
Y438269D03*
X1663713Y433069D03*
Y430469D03*
Y435669D03*
X1664567Y451677D03*
X1667067D03*
X1664567Y454177D03*
X1667067D03*
X1666271Y460218D03*
Y463618D03*
X1682330Y60438D03*
X1688011Y86012D03*
Y94374D03*
X1683152Y86046D03*
X1680155Y94351D03*
X1684104Y94279D03*
X1683348Y116594D03*
X1694291Y110784D03*
X1689291D03*
X1683348Y119594D03*
X1683782Y124283D03*
X1693870Y124663D03*
X1688848Y124879D03*
X1695214Y138838D03*
X1682189Y161306D03*
X1679440Y157370D03*
X1683524Y168665D03*
Y176665D03*
Y192665D03*
X1683637Y186778D03*
X1683556Y204864D03*
Y208864D03*
X1688605Y218085D03*
X1691405D03*
X1679197Y219379D03*
X1679825Y228631D03*
X1693932Y249108D03*
X1685313Y248371D03*
X1686339Y314890D03*
X1686115Y311740D03*
X1683523Y324518D03*
X1677810Y324466D03*
X1686408Y332584D03*
X1687424Y347937D03*
X1692676Y348015D03*
X1688593Y353470D03*
X1691182Y357016D03*
X1680518Y377912D03*
Y381912D03*
Y397912D03*
X1692253Y467306D03*
Y470706D03*
Y484879D03*
Y481479D03*
Y511439D03*
Y514839D03*
Y529013D03*
Y525613D03*
X1689920Y539315D03*
X1689236Y550137D03*
X1692028D03*
X1692253Y561479D03*
Y564879D03*
Y575652D03*
Y579052D03*
Y593225D03*
Y603999D03*
Y589825D03*
Y607399D03*
X1693000Y626912D03*
X1692379Y622912D03*
X1704934Y97667D03*
X1709184Y95111D03*
X1695317Y116594D03*
X1700590Y102495D03*
X1695317Y119594D03*
X1698851Y125107D03*
X1700324Y142862D03*
X1707465Y143762D03*
X1701365Y148717D03*
X1708913Y195176D03*
X1710931Y199248D03*
X1706413Y195176D03*
X1703913D03*
X1707931Y199248D03*
Y201748D03*
X1706494Y210509D03*
X1703994D03*
X1705767Y206806D03*
X1708267D03*
X1697984Y226320D03*
X1695205Y216385D03*
X1697918Y216970D03*
Y219470D03*
Y221970D03*
X1705686Y230556D03*
X1709941Y228747D03*
X1700945Y228646D03*
X1704671Y242078D03*
X1699902Y232971D03*
X1696552Y244571D03*
X1703895Y256394D03*
X1700223Y292141D03*
X1703609Y287320D03*
X1698292Y303962D03*
X1702655Y474418D03*
Y477818D03*
Y488591D03*
Y491991D03*
Y521952D03*
Y518552D03*
Y536125D03*
Y532725D03*
X1698716Y550065D03*
X1702655Y571991D03*
Y568591D03*
Y586165D03*
Y582765D03*
Y600338D03*
Y596938D03*
Y611111D03*
Y614511D03*
X1708015Y1142700D03*
X1711333Y1146609D03*
X1706450Y1173065D03*
X1703400Y1174400D03*
X1713394Y103411D03*
X1713788Y97667D03*
X1724584Y90650D03*
X1724334Y95236D03*
X1713553Y106561D03*
X1711413Y195176D03*
X1710931Y202048D03*
X1714531Y230117D03*
X1710547Y238714D03*
X1710028Y246874D03*
X1712248Y244297D03*
X1716755Y326179D03*
X1712226Y344028D03*
X1715930Y340969D03*
X1715590Y331719D03*
X1721746Y377173D03*
X1715228Y387966D03*
X1718851Y391533D03*
X1720571Y385644D03*
X1725746Y385123D03*
X1718318Y399918D03*
X1725154Y406060D03*
X1725415Y416289D03*
Y418889D03*
Y421489D03*
X1721423Y412106D03*
X1716310Y454334D03*
X1724627Y459330D03*
X1724580Y454214D03*
X1724923Y449045D03*
X1724930Y473571D03*
Y476071D03*
Y478571D03*
Y481071D03*
X1710174Y553101D03*
X1717626Y1134729D03*
X1710511Y1138130D03*
X1721008Y1134729D03*
X1723805Y1142666D03*
X1725008Y1134636D03*
X1725680Y1157544D03*
X1724191Y1167768D03*
X1713239Y1176038D03*
X1712526Y1171950D03*
X1728343Y1185205D03*
X1719692Y1187215D03*
X1719385Y1180175D03*
X1712715Y1188500D03*
X1721662Y1201043D03*
X1725658D03*
X1718625Y1199814D03*
X1712542Y1196600D03*
X1720536Y1217228D03*
X1723200Y1219895D03*
X1710825Y1231688D03*
X1712966Y1229841D03*
X1736405Y-69278D03*
Y-72678D03*
X1743175Y92874D03*
X1729896Y90615D03*
X1734267Y95236D03*
X1734217Y99961D03*
X1742224Y162368D03*
X1733079Y207978D03*
Y210478D03*
Y215478D03*
Y212978D03*
X1736408Y264180D03*
X1738908D03*
X1736333Y258880D03*
X1744524Y379429D03*
X1741746Y377173D03*
X1737786D03*
X1729751D03*
X1733746Y385123D03*
X1730746D03*
X1737746D03*
X1741420Y391569D03*
X1739847Y401066D03*
X1729508Y403300D03*
X1728915Y405889D03*
Y408489D03*
Y413689D03*
Y411089D03*
Y416289D03*
Y421489D03*
Y418889D03*
Y424089D03*
X1729302Y432718D03*
Y435518D03*
X1739179Y439318D03*
X1728915Y426689D03*
X1739179Y442118D03*
X1733014Y450091D03*
X1730014D03*
X1727404Y447209D03*
X1730404D03*
X1738824Y456034D03*
Y461034D03*
X1733014Y462060D03*
X1730014D03*
X1734952Y479217D03*
X1737646Y477213D03*
Y479713D03*
X1729002Y477053D03*
X1731502D03*
X1734952Y476717D03*
X1741800Y917900D03*
X1742029Y1116251D03*
X1739508Y1137129D03*
X1729008Y1134729D03*
X1732881D03*
X1739917Y1150087D03*
X1732137Y1157404D03*
X1737393Y1170767D03*
X1729210Y1167768D03*
X1728333Y1178240D03*
X1733052Y1187310D03*
X1737689Y1185238D03*
X1737482Y1180235D03*
X1733662Y1201039D03*
X1729628Y1201043D03*
X1737662Y1200969D03*
X1737781Y1208993D03*
X1726475Y1223170D03*
X1731533Y1228226D03*
X1729322Y1226016D03*
X1743131Y85539D03*
Y82939D03*
Y75139D03*
Y80339D03*
Y77739D03*
X1751456Y98551D03*
X1754351Y111223D03*
Y114623D03*
X1755006Y103783D03*
X1745202Y104249D03*
Y107649D03*
X1754351Y128796D03*
Y125396D03*
X1744824Y162368D03*
X1751924Y162793D03*
Y165393D03*
Y167993D03*
Y170493D03*
X1758848Y177616D03*
X1759429Y172190D03*
X1756927Y181009D03*
X1750921Y181426D03*
X1754132Y181366D03*
X1751129Y184221D03*
X1753746Y184012D03*
X1747607Y211695D03*
X1755165Y211359D03*
Y213859D03*
X1750107Y211695D03*
X1747607Y208695D03*
X1750407D03*
X1743535Y208213D03*
Y213213D03*
Y210713D03*
Y215713D03*
X1753784Y265701D03*
X1758871Y265896D03*
X1750602Y267526D03*
X1745302D03*
X1748102D03*
X1745302Y270026D03*
X1748102D03*
X1750602D03*
X1755419Y281716D03*
X1748497Y371060D03*
X1752497Y371076D03*
X1750135Y379088D03*
X1755433Y379028D03*
X1744180Y383966D03*
X1750187Y409539D03*
X1753187D03*
X1750187Y406739D03*
X1753187Y407039D03*
X1752851Y401981D03*
X1755351D03*
X1757124Y398278D03*
X1754624D03*
X1749470Y424067D03*
X1751970D03*
X1756970D03*
X1754470D03*
X1749705Y413611D03*
X1752205D03*
X1757205D03*
X1754705D03*
X1756844Y438293D03*
X1747179Y439318D03*
X1756844Y441093D03*
X1747179Y442118D03*
X1756844Y443893D03*
X1747306Y470001D03*
X1744806D03*
X1756894Y472020D03*
X1756553Y466409D03*
X1756954Y477318D03*
X1745231Y489036D03*
X1743092Y485580D03*
X1745592D03*
X1748092D03*
X1758401Y484882D03*
X1756391Y487382D03*
X1747467Y492836D03*
Y495636D03*
X1756089Y542952D03*
X1750879Y541940D03*
X1754906Y824333D03*
Y820737D03*
X1746897Y879199D03*
X1746884Y884649D03*
X1747900Y900160D03*
X1744900D03*
X1750915Y902055D03*
X1749267Y918413D03*
X1751200Y931100D03*
X1746600Y935100D03*
X1751854Y991297D03*
X1749314Y987904D03*
X1745824Y987058D03*
X1748677Y993986D03*
X1753860Y997271D03*
X1759569Y1021944D03*
X1744529Y1116251D03*
X1758390Y1577905D03*
X1759947Y1599029D03*
X1750685Y1621654D03*
X1767552Y76587D03*
Y72615D03*
X1762010Y97475D03*
X1768991Y100625D03*
X1761941Y106186D03*
X1773364Y112083D03*
X1764753Y121735D03*
Y118335D03*
Y132509D03*
Y135909D03*
X1771714Y171523D03*
X1776999Y183834D03*
X1762102Y168697D03*
X1763190Y191941D03*
X1771244Y192490D03*
X1776519Y190185D03*
X1767202Y192300D03*
X1765199Y206767D03*
X1770199D03*
X1767699D03*
X1758868Y213132D03*
X1765329Y221708D03*
X1770329D03*
X1767829D03*
X1764744Y224421D03*
X1766444Y231021D03*
Y228221D03*
X1774679Y221642D03*
X1758868Y215632D03*
X1771995Y236189D03*
X1769495D03*
X1766995D03*
X1771936Y248765D03*
X1769436D03*
X1766936D03*
X1759112Y256303D03*
X1763887Y266114D03*
X1767133Y270695D03*
X1769633D03*
X1772433Y268195D03*
Y270695D03*
X1769633Y268195D03*
X1767133D03*
X1761360Y281982D03*
X1762997Y377581D03*
X1765497Y379591D03*
X1772513Y387702D03*
X1769713D03*
X1765913Y389402D03*
X1763200Y388817D03*
Y383817D03*
Y386317D03*
X1766837Y438293D03*
Y441093D03*
Y443893D03*
X1768586Y467560D03*
X1764903Y470382D03*
X1764906Y474382D03*
X1776561Y467560D03*
X1777061Y475560D03*
X1768575D03*
X1770135Y490711D03*
X1758957Y543036D03*
X1773789Y927663D03*
X1765664Y923724D03*
X1769064D03*
X1773789Y930663D03*
X1774476Y995049D03*
X1773810Y990821D03*
X1762486Y990260D03*
X1760201Y992475D03*
X1758881Y995633D03*
X1769004Y1019395D03*
X1768844Y1023694D03*
Y1027248D03*
X1771773Y1028829D03*
X1772188Y1428369D03*
X1766313Y1580198D03*
X1761072Y1590719D03*
X1765040Y1599511D03*
X1760422Y1640303D03*
X1768422D03*
X1772422D03*
X1762041Y1631511D03*
X1768422Y1632245D03*
X1773820Y1631238D03*
X1779232Y55513D03*
X1775457Y68581D03*
X1785246Y60660D03*
X1781832Y60513D03*
X1775470Y80581D03*
X1781960Y85731D03*
X1790712Y81713D03*
X1790664Y71908D03*
X1779600Y88801D03*
X1790373Y94663D03*
X1786466Y85923D03*
Y94279D03*
X1782517Y94351D03*
X1777653Y103621D03*
X1785886Y168665D03*
Y176665D03*
X1777172Y172665D03*
X1777109Y178560D03*
X1777985Y186629D03*
X1785779Y192665D03*
X1785886Y196665D03*
X1777289Y200864D03*
X1785999Y186778D03*
X1785918Y204864D03*
X1777378Y212455D03*
X1777312Y207037D03*
X1785918Y208864D03*
X1781559Y219379D03*
X1782187Y228631D03*
X1778593Y265897D03*
X1776093D03*
X1787674Y303130D03*
X1777681Y387151D03*
Y382151D03*
Y384651D03*
X1786184Y435321D03*
Y438121D03*
X1783384Y435321D03*
Y438121D03*
X1786184Y440921D03*
X1783384D03*
X1786184Y443721D03*
X1783384D03*
X1786170Y448931D03*
X1792527Y452799D03*
X1786693Y459170D03*
X1790061Y474513D03*
X1779404Y826570D03*
X1791041Y818795D03*
X1780016Y874400D03*
X1775904Y924546D03*
X1778047Y916120D03*
X1789537Y930498D03*
X1780158Y953295D03*
X1785758Y956095D03*
Y953295D03*
X1782958D03*
Y956095D03*
X1780158D03*
X1789363Y969160D03*
X1782563Y979660D03*
X1785663D03*
X1779363D03*
X1786863Y985060D03*
X1779143Y995203D03*
X1779033Y1023432D03*
X1786740Y1019237D03*
X1780802Y1019474D03*
X1774863Y1019237D03*
X1774844Y1023694D03*
X1783844D03*
X1786844Y1027248D03*
X1780844D03*
X1774844D03*
X1789844Y1023694D03*
X1775998Y1074707D03*
Y1072207D03*
X1781198Y1074707D03*
X1778598D03*
X1783798D03*
Y1072207D03*
X1778598D03*
X1781198D03*
X1790736Y1072090D03*
Y1074590D03*
X1780326Y1089851D03*
X1777726D03*
X1782926D03*
Y1092351D03*
X1777726D03*
X1780326D03*
X1775126Y1089851D03*
Y1092351D03*
X1790639Y1082585D03*
X1790572Y1085152D03*
X1780662Y1108413D03*
X1783262D03*
X1778062D03*
X1775462D03*
X1785321Y1121122D03*
X1787921D03*
X1790521D03*
X1780566Y1111038D03*
X1783166D03*
X1777966D03*
X1775366D03*
X1790521Y1130822D03*
X1781874Y1139822D03*
X1787921Y1130822D03*
X1785321D03*
X1784374Y1139822D03*
X1781802Y1147822D03*
X1784302D03*
X1783278Y1208140D03*
X1778227Y1438099D03*
X1786091Y1443715D03*
X1787745Y1437765D03*
X1783178Y1437550D03*
X1778104Y1470289D03*
X1801761Y-33888D03*
Y-30488D03*
X1791088Y77296D03*
X1804758Y294429D03*
X1793524Y303343D03*
X1805196Y300952D03*
X1799897Y408104D03*
X1802697D03*
X1805497D03*
X1793475Y424939D03*
X1799614Y420375D03*
X1802414D03*
X1805214D03*
X1793475Y427439D03*
X1809095Y435101D03*
X1803700Y440101D03*
X1803530Y431112D03*
X1809358Y442114D03*
X1803335Y452718D03*
X1809346Y452601D03*
X1797907Y452987D03*
X1809338Y447121D03*
X1804933Y461607D03*
X1796933D03*
X1796136Y471334D03*
X1800933Y461607D03*
X1802000Y892447D03*
X1797365Y930761D03*
X1793474Y930374D03*
X1805463Y969260D03*
X1801963Y969160D03*
X1802363Y989660D03*
X1803351Y1027471D03*
X1805188Y1019078D03*
X1799646Y1018999D03*
X1793470Y1018762D03*
X1801844Y1023694D03*
X1795844D03*
X1798844Y1027248D03*
X1792844D03*
X1795936Y1072090D03*
X1793336D03*
X1798536D03*
Y1074590D03*
X1793336D03*
X1795936D03*
X1801961Y1081717D03*
X1795819Y1088553D03*
X1800813Y1103246D03*
X1806206Y1114589D03*
X1803506D03*
X1800906D03*
X1798306D03*
X1798702Y1124328D03*
X1801302D03*
X1803902D03*
X1806602D03*
X1793221Y1121122D03*
Y1130822D03*
X1804532Y1133356D03*
X1807232D03*
X1807035Y1136912D03*
Y1144912D03*
X1806835Y1214668D03*
X1800489Y1220598D03*
X1807243Y1219955D03*
X1802670Y1210905D03*
X1805126Y1225745D03*
X1799845Y1261044D03*
X1794845D03*
X1797345D03*
X1799845Y1263544D03*
X1797345D03*
X1794845D03*
X1803885Y1435046D03*
X1806428Y1444543D03*
X1795374D03*
X1802813Y1464015D03*
X1803762Y1467236D03*
X1819900Y906900D03*
X1807663Y966660D03*
Y963860D03*
X1808014Y984832D03*
X1812538Y1026859D03*
X1811468Y1021084D03*
X1807844Y1023694D03*
Y1027248D03*
X1810349Y1031264D03*
X1816756Y1089145D03*
Y1094145D03*
X1816235Y1083970D03*
X1810346Y1082250D03*
X1816756Y1097145D03*
Y1101145D03*
X1810310Y1104819D03*
X1809535Y1136912D03*
Y1144912D03*
X1812130Y1205349D03*
X1822594Y1211054D03*
Y1215324D03*
X1814741Y1217093D03*
X1811482Y1226423D03*
X1810018Y1295944D03*
X1812818D03*
X1815618Y1298744D03*
Y1295944D03*
X1812818Y1298744D03*
X1810018D03*
X1812202Y1432624D03*
X1809342Y1476733D03*
X1824706Y1085145D03*
X1824949Y1077145D03*
X1824706Y1100185D03*
Y1106145D03*
X1828272Y1095968D03*
X1824706Y1093150D03*
X1830915Y1109146D03*
X1834665Y1213239D03*
G54D23*
X51750Y617861D03*
X48207D03*
X44664D03*
X51750Y620661D03*
X48207D03*
X44664D03*
X55294Y617861D03*
Y620661D03*
X146948Y1088287D03*
X143208D03*
X146948Y1099507D03*
X143208D03*
X146948Y1106988D03*
X143208D03*
X146948Y1114468D03*
Y1121948D03*
X143208Y1114468D03*
Y1121948D03*
X146948Y1129429D03*
X143208D03*
X146948Y1136909D03*
X143208D03*
X146948Y1148129D03*
X143208D03*
X146947Y1170570D03*
X143207D03*
X146947Y1178051D03*
X143207D03*
X165649Y1073326D03*
X158169D03*
X150689D03*
X165649Y1092027D03*
X158169D03*
X150689D03*
X165649Y1077066D03*
X161909Y1084547D03*
X158169Y1077066D03*
X154429Y1084547D03*
X161909Y1080807D03*
X154429D03*
X165649Y1095767D03*
X161909Y1103247D03*
X158169Y1095767D03*
X154429Y1103247D03*
X150689Y1095767D03*
X161909Y1099507D03*
X154429D03*
X161909Y1118208D03*
Y1121948D03*
X165649Y1110728D03*
X161909D03*
X154429D03*
Y1118208D03*
X150689Y1110728D03*
Y1118208D03*
X154429Y1125688D03*
X150689D03*
Y1133169D03*
X165649D03*
X161909D03*
X154429D03*
X165649Y1148129D03*
Y1144389D03*
Y1155610D03*
X160039Y1176180D03*
X156299D03*
X169389Y1084547D03*
Y1080807D03*
Y1103247D03*
X173129Y1136909D03*
X169389D03*
X176870Y1151870D03*
Y1148129D03*
Y1144389D03*
X169389Y1151870D03*
Y1148129D03*
X176870Y1166830D03*
Y1159350D03*
X169389D03*
X176870Y1174310D03*
Y1178051D03*
Y1181791D03*
X188090Y1114468D03*
X184350D03*
X191830D03*
X195570D03*
X191830Y1140649D03*
Y1136909D03*
X195570Y1140649D03*
X184350Y1136909D03*
X191830Y1133169D03*
Y1129429D03*
Y1144389D03*
Y1151869D03*
X195570Y1148129D03*
Y1155610D03*
X184350Y1144389D03*
X188090Y1155610D03*
X184350Y1151870D03*
X188090Y1148129D03*
X191830Y1159350D03*
Y1170570D03*
X195570Y1166830D03*
X184350Y1159350D03*
Y1170570D03*
X188090Y1166830D03*
X191830Y1185531D03*
Y1178051D03*
X195570Y1181791D03*
Y1174310D03*
X184350Y1185531D03*
X188090Y1181791D03*
Y1174310D03*
X184350Y1178051D03*
X191830Y1193011D03*
X195570Y1215452D03*
X197440Y1217322D03*
X186220D03*
X189960D03*
Y1213582D03*
X203051Y1114468D03*
X199311D03*
X206791D03*
X210531D03*
X206791Y1136909D03*
X203051D03*
X199311D03*
X214271D03*
X210531D03*
X199311Y1129429D03*
X206791D03*
X214271D03*
X210531D03*
X203051D03*
X210531Y1155610D03*
X203051D03*
X206791Y1144389D03*
X203051D03*
X199311D03*
X214271D03*
X210531D03*
X214271Y1151870D03*
X210531D03*
X206791D03*
X203051D03*
X199311D03*
X214271Y1170570D03*
X210531Y1166830D03*
X214271Y1159350D03*
X206791Y1170570D03*
X203051Y1166830D03*
X199311Y1170570D03*
X206791Y1159350D03*
X199311D03*
X203051Y1174310D03*
X210531D03*
X203051Y1185531D03*
X199311D03*
X206791D03*
X214271D03*
X210531D03*
X206791Y1178051D03*
X203051D03*
X199311D03*
X214271D03*
X210531D03*
X214271Y1193011D03*
X210531D03*
X199311D03*
X203051D03*
X206791D03*
X214271Y1200491D03*
X210531D03*
X199311D03*
X206791D03*
X203051D03*
X201181Y1213582D03*
X214271Y1211712D03*
X208661Y1213582D03*
X203051Y1215452D03*
X214271D03*
X201181Y1217322D03*
X208661D03*
X210531Y1215452D03*
X204921Y1213582D03*
X225492Y1114468D03*
X221752D03*
X218011D03*
X225492Y1136909D03*
X221751D03*
X218011D03*
X229232D03*
Y1129429D03*
X218011D03*
X221751D03*
X225492D03*
X218011Y1155610D03*
X225492D03*
Y1144389D03*
X221751D03*
X218011D03*
X229232D03*
Y1151870D03*
X221752D03*
X218011D03*
X225492D03*
Y1166830D03*
X221751Y1170570D03*
X218011Y1166830D03*
X221751Y1159350D03*
X229232Y1170570D03*
Y1159350D03*
X225492Y1174310D03*
X218011D03*
X225492Y1185531D03*
X218011D03*
X221751D03*
X229232D03*
X225492Y1178051D03*
X221751D03*
X218011D03*
X229232D03*
X218011Y1193011D03*
X221751D03*
X225492D03*
X229232D03*
X218011Y1200491D03*
X221751D03*
X225492D03*
X229232D03*
X218011Y1215452D03*
X229232Y1211712D03*
Y1215452D03*
X225492Y1211712D03*
X221752D03*
Y1215452D03*
X240452Y1114468D03*
X244192D03*
X236712Y1118208D03*
X244192D03*
X236712Y1114468D03*
X240452Y1118208D03*
Y1136909D03*
X236712D03*
X244192D03*
Y1129429D03*
X240452D03*
X236712D03*
Y1155610D03*
X244192D03*
X240452Y1151869D03*
X236712D03*
X244192D03*
X240452Y1144389D03*
X236712D03*
X244192D03*
X236712Y1166830D03*
X240452Y1170570D03*
Y1159350D03*
X244192Y1166830D03*
X236712Y1174310D03*
X244192D03*
X240452Y1185531D03*
X236712D03*
X244192D03*
X240452Y1178051D03*
X236712D03*
X244192D03*
X240452Y1193011D03*
X236712D03*
X244192D03*
X236712Y1200491D03*
X244192D03*
X240452D03*
X244192Y1215452D03*
X240452D03*
X242322Y1217322D03*
X236712Y1211712D03*
Y1215452D03*
X238582Y1217322D03*
X262893Y1118208D03*
X259153Y1114468D03*
X262893D03*
X255413Y1118208D03*
Y1114468D03*
X247933D03*
X259153Y1118208D03*
X251673Y1114468D03*
X247933Y1118208D03*
X251673D03*
X255413Y1136909D03*
X251673D03*
X247933D03*
X259153D03*
X262893D03*
X247933Y1129429D03*
X259153D03*
X262893D03*
X255413D03*
X251673D03*
Y1155610D03*
X259153D03*
X251673Y1144389D03*
X247933D03*
X255413D03*
X259153Y1151869D03*
X262893D03*
X247933D03*
X255413D03*
X251673D03*
X262893Y1144389D03*
X259153D03*
X251673Y1166830D03*
X255413Y1170570D03*
X247933D03*
X255413Y1159350D03*
X247933D03*
X259153Y1166830D03*
X262893Y1170570D03*
Y1159350D03*
X251673Y1174310D03*
X259153D03*
X247933Y1185531D03*
X255413D03*
X251673D03*
X259153D03*
X262893D03*
X251673Y1178051D03*
X247933D03*
X255413D03*
X259153D03*
X262893D03*
X251673Y1193011D03*
X255413D03*
X247933D03*
X262893D03*
X259153D03*
Y1200491D03*
X262893D03*
X251673D03*
X247933D03*
X255413D03*
Y1215452D03*
X262893D03*
X247932Y1215451D03*
X259153Y1215452D03*
X251673D03*
X247932Y1211711D03*
X251673D03*
X270373Y1114468D03*
X274114D03*
X277854D03*
X266633Y1136909D03*
Y1129429D03*
X274114D03*
Y1140649D03*
Y1136909D03*
X266633Y1155610D03*
X277854D03*
X266633Y1151869D03*
Y1144389D03*
X274114D03*
X277854Y1159350D03*
Y1166830D03*
Y1170570D03*
X266633D03*
X270373D03*
X266633Y1159350D03*
X270373D03*
Y1166830D03*
X266633D03*
Y1174310D03*
X277854D03*
X266633Y1185531D03*
Y1178051D03*
X270373Y1181791D03*
X274114Y1185531D03*
Y1189271D03*
Y1178051D03*
X266633Y1193011D03*
Y1200491D03*
X274114D03*
Y1193011D03*
X277854Y1204232D03*
Y1196751D03*
Y1200491D03*
X274114Y1215452D03*
X277854D03*
X266633D03*
X274114Y1211712D03*
X277854Y1207972D03*
X285334Y1118208D03*
X281594D03*
X285334Y1114468D03*
X281594D03*
X289074Y1140649D03*
X285334D03*
Y1136909D03*
X292815Y1140649D03*
X285334Y1155610D03*
X281594Y1144389D03*
X285334Y1148129D03*
Y1144389D03*
X289074Y1148129D03*
X292815D03*
Y1155610D03*
X285334Y1170570D03*
Y1166830D03*
Y1159350D03*
X292815Y1170570D03*
X285334Y1174310D03*
X289074Y1189271D03*
X285334D03*
X281594Y1181791D03*
X285334Y1178051D03*
X289074Y1181791D03*
X285334Y1196751D03*
Y1204232D03*
X281594Y1200491D03*
X285334D03*
Y1207972D03*
Y1215452D03*
Y1211712D03*
X281594Y1215452D03*
Y1207972D03*
X311515Y1140649D03*
X304035Y1144389D03*
Y1151869D03*
X307775Y1144389D03*
Y1151869D03*
X296555Y1155610D03*
X311515Y1148129D03*
Y1155610D03*
X304035Y1166830D03*
Y1159350D03*
X307775Y1166830D03*
X296555Y1170570D03*
X311515D03*
X304035Y1174310D03*
Y1181791D03*
Y1189271D03*
X307775Y1174310D03*
Y1181791D03*
Y1189271D03*
X311515Y1178051D03*
Y1185531D03*
Y1193011D03*
X322736Y1136909D03*
X326476D03*
X315255Y1140649D03*
X322736Y1144389D03*
Y1151870D03*
X326476Y1144389D03*
X315255Y1148129D03*
X326476Y1151870D03*
X315255Y1155610D03*
X322736Y1159350D03*
X326476D03*
X315255Y1170570D03*
X322736Y1174310D03*
Y1181791D03*
Y1189271D03*
X326476Y1174310D03*
X315255Y1178051D03*
X326476Y1181791D03*
X315255Y1185531D03*
X326476Y1189271D03*
X315255Y1193011D03*
X425023Y441086D03*
Y433999D03*
Y437543D03*
X422223Y441086D03*
Y433999D03*
Y437543D03*
X425023Y444629D03*
X422223D03*
X501750Y620661D03*
X505293D03*
X501750Y617861D03*
X505293D03*
X512380D03*
X508836Y620661D03*
Y617861D03*
X512380Y620661D03*
X600295Y1088287D03*
X604035D03*
X600295Y1099507D03*
X604035D03*
X600295Y1106988D03*
X604035D03*
Y1121948D03*
X600295D03*
Y1114468D03*
X604035D03*
X600295Y1136909D03*
X604035D03*
X600295Y1129429D03*
X604035D03*
Y1148129D03*
X600295D03*
X604034Y1170570D03*
X600294D03*
X604034Y1178051D03*
X600294D03*
X615256Y1073326D03*
X607776D03*
X618996Y1084547D03*
Y1080807D03*
X615256Y1077066D03*
X611516Y1080807D03*
Y1084547D03*
X607776Y1092027D03*
X615256D03*
X607776Y1095767D03*
X615256D03*
X618996Y1103247D03*
X611516D03*
X618996Y1099507D03*
X611516D03*
X618996Y1118208D03*
Y1121948D03*
X611516Y1118208D03*
X607776D03*
X611516Y1110728D03*
X618996D03*
X607776D03*
X611516Y1125688D03*
X607776D03*
Y1133169D03*
X615256Y1178051D03*
X611516D03*
X622736Y1073326D03*
Y1077066D03*
X626476Y1084547D03*
X622736Y1092027D03*
X626476Y1080807D03*
X622736Y1095767D03*
X626476Y1103247D03*
X622736Y1118208D03*
X626476Y1114468D03*
X622736Y1110728D03*
X630216Y1114468D03*
X633957Y1151870D03*
Y1148129D03*
Y1144389D03*
X626476Y1148129D03*
X622736Y1144389D03*
Y1148129D03*
X626476Y1151870D03*
X622736Y1155610D03*
X633957Y1166830D03*
Y1159350D03*
X626476D03*
X633957Y1174310D03*
Y1178051D03*
Y1181791D03*
X645177Y1114468D03*
X641437D03*
X648917D03*
X652657D03*
X648917Y1140649D03*
Y1136909D03*
X652657Y1140649D03*
X641437Y1136909D03*
X648917Y1129429D03*
Y1133169D03*
X652657Y1148129D03*
Y1155610D03*
X648917Y1144389D03*
Y1151869D03*
X641437Y1144389D03*
Y1151870D03*
X645177Y1155610D03*
Y1148129D03*
X648917Y1159350D03*
Y1170570D03*
X652657Y1166830D03*
X641437Y1170570D03*
X645177Y1166830D03*
X641437Y1159350D03*
X648917Y1185531D03*
Y1178051D03*
X652657Y1181791D03*
Y1174310D03*
X641437Y1185531D03*
Y1178051D03*
X645177Y1181791D03*
Y1174310D03*
X648917Y1193011D03*
X652657Y1215452D03*
Y1219192D03*
X641437Y1215452D03*
X648917D03*
X645177D03*
X660138Y1114468D03*
X656398D03*
X663878D03*
X667618D03*
Y1129429D03*
X660138D03*
X656398D03*
X663878D03*
Y1136909D03*
X660138D03*
X656398D03*
X667618D03*
X660138Y1155610D03*
X667618D03*
Y1144389D03*
X663878D03*
X660138D03*
X656398D03*
X667618Y1151870D03*
X663878D03*
X660138D03*
X656398D03*
X663878Y1170570D03*
X660138Y1166830D03*
X656398Y1170570D03*
X663878Y1159350D03*
X656398D03*
X667618Y1166830D03*
Y1174310D03*
X660138D03*
X667618Y1185531D03*
X660138D03*
X656398D03*
X663878D03*
X667618Y1178051D03*
X663878D03*
X660138D03*
X656398D03*
X667618Y1200491D03*
X656398D03*
X663878D03*
X660138D03*
X663878Y1193011D03*
X660138D03*
X656398D03*
X667618D03*
X663878Y1211712D03*
X656398D03*
X660138Y1215452D03*
X656398D03*
X663878D03*
X667618D03*
X660138Y1211712D03*
X682579Y1114468D03*
X678839D03*
X675098D03*
Y1129429D03*
X671358D03*
X678838D03*
X682579D03*
Y1136909D03*
X678838D03*
X675098D03*
X671358D03*
X682579Y1155610D03*
X675098D03*
X678839Y1151870D03*
X675098D03*
X671358D03*
X682579D03*
Y1144389D03*
X671358D03*
X678838D03*
X675098D03*
X682579Y1166830D03*
X678838Y1170570D03*
X671358D03*
X675098Y1166830D03*
X671358Y1159350D03*
X678838D03*
X682579Y1174310D03*
X675098D03*
X682579Y1185531D03*
X675098D03*
X671358D03*
X678838D03*
X682579Y1178051D03*
X678838D03*
X675098D03*
X671358D03*
X675098Y1200491D03*
X671358D03*
X678838D03*
X682579D03*
Y1193011D03*
X678838D03*
X675098D03*
X671358D03*
X682579Y1211712D03*
X678839D03*
Y1215452D03*
X671358Y1211712D03*
Y1215452D03*
X675098D03*
X693799Y1114468D03*
Y1118208D03*
X701279Y1114468D03*
X697539Y1118208D03*
Y1114468D03*
X701279Y1118208D03*
Y1129429D03*
X697539D03*
X693799D03*
X686319D03*
X697539Y1136909D03*
X693799D03*
X701279D03*
X686319D03*
X701279Y1155610D03*
X693799D03*
X701279Y1151869D03*
X697539D03*
X693799D03*
X701279Y1144389D03*
X697539D03*
X693799D03*
X686319D03*
Y1151870D03*
X693799Y1166830D03*
X697539Y1170570D03*
Y1159350D03*
X701279Y1166830D03*
X686319Y1170570D03*
Y1159350D03*
X701279Y1174310D03*
X693799D03*
X701279Y1185531D03*
X697539D03*
X693799D03*
X701279Y1178051D03*
X697539D03*
X693799D03*
X686319Y1185531D03*
Y1178051D03*
X701279Y1200491D03*
X697539D03*
X693799D03*
X686319D03*
X701279Y1193011D03*
X697539D03*
X693799D03*
X686319D03*
Y1211712D03*
Y1215452D03*
X699409Y1217322D03*
X697539Y1215452D03*
X693799D03*
Y1211712D03*
X701279Y1215452D03*
X695669Y1217322D03*
X708760Y1114468D03*
X716240Y1118208D03*
X705020Y1114468D03*
X712500D03*
X716240D03*
X705020Y1118208D03*
X712500D03*
X708760D03*
X705020Y1129429D03*
X708760D03*
X712500D03*
X716240D03*
Y1136909D03*
X705020D03*
X708760D03*
X712500D03*
X708760Y1155610D03*
X716240D03*
Y1151869D03*
X708760D03*
X712500D03*
X705020D03*
X712500Y1144389D03*
X705020D03*
X708760D03*
X716240D03*
Y1166830D03*
X705020Y1159350D03*
X712500D03*
X705020Y1170570D03*
X712500D03*
X708760Y1166830D03*
X716240Y1174310D03*
X708760D03*
X716240Y1185531D03*
X708760D03*
X712500D03*
X705020D03*
X716240Y1178051D03*
X712500D03*
X705020D03*
X708760D03*
X712500Y1200491D03*
X705020D03*
X708760D03*
X716240D03*
X708760Y1193011D03*
X712500D03*
X705020D03*
X716240D03*
Y1215452D03*
X708760D03*
X712500D03*
X705019Y1215451D03*
Y1211711D03*
X708760D03*
X731201Y1114468D03*
X734941D03*
X727460D03*
X719980Y1118208D03*
Y1114468D03*
Y1129429D03*
X723720D03*
X731201D03*
X719980Y1136909D03*
X723720D03*
X731201D03*
Y1140649D03*
X723720Y1155610D03*
X719980Y1151869D03*
X723720D03*
Y1144389D03*
X719980D03*
X734941Y1155610D03*
X731201Y1144389D03*
X719980Y1159350D03*
X727460D03*
X723720D03*
Y1166830D03*
X727460D03*
X719980Y1170570D03*
X727460D03*
X723720D03*
X734941Y1159350D03*
Y1166830D03*
Y1170570D03*
X723720Y1174310D03*
X727460Y1181791D03*
X719980Y1185531D03*
Y1178051D03*
X723720D03*
Y1185531D03*
X734941Y1174310D03*
X731201Y1189271D03*
Y1185531D03*
Y1178051D03*
X719980Y1200491D03*
X723720D03*
X731201D03*
X719980Y1193011D03*
X723720D03*
X731201D03*
X734941Y1196751D03*
Y1204232D03*
Y1200491D03*
X731201Y1215452D03*
X734941D03*
X723720D03*
X719980D03*
X731201Y1211712D03*
X734941Y1207972D03*
X727461Y1215452D03*
X738681Y1118208D03*
X742421D03*
X738681Y1114468D03*
X742421D03*
Y1140649D03*
Y1136909D03*
X746161Y1140649D03*
X749902D03*
X742421Y1155610D03*
X746161Y1148129D03*
X738681Y1144389D03*
X742421Y1148129D03*
Y1144389D03*
X749902Y1155610D03*
Y1148129D03*
X742421Y1159350D03*
Y1166830D03*
Y1170570D03*
X749902D03*
X742421Y1189271D03*
X746161D03*
X742421Y1174310D03*
X738681Y1181791D03*
X746161D03*
X742421Y1178051D03*
Y1196751D03*
X738681Y1200491D03*
X742421Y1204232D03*
Y1200491D03*
Y1211712D03*
Y1215452D03*
Y1207972D03*
X738681Y1215452D03*
Y1207972D03*
Y1211712D03*
X761122Y1144389D03*
Y1151869D03*
X753642Y1155610D03*
X764862Y1151869D03*
Y1144389D03*
Y1166830D03*
X761122D03*
Y1159350D03*
X753642Y1170570D03*
X764862Y1174310D03*
X761122Y1181791D03*
X764862D03*
X761122Y1174310D03*
X768602Y1140649D03*
X772342D03*
Y1148129D03*
Y1155610D03*
X783563Y1151870D03*
X779823D03*
Y1144389D03*
X783563D03*
X768602Y1155610D03*
Y1148129D03*
X779823Y1159350D03*
X772342Y1170570D03*
X768602D03*
X783563Y1159350D03*
Y1189271D03*
X768602Y1185531D03*
X772342Y1178051D03*
X779823Y1189271D03*
X772342Y1185531D03*
X783563Y1174310D03*
X779823D03*
X783563Y1181791D03*
X768602Y1178051D03*
X779823Y1181791D03*
X768602Y1193011D03*
X772342D03*
X920349Y450340D03*
X917549D03*
X920349Y453884D03*
Y457427D03*
X917549Y453884D03*
Y457427D03*
X920349Y460970D03*
X917549D03*
X962380Y617861D03*
X958837D03*
X962380Y620661D03*
X958837D03*
X969467D03*
X965923Y617861D03*
Y620661D03*
X969467Y617861D03*
X1057381Y1088287D03*
Y1106988D03*
Y1099507D03*
Y1114468D03*
Y1121948D03*
Y1129429D03*
Y1136909D03*
Y1148129D03*
X1057380Y1170570D03*
Y1178051D03*
X1072342Y1073326D03*
X1064862D03*
Y1092027D03*
X1072342Y1077066D03*
X1068602Y1084547D03*
Y1080807D03*
X1061121Y1088287D03*
X1072342Y1092027D03*
X1068602Y1099507D03*
X1072342Y1095767D03*
X1061121Y1106988D03*
X1068602Y1103247D03*
X1064862Y1095767D03*
X1061121Y1099507D03*
Y1114468D03*
X1068602Y1110728D03*
Y1118208D03*
X1064862Y1110728D03*
Y1118208D03*
X1061121Y1121948D03*
X1064862Y1125688D03*
X1068602D03*
X1061121Y1129429D03*
X1064862Y1133169D03*
X1061121Y1136909D03*
Y1148129D03*
X1061120Y1170570D03*
X1072342Y1178051D03*
X1068602D03*
X1061120D03*
X1079822Y1073326D03*
Y1092027D03*
X1083562Y1084547D03*
X1079822Y1077066D03*
X1076082Y1084547D03*
Y1080807D03*
X1083562D03*
X1076082Y1103247D03*
X1079822Y1095767D03*
X1076082Y1099507D03*
X1083562Y1103247D03*
X1079822Y1118208D03*
X1076082Y1121948D03*
Y1118208D03*
X1079822Y1110728D03*
X1083562Y1114468D03*
X1087302D03*
X1076082Y1110728D03*
X1091043Y1151870D03*
Y1148129D03*
Y1144389D03*
X1083562Y1148129D03*
X1079822Y1144389D03*
Y1148129D03*
X1083562Y1151870D03*
X1079822Y1155610D03*
X1091043Y1166830D03*
Y1159350D03*
X1083562D03*
X1091043Y1181791D03*
Y1178051D03*
Y1174310D03*
X1102263Y1114468D03*
X1098523D03*
X1106003D03*
Y1140649D03*
Y1136909D03*
X1098523D03*
X1106003Y1129429D03*
Y1133169D03*
Y1151869D03*
Y1144389D03*
X1098523D03*
Y1151870D03*
X1102263Y1148129D03*
Y1155610D03*
X1106003Y1170570D03*
Y1159350D03*
X1102263Y1166830D03*
X1098523Y1159350D03*
Y1170570D03*
X1106003Y1178051D03*
Y1185531D03*
X1098523D03*
X1102263Y1174310D03*
X1098523Y1178051D03*
X1102263Y1181791D03*
X1106003Y1193011D03*
Y1215452D03*
X1098523D03*
X1102263D03*
X1117224Y1114468D03*
X1113484D03*
X1120964D03*
X1124704D03*
X1109743D03*
X1120964Y1129429D03*
X1113484D03*
X1117224D03*
X1124704D03*
Y1136909D03*
X1113484D03*
X1117224D03*
X1120964D03*
X1109743Y1140649D03*
X1124704Y1144389D03*
X1113484D03*
X1117224D03*
X1120964D03*
X1113484Y1151870D03*
X1117224D03*
X1120964D03*
X1124704D03*
Y1155610D03*
X1109743D03*
Y1148129D03*
X1117224Y1155610D03*
X1113484Y1159350D03*
X1120964D03*
X1109743Y1166830D03*
X1113484Y1170570D03*
X1117224Y1166830D03*
X1120964Y1170570D03*
X1124704Y1166830D03*
X1113484Y1178051D03*
X1117224D03*
X1120964D03*
X1124704D03*
X1120964Y1185531D03*
X1113484D03*
X1117224D03*
X1124704D03*
X1109743Y1174310D03*
Y1181791D03*
X1117224Y1174310D03*
X1124704D03*
X1117224Y1200491D03*
X1120964D03*
X1113484D03*
X1124704D03*
X1120964Y1193011D03*
X1117224D03*
X1113484D03*
X1124704D03*
Y1215452D03*
X1120964D03*
Y1211712D03*
X1117224Y1215452D03*
X1109743D03*
X1113484Y1211712D03*
X1111613Y1217322D03*
X1115354D03*
X1117224Y1211712D03*
X1139665Y1114468D03*
X1135925D03*
X1132184D03*
Y1129429D03*
X1128444D03*
X1135924D03*
X1139665D03*
Y1136909D03*
X1135924D03*
X1132184D03*
X1128444D03*
Y1144389D03*
X1135924D03*
X1132184D03*
X1139665D03*
X1135925Y1151870D03*
X1132184D03*
X1128444D03*
X1139665D03*
Y1155610D03*
X1132184D03*
X1139665Y1166830D03*
X1135924Y1170570D03*
X1128444D03*
X1132184Y1166830D03*
X1128444Y1159350D03*
X1135924D03*
X1139665Y1178051D03*
X1135924D03*
X1132184D03*
X1128444D03*
X1139665Y1185531D03*
X1132184D03*
X1128444D03*
X1135924D03*
X1139665Y1174310D03*
X1132184D03*
Y1200491D03*
X1128444D03*
X1135924D03*
X1139665D03*
X1128444Y1193011D03*
X1132184D03*
X1135924D03*
X1139665D03*
Y1211712D03*
X1135925D03*
Y1215452D03*
X1128444D03*
X1132184D03*
X1128444Y1211712D03*
X1154625Y1118208D03*
X1150885D03*
X1154625Y1114468D03*
X1150885D03*
X1154625Y1129429D03*
X1150885D03*
X1143405D03*
Y1136909D03*
X1154625D03*
X1150885D03*
X1143405Y1144389D03*
X1150885Y1151869D03*
X1154625D03*
Y1144389D03*
X1150885D03*
X1143405Y1151870D03*
X1150885Y1155610D03*
X1143405Y1170570D03*
X1154625Y1159350D03*
X1143405D03*
X1150885Y1166830D03*
X1154625Y1170570D03*
X1143405Y1178051D03*
Y1185531D03*
X1154625D03*
X1150885D03*
X1154625Y1178051D03*
X1150885D03*
Y1174310D03*
X1143405Y1200491D03*
X1154625D03*
X1150885D03*
Y1193011D03*
X1154625D03*
X1143405D03*
Y1211712D03*
Y1215452D03*
X1150885Y1211712D03*
Y1215452D03*
X1154625D03*
X1156495Y1217322D03*
X1152755D03*
X1162106Y1114468D03*
X1169586D03*
X1162106Y1118208D03*
X1173326Y1114468D03*
X1158365Y1118208D03*
X1173326D03*
X1165846Y1114468D03*
X1158365D03*
X1169586Y1118208D03*
X1165846D03*
X1169586Y1129429D03*
X1165846D03*
X1162106D03*
X1158365D03*
X1173326D03*
Y1136909D03*
X1169586D03*
X1165846D03*
X1158365D03*
X1162106D03*
X1173326Y1151869D03*
X1158365D03*
X1162106D03*
X1169586D03*
X1165846D03*
X1173326Y1144389D03*
X1165846D03*
X1158365D03*
X1162106D03*
X1169586D03*
X1173326Y1155610D03*
X1165846D03*
X1158365D03*
X1173326Y1166830D03*
X1165846D03*
X1169586Y1170570D03*
X1158365Y1166830D03*
X1162106Y1170570D03*
X1169586Y1159350D03*
X1162106D03*
X1158365Y1185531D03*
X1162106D03*
X1169586D03*
X1165846D03*
X1173326D03*
X1165846Y1178051D03*
X1158365D03*
X1162106D03*
X1169586D03*
X1173326D03*
X1165846Y1174310D03*
X1158365D03*
X1173326D03*
Y1200491D03*
X1165846D03*
X1162106D03*
X1158365D03*
X1169586D03*
X1165846Y1193011D03*
X1169586D03*
X1158365D03*
X1162106D03*
X1173326D03*
Y1215452D03*
X1165846D03*
X1169586D03*
X1162105Y1215451D03*
X1158365Y1215452D03*
X1162105Y1211711D03*
X1165846D03*
X1188287Y1114468D03*
X1177066D03*
Y1118208D03*
X1184546Y1114468D03*
X1180806Y1129429D03*
X1177066D03*
X1188287D03*
X1180806Y1136909D03*
X1177066D03*
X1188287D03*
Y1140649D03*
X1180806Y1151869D03*
X1177066D03*
Y1144389D03*
X1180806D03*
Y1155610D03*
X1188287Y1144389D03*
X1180806Y1170570D03*
X1184546D03*
X1177066D03*
X1184546Y1166830D03*
X1180806D03*
X1177066Y1159350D03*
X1180806D03*
X1184546D03*
X1177066Y1185531D03*
Y1178051D03*
X1180806Y1185531D03*
Y1178051D03*
Y1174310D03*
X1184546Y1181791D03*
X1188287Y1185531D03*
Y1189271D03*
Y1178051D03*
X1180806Y1200491D03*
X1177066D03*
X1188287D03*
X1177066Y1193011D03*
X1180806D03*
X1188287D03*
Y1215452D03*
X1180806D03*
X1177066D03*
X1188287Y1211712D03*
X1199507Y1118208D03*
X1195767D03*
Y1114468D03*
X1192027D03*
X1199507D03*
Y1140649D03*
Y1136909D03*
X1203247Y1140649D03*
X1199507Y1155610D03*
X1192027D03*
X1203247Y1148129D03*
X1195767Y1144389D03*
X1199507Y1148129D03*
Y1144389D03*
Y1170570D03*
Y1166830D03*
Y1159350D03*
X1192027Y1166830D03*
Y1170570D03*
Y1159350D03*
X1203247Y1189271D03*
X1199507D03*
Y1174310D03*
X1195767Y1181791D03*
X1192027Y1174310D03*
X1199507Y1178051D03*
X1203247Y1181791D03*
X1199507Y1196751D03*
Y1204232D03*
X1195767Y1200491D03*
X1192027Y1196751D03*
Y1200491D03*
Y1204232D03*
X1199507Y1200491D03*
X1192027Y1215452D03*
X1199507Y1211712D03*
Y1215452D03*
Y1207972D03*
X1195767Y1215452D03*
X1192027Y1207972D03*
X1195767D03*
Y1211712D03*
X1206988Y1140649D03*
X1218208Y1144389D03*
Y1151869D03*
X1206988Y1155610D03*
Y1148129D03*
X1210728Y1155610D03*
X1221948Y1151869D03*
Y1144389D03*
X1218208Y1166830D03*
Y1159350D03*
X1221948Y1166830D03*
X1210728Y1170570D03*
X1206988D03*
X1218208Y1189271D03*
Y1174310D03*
X1221948Y1181791D03*
Y1174310D03*
X1218208Y1181791D03*
X1221948Y1189271D03*
X1236909Y1136909D03*
X1225688Y1140649D03*
X1229428D03*
X1236909Y1151870D03*
X1225688Y1148129D03*
X1229428D03*
X1225688Y1155610D03*
X1236909Y1144389D03*
X1229428Y1155610D03*
Y1170570D03*
X1225688D03*
X1236909Y1159350D03*
Y1181791D03*
X1225688Y1185531D03*
X1236909Y1189271D03*
X1229428Y1178051D03*
Y1185531D03*
X1236909Y1174310D03*
X1225688Y1178051D03*
Y1193011D03*
X1229428D03*
X1240649Y1136909D03*
Y1151870D03*
Y1144389D03*
Y1159350D03*
Y1174310D03*
Y1181791D03*
Y1189271D03*
X1339196Y441086D03*
Y433999D03*
Y437543D03*
X1336396Y441086D03*
Y433999D03*
Y437543D03*
X1339196Y444629D03*
X1336396D03*
X1415924Y620661D03*
Y617861D03*
X1423010Y620661D03*
X1419467Y617861D03*
X1423010D03*
X1426554Y620661D03*
Y617861D03*
X1419467Y620661D03*
X1514468Y1088287D03*
Y1099507D03*
Y1106988D03*
Y1121948D03*
Y1114468D03*
Y1129429D03*
Y1136909D03*
Y1148129D03*
Y1155610D03*
X1514467Y1170570D03*
Y1178051D03*
X1521949Y1073326D03*
X1529429D03*
Y1077066D03*
X1525689Y1084547D03*
X1529429Y1092027D03*
X1521949D03*
X1518208Y1088287D03*
X1525689Y1080807D03*
X1518208Y1099507D03*
X1525689D03*
X1529429Y1095767D03*
X1525689Y1103247D03*
X1518208Y1106988D03*
X1521949Y1095767D03*
Y1110728D03*
X1518208Y1114468D03*
X1525689Y1110728D03*
X1518208Y1121948D03*
X1521949Y1118208D03*
X1525689D03*
Y1125688D03*
X1518208Y1129429D03*
X1521949Y1125688D03*
X1518208Y1136909D03*
X1521949Y1133169D03*
X1518208Y1148129D03*
Y1155610D03*
X1518207Y1170570D03*
X1527559Y1176180D03*
X1518207Y1178051D03*
X1536909Y1073326D03*
X1533169Y1080807D03*
Y1084547D03*
X1540649Y1080807D03*
X1536909Y1077066D03*
X1540649Y1084547D03*
X1536909Y1092027D03*
Y1095767D03*
X1533169Y1099507D03*
X1540649Y1103247D03*
X1533169D03*
X1536909Y1118208D03*
X1533169D03*
Y1121948D03*
X1544389Y1114468D03*
X1536909Y1110728D03*
X1533169D03*
X1540649Y1114468D03*
X1536909Y1148129D03*
X1540649Y1151870D03*
Y1148129D03*
X1536909Y1144389D03*
Y1155610D03*
X1540649Y1159350D03*
Y1170570D03*
Y1174310D03*
Y1178050D03*
X1531299Y1176180D03*
X1559350Y1114468D03*
X1555610D03*
X1563090D03*
Y1140649D03*
Y1136909D03*
X1555610D03*
X1563090Y1129429D03*
Y1133169D03*
Y1144389D03*
Y1151869D03*
X1555610Y1144389D03*
X1548130Y1151870D03*
Y1148129D03*
Y1144389D03*
X1559350Y1155610D03*
X1555610Y1151870D03*
X1559350Y1148129D03*
X1563090Y1159350D03*
Y1170570D03*
X1548130Y1166830D03*
Y1159350D03*
X1555610Y1170570D03*
X1559350Y1166830D03*
X1555610Y1159350D03*
X1548130Y1174310D03*
Y1178051D03*
Y1181791D03*
X1563090Y1185531D03*
Y1178051D03*
X1555610Y1185531D03*
X1559350Y1174310D03*
Y1181791D03*
X1555610Y1178051D03*
X1563090Y1193011D03*
X1555610Y1215452D03*
X1563090D03*
X1559350D03*
X1574311Y1114468D03*
X1570571D03*
X1578051D03*
X1566830D03*
X1578051Y1136909D03*
X1574311D03*
X1570571D03*
X1574311Y1129429D03*
X1570571D03*
X1578051D03*
X1566830Y1140649D03*
X1578051Y1144389D03*
X1574311D03*
X1570571D03*
X1578051Y1151870D03*
X1574311D03*
X1570571D03*
X1574311Y1155610D03*
X1566830Y1148129D03*
Y1155610D03*
X1578051Y1170570D03*
X1574311Y1166830D03*
X1570571Y1170570D03*
X1566830Y1166830D03*
X1578051Y1159350D03*
X1570571D03*
X1574311Y1185531D03*
X1570571D03*
X1578051D03*
Y1178051D03*
X1574311D03*
X1570571D03*
X1574311Y1174310D03*
X1566830Y1181791D03*
Y1174310D03*
X1570571Y1193011D03*
X1574311D03*
X1578051D03*
X1570571Y1200491D03*
X1578051D03*
X1574311D03*
X1578051Y1215452D03*
X1566830D03*
X1570571Y1211712D03*
X1566830Y1219192D03*
X1574311Y1215452D03*
X1570571D03*
X1578051Y1211712D03*
X1574311D03*
X1593012Y1114468D03*
X1589271D03*
X1581791D03*
X1593011Y1136909D03*
X1589271D03*
X1585531D03*
X1581791D03*
X1589271Y1129429D03*
X1585531D03*
X1581791D03*
X1593011D03*
X1585531Y1144389D03*
X1581791D03*
X1593011D03*
X1589271D03*
X1593012Y1151870D03*
X1589271D03*
X1585531D03*
X1581791D03*
Y1155610D03*
X1589271D03*
X1593011Y1170570D03*
X1585531D03*
X1589271Y1166830D03*
X1581791D03*
X1585531Y1159350D03*
X1593011D03*
X1589271Y1185531D03*
X1585531D03*
X1581791D03*
X1593011D03*
X1581791Y1178051D03*
X1593011D03*
X1589271D03*
X1585531D03*
X1589271Y1174310D03*
X1581791D03*
X1585531Y1193011D03*
X1589271D03*
X1593011D03*
X1581791D03*
X1589271Y1200491D03*
X1585531D03*
X1581791D03*
X1593011D03*
X1593012Y1211712D03*
Y1215452D03*
X1581791D03*
X1589271D03*
X1585531D03*
Y1211712D03*
X1596752Y1114468D03*
X1607972D03*
X1611712Y1118208D03*
X1607972D03*
X1611712Y1114468D03*
X1600492Y1136909D03*
X1596752D03*
X1611712D03*
X1607972D03*
X1611712Y1129429D03*
X1607972D03*
X1600492D03*
X1596752D03*
X1600492Y1144389D03*
X1596752D03*
X1611712Y1151869D03*
X1607972D03*
X1611712Y1144389D03*
X1607972D03*
X1600492Y1151870D03*
X1596752D03*
Y1155610D03*
X1607972D03*
Y1166830D03*
X1611712Y1170570D03*
X1600492D03*
X1596752Y1166830D03*
X1611712Y1159350D03*
X1600492D03*
Y1185531D03*
X1596752D03*
X1600492Y1178051D03*
X1596752D03*
X1611712Y1185531D03*
X1607972D03*
X1611712Y1178051D03*
X1607972D03*
Y1174310D03*
X1596752D03*
X1607972Y1193011D03*
X1611712D03*
X1600492D03*
X1596752D03*
X1600492Y1200491D03*
X1596752D03*
X1611712D03*
X1607972D03*
X1600492Y1211712D03*
Y1215452D03*
X1596752Y1211712D03*
X1611712Y1215452D03*
X1607972D03*
Y1211712D03*
X1609842Y1217322D03*
X1615452Y1118208D03*
X1619193D03*
X1615452Y1114468D03*
X1619193D03*
X1622933D03*
X1626673D03*
Y1118208D03*
X1622933D03*
X1626673Y1136909D03*
X1622933D03*
X1615452D03*
X1619193D03*
X1626673Y1129429D03*
X1622933D03*
X1619193D03*
X1615452D03*
Y1151869D03*
X1619193D03*
X1626673D03*
X1622933D03*
Y1144389D03*
X1615452D03*
X1619193D03*
X1626673D03*
X1622933Y1155610D03*
X1615452D03*
Y1166830D03*
X1619193Y1170570D03*
X1626673Y1159350D03*
X1619193D03*
X1622933Y1166830D03*
X1626673Y1170570D03*
X1619193Y1185531D03*
X1626673D03*
X1622933D03*
Y1178051D03*
X1615452D03*
X1619193D03*
X1626673D03*
X1615452Y1185531D03*
X1622933Y1174310D03*
X1615452D03*
X1622933Y1193011D03*
X1626673D03*
X1615452D03*
X1619193D03*
X1622933Y1200491D03*
X1619193D03*
X1615452D03*
X1626673D03*
X1622933Y1215452D03*
X1619192Y1215451D03*
X1626673Y1215452D03*
X1615452D03*
X1613582Y1217322D03*
X1619192Y1211711D03*
X1622933D03*
X1637893Y1118208D03*
Y1114468D03*
X1634153D03*
X1630413D03*
X1641633D03*
X1634153Y1118208D03*
X1630413D03*
Y1136909D03*
X1637893D03*
X1634153D03*
X1630413Y1129429D03*
X1637893D03*
X1634153D03*
X1630413Y1151869D03*
X1637893D03*
X1634153D03*
Y1144389D03*
X1630413D03*
X1637893D03*
Y1155610D03*
X1630413D03*
X1637893Y1170570D03*
X1641633D03*
X1634153D03*
X1641633Y1166830D03*
X1637893D03*
Y1159350D03*
X1641633D03*
X1634153D03*
X1630413Y1166830D03*
X1641633Y1181791D03*
X1630413Y1185531D03*
X1634153D03*
X1630413Y1178051D03*
X1634153D03*
X1637893Y1185531D03*
Y1178051D03*
Y1174310D03*
X1630413D03*
X1634153Y1193011D03*
X1637893D03*
X1630413D03*
Y1200491D03*
X1637893D03*
X1634153D03*
X1630413Y1215452D03*
X1637893D03*
X1634153D03*
X1656594Y1118208D03*
X1652854D03*
Y1114468D03*
X1645374D03*
X1649114D03*
X1656594D03*
X1645374Y1129429D03*
Y1136909D03*
Y1140649D03*
X1656594Y1133169D03*
Y1140649D03*
Y1136909D03*
X1660334Y1140649D03*
X1649114Y1155610D03*
X1656594D03*
X1645374Y1144389D03*
X1660334Y1148129D03*
X1652854Y1144389D03*
X1656594Y1148129D03*
Y1144389D03*
X1649114Y1159350D03*
Y1170570D03*
Y1166830D03*
X1656594Y1170570D03*
Y1166830D03*
Y1159350D03*
Y1189271D03*
X1649114Y1174310D03*
X1656594D03*
X1652854Y1181791D03*
X1660334Y1189271D03*
X1645374Y1185531D03*
Y1189271D03*
X1660334Y1181791D03*
X1656594Y1178051D03*
X1645374D03*
Y1200491D03*
Y1193011D03*
X1656594Y1196751D03*
Y1204232D03*
X1652854Y1200491D03*
X1649114Y1204232D03*
Y1196751D03*
Y1200491D03*
X1656594D03*
X1645374Y1215452D03*
X1649114D03*
X1652854D03*
X1656594Y1211712D03*
X1645374D03*
X1656594Y1215452D03*
Y1207972D03*
X1649114D03*
X1652854D03*
Y1211712D03*
X1664075Y1140649D03*
X1667815Y1155610D03*
X1664075Y1148129D03*
Y1155610D03*
X1675295Y1144389D03*
Y1151869D03*
Y1166830D03*
Y1159350D03*
X1664075Y1170570D03*
X1667815D03*
X1675295Y1189271D03*
Y1174310D03*
Y1181791D03*
X1686515Y1140649D03*
X1682775D03*
X1679035Y1151869D03*
Y1144389D03*
X1682775Y1148129D03*
X1686515Y1155610D03*
Y1148129D03*
X1682775Y1155610D03*
X1679035Y1166830D03*
X1686515Y1170570D03*
X1682775D03*
X1679035Y1181791D03*
Y1189271D03*
Y1174310D03*
X1686515Y1185531D03*
X1682775Y1178051D03*
X1686515D03*
X1682775Y1185531D03*
X1686515Y1193011D03*
X1682775D03*
Y1222932D03*
X1693996Y1136909D03*
X1697736D03*
X1693996Y1151870D03*
X1697736D03*
X1693996Y1144389D03*
X1697736D03*
Y1159350D03*
X1693996D03*
X1697736Y1174310D03*
X1693996Y1189271D03*
X1697736D03*
Y1181791D03*
X1693996D03*
Y1174310D03*
X1796283Y441086D03*
Y433999D03*
Y437543D03*
X1793483Y441086D03*
Y433999D03*
Y437543D03*
X1796283Y444629D03*
X1793483D03*
G54D53*
X970071Y1365652D03*
Y1409152D03*
G54D33*
X109882Y1458622D03*
Y1463741D03*
Y1489331D03*
Y1494449D03*
Y1560985D03*
Y1566103D03*
Y1591693D03*
Y1596811D03*
Y1622402D03*
X127205Y1458622D03*
Y1463741D03*
X118543Y1452717D03*
Y1462953D03*
Y1468071D03*
X127205Y1489331D03*
Y1494449D03*
X118543Y1493662D03*
Y1498780D03*
X127205Y1560985D03*
Y1566103D03*
X118543Y1565315D03*
Y1570434D03*
X127205Y1591693D03*
X118543Y1596024D03*
X127205Y1596811D03*
X118543Y1601142D03*
X127205Y1622402D03*
X144528Y1458622D03*
Y1463741D03*
X135866Y1452717D03*
Y1462953D03*
Y1468071D03*
X144528Y1489331D03*
Y1494449D03*
X135866Y1493662D03*
Y1498780D03*
X144528Y1560985D03*
Y1566103D03*
X135866Y1565315D03*
Y1570434D03*
X144528Y1591693D03*
X135866Y1596024D03*
X144528Y1596811D03*
X135866Y1601142D03*
X144528Y1622402D03*
X161850Y1458622D03*
Y1463741D03*
X153189Y1452717D03*
Y1462953D03*
Y1468071D03*
X161850Y1489331D03*
Y1494449D03*
X153189Y1493662D03*
Y1498780D03*
X161850Y1560985D03*
Y1566103D03*
X153189Y1565315D03*
Y1570434D03*
X161850Y1591693D03*
X153189Y1596024D03*
X161850Y1596811D03*
X153189Y1601142D03*
X161850Y1622402D03*
X179173Y1458622D03*
Y1463741D03*
X170512Y1452717D03*
Y1462953D03*
X179173Y1473977D03*
Y1479095D03*
X170512Y1468071D03*
X179173Y1489331D03*
Y1494449D03*
X170512Y1493662D03*
Y1498780D03*
X179173Y1504685D03*
Y1509804D03*
Y1560985D03*
Y1566103D03*
Y1576339D03*
X170512Y1565315D03*
Y1570434D03*
X179173Y1581457D03*
Y1591693D03*
X170512Y1596024D03*
X179173Y1596811D03*
Y1607048D03*
Y1612166D03*
X170512Y1601142D03*
X179173Y1622402D03*
X187835Y1452717D03*
Y1462953D03*
Y1468071D03*
Y1478308D03*
Y1483426D03*
Y1493662D03*
Y1498780D03*
Y1509016D03*
Y1514134D03*
Y1565315D03*
Y1570434D03*
Y1580670D03*
Y1585788D03*
Y1596024D03*
Y1601142D03*
Y1611378D03*
Y1616496D03*
X291771Y1452717D03*
X283110Y1473977D03*
X291771Y1478308D03*
X283110Y1479095D03*
X291771Y1483426D03*
X283110Y1504685D03*
X291771Y1509016D03*
X283110Y1509804D03*
X291771Y1514134D03*
X283110Y1560985D03*
X291771Y1565315D03*
X283110Y1566103D03*
X291771Y1570434D03*
X283110Y1607048D03*
X291771Y1611378D03*
X283110Y1612166D03*
X291771Y1616496D03*
X283110Y1622402D03*
X309094Y1452717D03*
X300433Y1473977D03*
X309094Y1478308D03*
X300433Y1479095D03*
X309094Y1483426D03*
X300433Y1504685D03*
X309094Y1509016D03*
X300433Y1509804D03*
X309094Y1514134D03*
X300433Y1560985D03*
X309094Y1565315D03*
X300433Y1566103D03*
X309094Y1570434D03*
X300433Y1607048D03*
X309094Y1611378D03*
X300433Y1612166D03*
X309094Y1616496D03*
X300433Y1622402D03*
X326417Y1452717D03*
X317756Y1473977D03*
X326417Y1478308D03*
X317756Y1479095D03*
X326417Y1483426D03*
X317756Y1504685D03*
X326417Y1509016D03*
X317756Y1509804D03*
X326417Y1514134D03*
X317756Y1560985D03*
X326417Y1565315D03*
X317756Y1566103D03*
X326417Y1570434D03*
X317756Y1607048D03*
X326417Y1611378D03*
X317756Y1612166D03*
X326417Y1616496D03*
X317756Y1622402D03*
X343740Y1452717D03*
X335078Y1473977D03*
X343740Y1478308D03*
X335078Y1479095D03*
X343740Y1483426D03*
X335078Y1504685D03*
X343740Y1509016D03*
X335078Y1509804D03*
X343740Y1514134D03*
X335078Y1560985D03*
X343740Y1565315D03*
X335078Y1566103D03*
X343740Y1570434D03*
X335078Y1607048D03*
X343740Y1611378D03*
X335078Y1612166D03*
X343740Y1616496D03*
X335078Y1622402D03*
X361063Y1452717D03*
X352401Y1458622D03*
Y1463741D03*
X361063Y1462953D03*
Y1468071D03*
X352401Y1473977D03*
Y1479095D03*
X361063Y1478308D03*
Y1483426D03*
X352401Y1489331D03*
Y1494449D03*
X361063Y1493662D03*
Y1498780D03*
X352401Y1504685D03*
Y1509804D03*
X361063Y1509016D03*
Y1514134D03*
X352401Y1560985D03*
Y1566103D03*
X361063Y1565315D03*
Y1570434D03*
X352401Y1576339D03*
Y1581457D03*
X361063Y1580670D03*
Y1585788D03*
X352401Y1591693D03*
X361063Y1596024D03*
X352401Y1596811D03*
X361063Y1601142D03*
X352401Y1607048D03*
Y1612166D03*
X361063Y1611378D03*
Y1616496D03*
X352401Y1622402D03*
X456339Y1458622D03*
Y1463741D03*
Y1489331D03*
Y1494449D03*
Y1576339D03*
Y1581457D03*
Y1607048D03*
Y1612166D03*
Y1622402D03*
X473662Y1458622D03*
Y1463741D03*
X465000Y1452717D03*
Y1462953D03*
Y1468071D03*
X473662Y1489331D03*
Y1494449D03*
X465000Y1493662D03*
Y1498780D03*
X473662Y1576339D03*
Y1581457D03*
X465000Y1580670D03*
Y1585788D03*
X473662Y1607048D03*
Y1612166D03*
X465000Y1611378D03*
X473662Y1622402D03*
X465000Y1616496D03*
X490985Y1458622D03*
Y1463741D03*
X482323Y1452717D03*
Y1462953D03*
Y1468071D03*
X490985Y1489331D03*
Y1494449D03*
X482323Y1493662D03*
Y1498780D03*
X490985Y1576339D03*
Y1581457D03*
X482323Y1580670D03*
Y1585788D03*
X490985Y1607048D03*
Y1612166D03*
X482323Y1611378D03*
X490985Y1622402D03*
X482323Y1616496D03*
X499646Y1452717D03*
Y1462953D03*
Y1468071D03*
Y1493662D03*
Y1498780D03*
Y1580670D03*
Y1585788D03*
Y1611378D03*
Y1616496D03*
X516969Y1452717D03*
X508307Y1458622D03*
X516969Y1462953D03*
X508307Y1463741D03*
X516969Y1468071D03*
X508307Y1489331D03*
X516969Y1493662D03*
X508307Y1494449D03*
X516969Y1498780D03*
X508307Y1576339D03*
X516969Y1580670D03*
X508307Y1581457D03*
X516969Y1585788D03*
X508307Y1607048D03*
X516969Y1611378D03*
X508307Y1612166D03*
X516969Y1616496D03*
X508307Y1622402D03*
X534292Y1452717D03*
X525630Y1458622D03*
Y1463741D03*
X534292Y1462953D03*
Y1468071D03*
X525630Y1473977D03*
Y1479095D03*
X534292Y1478308D03*
Y1483426D03*
X525630Y1489331D03*
Y1494449D03*
X534292Y1493662D03*
Y1498780D03*
X525630Y1504685D03*
Y1509804D03*
X534292Y1509016D03*
Y1514134D03*
X525630Y1560985D03*
Y1566103D03*
X534292Y1565315D03*
Y1570434D03*
X525630Y1576339D03*
Y1581457D03*
X534292Y1580670D03*
Y1585788D03*
X525630Y1591693D03*
X534292Y1596024D03*
X525630Y1596811D03*
X534292Y1601142D03*
X525630Y1607048D03*
Y1612166D03*
X534292Y1611378D03*
Y1616496D03*
X525630Y1622402D03*
X629567Y1473977D03*
Y1479095D03*
Y1504685D03*
Y1509804D03*
Y1576339D03*
Y1581457D03*
Y1607048D03*
Y1612166D03*
Y1622402D03*
X638228Y1452717D03*
X646890Y1473977D03*
Y1479095D03*
X638228Y1478308D03*
Y1483426D03*
X646890Y1504685D03*
Y1509804D03*
X638228Y1509016D03*
Y1514134D03*
X646890Y1576339D03*
Y1581457D03*
X638228Y1580670D03*
Y1585788D03*
X646890Y1607048D03*
Y1612166D03*
X638228Y1611378D03*
X646890Y1622402D03*
X638228Y1616496D03*
X655551Y1452717D03*
X664213Y1473977D03*
Y1479095D03*
X655551Y1478308D03*
Y1483426D03*
X664213Y1504685D03*
Y1509804D03*
X655551Y1509016D03*
Y1514134D03*
X664213Y1576339D03*
Y1581457D03*
X655551Y1580670D03*
Y1585788D03*
X664213Y1607048D03*
Y1612166D03*
X655551Y1611378D03*
X664213Y1622402D03*
X655551Y1616496D03*
X672874Y1452717D03*
X681535Y1473977D03*
Y1479095D03*
X672874Y1478308D03*
Y1483426D03*
X681535Y1504685D03*
Y1509804D03*
X672874Y1509016D03*
Y1514134D03*
X681535Y1576339D03*
Y1581457D03*
X672874Y1580670D03*
Y1585788D03*
X681535Y1607048D03*
Y1612166D03*
X672874Y1611378D03*
X681535Y1622402D03*
X672874Y1616496D03*
X698858Y1458622D03*
Y1463741D03*
X690197Y1452717D03*
X698858Y1473977D03*
Y1479095D03*
X690197Y1478308D03*
X698858Y1489331D03*
Y1494449D03*
X690197Y1483426D03*
X698858Y1504685D03*
Y1509804D03*
X690197Y1509016D03*
Y1514134D03*
X698858Y1560985D03*
Y1566103D03*
Y1576339D03*
Y1581457D03*
Y1591693D03*
X690197Y1580670D03*
Y1585788D03*
X698858Y1596811D03*
Y1607048D03*
Y1612166D03*
X690197Y1611378D03*
X698858Y1622402D03*
X690197Y1616496D03*
X707520Y1452717D03*
Y1462953D03*
Y1468071D03*
Y1478308D03*
Y1483426D03*
Y1493662D03*
Y1498780D03*
Y1509016D03*
Y1514134D03*
Y1565315D03*
Y1570434D03*
Y1580670D03*
Y1585788D03*
Y1596024D03*
Y1601142D03*
Y1611378D03*
Y1616496D03*
X1140511Y1452717D03*
X1131850Y1458622D03*
X1140511Y1462953D03*
X1131850Y1463741D03*
X1140511Y1468071D03*
X1131850Y1489331D03*
X1140511Y1493662D03*
X1131850Y1494449D03*
X1140511Y1498780D03*
X1131850Y1560985D03*
X1140511Y1565315D03*
X1131850Y1566103D03*
X1140511Y1570434D03*
X1131850Y1591693D03*
X1140511Y1596024D03*
X1131850Y1596811D03*
X1140511Y1601142D03*
X1131850Y1622402D03*
X1149173Y1458622D03*
Y1463741D03*
Y1489331D03*
Y1494449D03*
Y1560985D03*
Y1566103D03*
Y1591693D03*
Y1596811D03*
Y1622402D03*
X1166496Y1458622D03*
Y1463741D03*
X1157834Y1452717D03*
Y1462953D03*
Y1468071D03*
X1166496Y1489331D03*
Y1494449D03*
X1157834Y1493662D03*
Y1498780D03*
X1166496Y1560985D03*
Y1566103D03*
X1157834Y1565315D03*
Y1570434D03*
X1166496Y1591693D03*
X1157834Y1596024D03*
X1166496Y1596811D03*
X1157834Y1601142D03*
X1166496Y1622402D03*
X1183818Y1458622D03*
Y1463741D03*
X1175157Y1452717D03*
Y1462953D03*
Y1468071D03*
X1183818Y1489331D03*
Y1494449D03*
X1175157Y1493662D03*
Y1498780D03*
X1183818Y1560985D03*
Y1566103D03*
X1175157Y1565315D03*
Y1570434D03*
X1183818Y1591693D03*
X1175157Y1596024D03*
X1183818Y1596811D03*
X1175157Y1601142D03*
X1183818Y1622402D03*
X1201141Y1458622D03*
Y1463741D03*
X1192480Y1452717D03*
Y1462953D03*
X1201141Y1473977D03*
Y1479095D03*
X1192480Y1468071D03*
X1201141Y1489331D03*
Y1494449D03*
X1192480Y1493662D03*
Y1498780D03*
X1201141Y1504685D03*
Y1509804D03*
Y1560985D03*
Y1566103D03*
Y1576339D03*
X1192480Y1565315D03*
Y1570434D03*
X1201141Y1581457D03*
Y1591693D03*
X1192480Y1596024D03*
X1201141Y1596811D03*
Y1607048D03*
Y1612166D03*
X1192480Y1601142D03*
X1201141Y1622402D03*
X1209803Y1452717D03*
Y1462953D03*
Y1468071D03*
Y1478308D03*
Y1483426D03*
Y1493662D03*
Y1498780D03*
Y1509016D03*
Y1514134D03*
Y1565315D03*
Y1570434D03*
Y1580670D03*
Y1585788D03*
Y1596024D03*
Y1601142D03*
Y1611378D03*
Y1616496D03*
X1313740Y1452717D03*
X1305079Y1473977D03*
X1313740Y1478308D03*
X1305079Y1479095D03*
X1313740Y1483426D03*
X1305079Y1504685D03*
X1313740Y1509016D03*
X1305079Y1509804D03*
X1313740Y1514134D03*
X1305079Y1560985D03*
X1313740Y1565315D03*
X1305079Y1566103D03*
X1313740Y1570434D03*
X1305079Y1607048D03*
X1313740Y1611378D03*
X1305079Y1612166D03*
X1313740Y1616496D03*
X1305079Y1622402D03*
X1331063Y1452717D03*
X1322402Y1473977D03*
X1331063Y1478308D03*
X1322402Y1479095D03*
X1331063Y1483426D03*
X1322402Y1504685D03*
X1331063Y1509016D03*
X1322402Y1509804D03*
X1331063Y1514134D03*
X1322402Y1560985D03*
X1331063Y1565315D03*
X1322402Y1566103D03*
X1331063Y1570434D03*
X1322402Y1607048D03*
X1331063Y1611378D03*
X1322402Y1612166D03*
X1331063Y1616496D03*
X1322402Y1622402D03*
X1348386Y1452717D03*
X1339725Y1473977D03*
X1348386Y1478308D03*
X1339725Y1479095D03*
X1348386Y1483426D03*
X1339725Y1504685D03*
X1348386Y1509016D03*
X1339725Y1509804D03*
X1348386Y1514134D03*
X1339725Y1560985D03*
X1348386Y1565315D03*
X1339725Y1566103D03*
X1348386Y1570434D03*
X1339725Y1607048D03*
X1348386Y1611378D03*
X1339725Y1612166D03*
X1348386Y1616496D03*
X1339725Y1622402D03*
X1365709Y1452717D03*
X1357047Y1473977D03*
X1365709Y1478308D03*
X1357047Y1479095D03*
X1365709Y1483426D03*
X1357047Y1504685D03*
X1365709Y1509016D03*
X1357047Y1509804D03*
X1365709Y1514134D03*
X1357047Y1560985D03*
X1365709Y1565315D03*
X1357047Y1566103D03*
X1365709Y1570434D03*
X1357047Y1607048D03*
X1365709Y1611378D03*
X1357047Y1612166D03*
X1365709Y1616496D03*
X1357047Y1622402D03*
X1383032Y1452717D03*
X1374370Y1458622D03*
Y1463741D03*
X1383032Y1462953D03*
Y1468071D03*
X1374370Y1473977D03*
Y1479095D03*
X1383032Y1478308D03*
Y1483426D03*
X1374370Y1489331D03*
Y1494449D03*
X1383032Y1493662D03*
Y1498780D03*
X1374370Y1504685D03*
Y1509804D03*
X1383032Y1509016D03*
Y1514134D03*
X1374370Y1560985D03*
Y1566103D03*
X1383032Y1565315D03*
Y1570434D03*
X1374370Y1576339D03*
Y1581457D03*
X1383032Y1580670D03*
Y1585788D03*
X1374370Y1591693D03*
X1383032Y1596024D03*
X1374370Y1596811D03*
X1383032Y1601142D03*
X1374370Y1607048D03*
Y1612166D03*
X1383032Y1611378D03*
Y1616496D03*
X1374370Y1622402D03*
X1478307Y1458622D03*
Y1463741D03*
Y1489331D03*
Y1494449D03*
Y1576339D03*
Y1581457D03*
Y1607048D03*
Y1612166D03*
Y1622402D03*
X1495630Y1458622D03*
Y1463741D03*
X1486968Y1452717D03*
Y1462953D03*
Y1468071D03*
X1495630Y1489331D03*
Y1494449D03*
X1486968Y1493662D03*
Y1498780D03*
X1495630Y1576339D03*
Y1581457D03*
X1486968Y1580670D03*
Y1585788D03*
X1495630Y1607048D03*
Y1612166D03*
X1486968Y1611378D03*
X1495630Y1622402D03*
X1486968Y1616496D03*
X1512953Y1458622D03*
Y1463741D03*
X1504291Y1452717D03*
Y1462953D03*
Y1468071D03*
X1512953Y1489331D03*
Y1494449D03*
X1504291Y1493662D03*
Y1498780D03*
X1512953Y1576339D03*
Y1581457D03*
X1504291Y1580670D03*
Y1585788D03*
X1512953Y1607048D03*
Y1612166D03*
X1504291Y1611378D03*
X1512953Y1622402D03*
X1504291Y1616496D03*
X1530275Y1458622D03*
Y1463741D03*
X1521614Y1452717D03*
Y1462953D03*
Y1468071D03*
X1530275Y1489331D03*
Y1494449D03*
X1521614Y1493662D03*
Y1498780D03*
X1530275Y1576339D03*
Y1581457D03*
X1521614Y1580670D03*
Y1585788D03*
X1530275Y1607048D03*
Y1612166D03*
X1521614Y1611378D03*
X1530275Y1622402D03*
X1521614Y1616496D03*
X1538937Y1452717D03*
Y1462953D03*
Y1468071D03*
Y1493662D03*
Y1498780D03*
Y1580670D03*
Y1585788D03*
Y1611378D03*
Y1616496D03*
X1556260Y1452717D03*
X1547598Y1458622D03*
Y1463741D03*
X1556260Y1462953D03*
Y1468071D03*
X1547598Y1473977D03*
Y1479095D03*
X1556260Y1478308D03*
Y1483426D03*
X1547598Y1489331D03*
Y1494449D03*
X1556260Y1493662D03*
Y1498780D03*
X1547598Y1504685D03*
Y1509804D03*
X1556260Y1509016D03*
Y1514134D03*
X1547598Y1560985D03*
Y1566103D03*
X1556260Y1565315D03*
Y1570434D03*
X1547598Y1576339D03*
Y1581457D03*
X1556260Y1580670D03*
Y1585788D03*
X1547598Y1591693D03*
X1556260Y1596024D03*
X1547598Y1596811D03*
X1556260Y1601142D03*
X1547598Y1607048D03*
Y1612166D03*
X1556260Y1611378D03*
Y1616496D03*
X1547598Y1622402D03*
X1660196Y1452717D03*
X1651535Y1473977D03*
X1660196Y1478308D03*
X1651535Y1479095D03*
X1660196Y1483426D03*
X1651535Y1504685D03*
X1660196Y1509016D03*
X1651535Y1509804D03*
X1660196Y1514134D03*
X1651535Y1576339D03*
X1660196Y1580670D03*
X1651535Y1581457D03*
X1660196Y1585788D03*
X1651535Y1607048D03*
X1660196Y1611378D03*
X1651535Y1612166D03*
X1660196Y1616496D03*
X1651535Y1622402D03*
X1668858Y1473977D03*
Y1479095D03*
Y1504685D03*
Y1509804D03*
Y1576339D03*
Y1581457D03*
Y1607048D03*
Y1612166D03*
Y1622402D03*
X1677519Y1452717D03*
X1686181Y1473977D03*
Y1479095D03*
X1677519Y1478308D03*
Y1483426D03*
X1686181Y1504685D03*
Y1509804D03*
X1677519Y1509016D03*
Y1514134D03*
X1686181Y1576339D03*
Y1581457D03*
X1677519Y1580670D03*
Y1585788D03*
X1686181Y1607048D03*
Y1612166D03*
X1677519Y1611378D03*
X1686181Y1622402D03*
X1677519Y1616496D03*
X1694842Y1452717D03*
X1703503Y1473977D03*
Y1479095D03*
X1694842Y1478308D03*
Y1483426D03*
X1703503Y1504685D03*
Y1509804D03*
X1694842Y1509016D03*
Y1514134D03*
X1703503Y1576339D03*
Y1581457D03*
X1694842Y1580670D03*
Y1585788D03*
X1703503Y1607048D03*
Y1612166D03*
X1694842Y1611378D03*
X1703503Y1622402D03*
X1694842Y1616496D03*
X1720826Y1458622D03*
Y1463741D03*
X1712165Y1452717D03*
X1720826Y1473977D03*
Y1479095D03*
X1712165Y1478308D03*
X1720826Y1489331D03*
Y1494449D03*
X1712165Y1483426D03*
X1720826Y1504685D03*
Y1509804D03*
X1712165Y1509016D03*
Y1514134D03*
X1720826Y1560985D03*
Y1566103D03*
Y1576339D03*
Y1581457D03*
Y1591693D03*
X1712165Y1580670D03*
Y1585788D03*
X1720826Y1596811D03*
Y1607048D03*
Y1612166D03*
X1712165Y1611378D03*
X1720826Y1622402D03*
X1712165Y1616496D03*
X1729488Y1452717D03*
Y1462953D03*
Y1468071D03*
Y1478308D03*
Y1483426D03*
Y1493662D03*
Y1498780D03*
Y1509016D03*
Y1514134D03*
Y1565315D03*
Y1570434D03*
Y1580670D03*
Y1585788D03*
Y1596024D03*
Y1601142D03*
Y1611378D03*
Y1616496D03*
G54D54*
X1030635Y754546D03*
Y774546D03*
Y784546D03*
Y794546D03*
Y804546D03*
Y814546D03*
Y824546D03*
G54D28*
X76112Y1348187D03*
X79512D03*
X76112Y1360099D03*
X79512D03*
X100592Y1348187D03*
Y1360099D03*
X91752Y1372385D03*
X88352D03*
Y1384297D03*
X91752D03*
X100592Y1396583D03*
Y1408495D03*
X103992Y1348187D03*
Y1360099D03*
X112832Y1384297D03*
X116232Y1372385D03*
Y1384297D03*
X112832Y1372385D03*
X103992Y1396583D03*
Y1408495D03*
X125072Y1348187D03*
X128472D03*
Y1360099D03*
X125072D03*
Y1396583D03*
X128472D03*
X125072Y1408495D03*
X128472D03*
X149552Y1348187D03*
Y1360099D03*
X140712Y1372385D03*
Y1384297D03*
X137312D03*
Y1372385D03*
X149552Y1396583D03*
Y1408495D03*
X152952Y1348187D03*
Y1360099D03*
X161792Y1384297D03*
X165192Y1372385D03*
Y1384297D03*
X161792Y1372385D03*
X152952Y1396583D03*
Y1408495D03*
X177432Y1348187D03*
X174032D03*
Y1360099D03*
X177432D03*
Y1396583D03*
X174032D03*
X177432Y1408495D03*
X174032D03*
X198512Y1348187D03*
Y1360099D03*
X186272Y1384297D03*
X189672D03*
Y1372385D03*
X186272D03*
X198512Y1396583D03*
Y1408495D03*
X201912Y1348187D03*
Y1360099D03*
Y1396583D03*
Y1408495D03*
X241623Y1348187D03*
X245023D03*
Y1360099D03*
X241623D03*
X253863Y1372385D03*
X257263D03*
X253863Y1384297D03*
X257263D03*
X281594Y1211712D03*
X270374Y1215452D03*
X269503Y1348187D03*
X266103D03*
Y1360099D03*
X269503D03*
X278343Y1372385D03*
Y1384297D03*
X269503Y1396583D03*
X266103D03*
X269503Y1408495D03*
X266103D03*
X293983Y1348187D03*
X290583D03*
X293983Y1360099D03*
X290583D03*
X281743Y1372385D03*
Y1384297D03*
X293983Y1396583D03*
X290583D03*
X293983Y1408495D03*
X290583D03*
X306223Y1372385D03*
X302823D03*
X306223Y1384297D03*
X302823D03*
X315063Y1348187D03*
X318463D03*
X315063Y1360099D03*
X318463D03*
X327303Y1372385D03*
Y1384297D03*
X315063Y1396583D03*
X318463D03*
Y1408495D03*
X315063D03*
X339543Y1348187D03*
X342943D03*
Y1360099D03*
X339543D03*
X330703Y1372385D03*
Y1384297D03*
X339543Y1396583D03*
X342943D03*
Y1408495D03*
X339543D03*
X351783Y1372385D03*
X355183D03*
Y1384297D03*
X351783D03*
X364023Y1348187D03*
X367423D03*
Y1360099D03*
X364023D03*
Y1396583D03*
X367423D03*
X364023Y1408495D03*
X367423D03*
X393094Y1423600D03*
X395894D03*
X440402Y1348187D03*
Y1360099D03*
X443802Y1348187D03*
Y1360099D03*
X452642Y1372385D03*
X456042D03*
X452642Y1384297D03*
X456042D03*
X468282Y1348187D03*
X464882D03*
X468282Y1360099D03*
X464882D03*
X468282Y1396583D03*
X464882D03*
Y1408495D03*
X468282D03*
X489362Y1348187D03*
Y1360099D03*
X477122Y1372385D03*
X480522D03*
Y1384297D03*
X477122D03*
X489362Y1396583D03*
Y1408495D03*
X492762Y1348187D03*
Y1360099D03*
X505002Y1372385D03*
X501602D03*
X505002Y1384297D03*
X501602D03*
X492762Y1396583D03*
Y1408495D03*
X517242Y1348187D03*
X513842D03*
Y1360099D03*
X517242D03*
Y1396583D03*
X513842D03*
X517242Y1408495D03*
X513842D03*
X538322Y1348187D03*
Y1360099D03*
X529482Y1372385D03*
Y1384297D03*
X526082Y1372385D03*
Y1384297D03*
X538322Y1396583D03*
Y1408495D03*
X541722Y1348187D03*
Y1360099D03*
X550562Y1372385D03*
X553962Y1384297D03*
X550562D03*
X553962Y1372385D03*
X541722Y1396583D03*
Y1408495D03*
X562802Y1348187D03*
X566202D03*
Y1360099D03*
X562802D03*
X566202Y1396583D03*
X562802D03*
X566202Y1408495D03*
X562802D03*
X629688Y1396583D03*
X626288D03*
Y1408495D03*
X629688D03*
X650768Y1384297D03*
Y1372385D03*
X641928Y1396583D03*
X638528D03*
Y1408495D03*
X641928D03*
X666408Y1348187D03*
X663008D03*
X666408Y1360099D03*
X663008D03*
X654168Y1384297D03*
Y1372385D03*
X666408Y1396583D03*
X663008D03*
X666408Y1408495D03*
X663008D03*
X675248Y1384297D03*
X678648D03*
Y1372385D03*
X675248D03*
X690888Y1348187D03*
X687488D03*
Y1360099D03*
X690888D03*
X699728Y1372385D03*
Y1384297D03*
X690888Y1396583D03*
X687488D03*
Y1408495D03*
X690888D03*
X715368Y1348187D03*
X711968D03*
X715368Y1360099D03*
X711968D03*
X703128Y1372385D03*
Y1384297D03*
X715368Y1396583D03*
X711968D03*
X715368Y1408495D03*
X711968D03*
X724208Y1372385D03*
Y1384297D03*
X727608D03*
Y1372385D03*
X739848Y1348187D03*
X736448D03*
Y1360099D03*
X739848D03*
X748688Y1372385D03*
Y1384297D03*
X739848Y1396489D03*
X736448D03*
X739848Y1408401D03*
X736448D03*
X760928Y1348187D03*
X764328D03*
Y1360099D03*
X760928D03*
X752088Y1372385D03*
Y1384297D03*
X878220Y848442D03*
Y845293D03*
Y835844D03*
Y851592D03*
X877800Y876500D03*
X897118Y848442D03*
X881370Y835844D03*
X893968Y845293D03*
X884519Y848442D03*
X897118Y842143D03*
X893968D03*
X887669Y848442D03*
X886093Y835318D03*
X897118Y845293D03*
X893968Y838994D03*
X890818Y842143D03*
X893968Y835846D03*
X887669Y845293D03*
X890818D03*
X893968Y848442D03*
X884519Y845293D03*
X881370D03*
X884519Y842143D03*
X887669D03*
X881370Y848442D03*
X890818D03*
X887669Y851592D03*
X890818Y854742D03*
X887669D03*
X897118Y851592D03*
X890818Y864189D03*
Y857891D03*
X887669Y864189D03*
X884519Y854742D03*
Y851592D03*
Y857891D03*
X887669D03*
X890818Y851592D03*
X893967Y851591D03*
X881370Y851592D03*
X887669Y867338D03*
X890818Y870488D03*
X887669D03*
X897118Y876787D03*
X890818Y867338D03*
X881370D03*
X897118Y879937D03*
X884519Y873638D03*
X887669D03*
X884519Y876787D03*
X890818Y879937D03*
X881370Y876787D03*
X887669Y879937D03*
X884519Y867338D03*
X890818Y873638D03*
X893968Y876787D03*
Y879937D03*
X890818Y876787D03*
X884519Y879937D03*
Y870488D03*
X881370D03*
Y883086D03*
X884585Y886354D03*
X885126Y889742D03*
X881370Y886236D03*
X906565Y848442D03*
X900267D03*
X906565Y838994D03*
X900267Y838992D03*
X909714Y848442D03*
X906565Y842143D03*
X900267Y845293D03*
Y842143D03*
X906565Y845293D03*
X900266Y835844D03*
X900267Y851592D03*
X906565D03*
X909714D03*
Y876787D03*
X900267Y879937D03*
Y876787D03*
X906565D03*
X912864Y873638D03*
Y879937D03*
X909714D03*
X906565D03*
X912864Y876787D03*
X922313Y845293D03*
X916014Y848442D03*
Y842143D03*
X919163Y845293D03*
X922313Y842143D03*
X916014Y845293D03*
X919163Y835844D03*
Y838994D03*
Y842143D03*
X925462Y845293D03*
X919163Y854742D03*
Y857891D03*
X922313Y854742D03*
X916014Y857891D03*
Y854742D03*
Y851592D03*
Y864189D03*
X925462Y851592D03*
X922313Y864189D03*
Y857891D03*
X925462D03*
X928612Y864189D03*
X919163D03*
X925462D03*
X916014Y870488D03*
X925462Y873638D03*
X922313Y876787D03*
X928612Y870488D03*
X925462D03*
X916014Y873638D03*
X922313D03*
X916014Y876787D03*
X928612Y873638D03*
X925462Y876787D03*
X928612D03*
Y879937D03*
X916014D03*
X922313D03*
X919163D03*
X925462D03*
X916014Y867338D03*
X919163Y873638D03*
Y870488D03*
X922313D03*
X919163Y876787D03*
X922313Y867338D03*
X919163D03*
X925462D03*
X922313Y883086D03*
Y886236D03*
X925462D03*
X919163Y883086D03*
X928612Y886236D03*
X925462Y883086D03*
X928612D03*
X1058113Y1348187D03*
X1054713D03*
X1058113Y1360099D03*
X1054713D03*
X1066953Y1384297D03*
Y1372385D03*
X1070353D03*
Y1384297D03*
X1082593Y1348187D03*
X1079193D03*
X1082593Y1360099D03*
X1079193D03*
X1091433Y1384297D03*
Y1372385D03*
X1082593Y1396583D03*
X1079193D03*
X1082593Y1408495D03*
X1079193D03*
X1107073Y1348187D03*
X1103673D03*
Y1360099D03*
X1107073D03*
X1094833Y1384297D03*
Y1372385D03*
X1107073Y1396583D03*
X1103673D03*
X1107073Y1408495D03*
X1103673D03*
X1119313Y1384297D03*
X1115913Y1372385D03*
X1119313D03*
X1115913Y1384297D03*
X1131553Y1348187D03*
X1128153D03*
X1131553Y1360099D03*
X1128153D03*
X1140393Y1384297D03*
Y1372385D03*
X1131553Y1396583D03*
X1128153D03*
Y1408495D03*
X1131553D03*
X1156033Y1348187D03*
X1152633D03*
Y1360099D03*
X1156033D03*
X1143793Y1372385D03*
Y1384297D03*
X1156033Y1396583D03*
X1152633D03*
Y1408495D03*
X1156033D03*
X1168273Y1384297D03*
X1164873D03*
X1168273Y1372385D03*
X1164873D03*
X1184547Y1215452D03*
X1177113Y1348187D03*
X1180513D03*
X1177113Y1360099D03*
X1180513D03*
Y1396583D03*
X1177113D03*
Y1408495D03*
X1180513D03*
X1230326Y1348187D03*
X1233726D03*
X1230326Y1360099D03*
X1233726D03*
X1254806Y1348187D03*
Y1360099D03*
X1242566Y1372385D03*
X1245966D03*
X1242566Y1384297D03*
X1245966D03*
X1254806Y1396583D03*
Y1408495D03*
X1258206Y1348187D03*
Y1360099D03*
X1270446Y1372385D03*
X1267046D03*
X1270446Y1384297D03*
X1267046D03*
X1258206Y1396583D03*
Y1408495D03*
X1282686Y1348187D03*
X1279286D03*
Y1360099D03*
X1282686D03*
X1279286Y1396583D03*
X1282686D03*
X1279286Y1408495D03*
X1282686D03*
X1291526Y1372385D03*
X1294926D03*
X1291526Y1384297D03*
X1294926D03*
X1316906Y829871D03*
Y833021D03*
Y848769D03*
X1313756Y833021D03*
Y836170D03*
X1316906Y839320D03*
X1310555Y848675D03*
X1313756Y848769D03*
X1316906Y836170D03*
X1313756Y842470D03*
Y858218D03*
X1316906Y855068D03*
X1313756Y855066D03*
X1316906Y858218D03*
X1307166Y1348187D03*
X1303766D03*
X1307166Y1360099D03*
X1303766D03*
X1316006Y1372385D03*
X1319406D03*
X1316006Y1384297D03*
X1319406D03*
X1303766Y1396583D03*
X1307166D03*
Y1408495D03*
X1303766D03*
X1335803Y829871D03*
X1323205D03*
X1326355Y839320D03*
X1335803D03*
X1329504Y833021D03*
X1332654Y842470D03*
X1329504Y845619D03*
X1332654D03*
X1326355Y836170D03*
X1335803Y842470D03*
X1329504Y836170D03*
X1335803Y845619D03*
Y848769D03*
X1329504Y839320D03*
X1323205Y836170D03*
X1335803D03*
X1329504Y842470D03*
X1335803Y833021D03*
X1323205D03*
X1320055Y845619D03*
X1326355D03*
X1320055Y836170D03*
X1326355Y842470D03*
X1320055Y848769D03*
X1323205Y845619D03*
X1332654Y848769D03*
X1320055Y839320D03*
X1326355Y848769D03*
X1323205D03*
X1329504D03*
X1323204Y839319D03*
X1332654Y839320D03*
X1320055Y842470D03*
X1323205D03*
X1329504Y855068D03*
Y858218D03*
X1320055Y851918D03*
X1332654Y855068D03*
X1326355D03*
Y858218D03*
X1329504Y861367D03*
X1323205Y858218D03*
X1320055D03*
X1332654Y861367D03*
X1329504Y851918D03*
X1323205D03*
X1326355Y861367D03*
X1320055Y855068D03*
X1332654Y858218D03*
X1335803Y855068D03*
Y858218D03*
Y861367D03*
X1320055D03*
X1323204Y855067D03*
X1326355Y851918D03*
X1332654D03*
X1326355Y880263D03*
X1329504Y877114D03*
X1335803Y880263D03*
X1326355Y867665D03*
Y870814D03*
X1323205D03*
X1320055D03*
X1329504Y867665D03*
X1326355Y873964D03*
X1332654Y880263D03*
X1329504D03*
X1332654Y877114D03*
X1326355D03*
X1329504Y870814D03*
X1320055Y873964D03*
X1332654Y870814D03*
X1323204Y873965D03*
X1332654Y867665D03*
X1320055Y880263D03*
Y867665D03*
X1323205Y880263D03*
Y877114D03*
X1320055D03*
X1335803Y867665D03*
Y873964D03*
Y870814D03*
X1332654Y873964D03*
X1329504D03*
X1323205Y867665D03*
Y886562D03*
X1326355Y889712D03*
X1335803Y883413D03*
X1329504Y892862D03*
X1332654Y889712D03*
X1335803Y892862D03*
Y889712D03*
X1326355Y892862D03*
X1329504Y889712D03*
X1320055Y892862D03*
X1323205D03*
X1329504Y886562D03*
X1332654Y883413D03*
X1320055Y886562D03*
X1326355Y883413D03*
X1323205D03*
X1332654Y892862D03*
X1320055Y883413D03*
X1332654Y886562D03*
X1335803D03*
X1320055Y889712D03*
X1323204Y889713D03*
X1329504Y883413D03*
X1328246Y1348187D03*
X1331646D03*
X1328246Y1360099D03*
X1331646D03*
Y1396583D03*
X1328246D03*
X1331646Y1408495D03*
X1328246D03*
X1342103Y845619D03*
X1345252Y836170D03*
X1338953Y845619D03*
X1345252Y833021D03*
X1342103Y836170D03*
X1351550D03*
X1342103Y842470D03*
X1345252Y845619D03*
X1342103Y839320D03*
X1338953Y848769D03*
X1338952Y839319D03*
X1345252Y842470D03*
X1342103Y848769D03*
X1338953Y842470D03*
X1345252Y848769D03*
X1338953Y836170D03*
X1351550Y842470D03*
Y848769D03*
Y845619D03*
X1345252Y839320D03*
X1351550Y858218D03*
X1345252D03*
Y861367D03*
X1342103Y858218D03*
X1351550Y861367D03*
X1338953Y851918D03*
X1342103D03*
X1345252D03*
X1351550D03*
X1338953Y880263D03*
X1351550D03*
X1345252D03*
X1342103Y870814D03*
X1345252D03*
Y867665D03*
X1351550Y870814D03*
Y867665D03*
X1338953Y877114D03*
X1345252D03*
X1351550D03*
X1342103Y880263D03*
X1338953Y883413D03*
X1345252Y889712D03*
Y886562D03*
X1342103Y883413D03*
X1345252D03*
X1338952Y889713D03*
X1338953Y892862D03*
X1342103Y886562D03*
Y892862D03*
Y889712D03*
X1338953Y886562D03*
X1351550Y883413D03*
Y889712D03*
Y886562D03*
Y892862D03*
X1343886Y1372385D03*
X1340486D03*
Y1384297D03*
X1343886D03*
X1364148Y829871D03*
X1367298D03*
X1359425Y829000D03*
X1354699Y842470D03*
Y848769D03*
X1357849D03*
X1364148Y845619D03*
X1354699Y836170D03*
X1357849Y833021D03*
X1367298Y845619D03*
X1364148Y842470D03*
X1357850Y839319D03*
X1357849Y836170D03*
X1360999Y842470D03*
X1354699Y845619D03*
X1357849D03*
X1360999Y839320D03*
X1367298Y842470D03*
X1360999Y848769D03*
Y845619D03*
X1367298Y833021D03*
X1354699Y839320D03*
X1360999Y836170D03*
X1367298Y848769D03*
X1364148Y839320D03*
X1357849Y842470D03*
X1364148Y833021D03*
X1367298Y836170D03*
Y839320D03*
X1364148Y848769D03*
Y851918D03*
X1367298Y861367D03*
X1364148Y858218D03*
Y855068D03*
Y861367D03*
X1367298Y858218D03*
Y851918D03*
X1354699Y858218D03*
X1367298Y855068D03*
X1360999D03*
Y858218D03*
Y861367D03*
X1354699Y851918D03*
X1357849D03*
X1364148Y867665D03*
X1367298Y877114D03*
X1364148Y870814D03*
X1367298Y873964D03*
X1364148D03*
Y877114D03*
X1367298Y870814D03*
X1364148Y880263D03*
X1367298D03*
X1357849D03*
X1360999D03*
X1367298Y867665D03*
X1354699Y870814D03*
X1357849Y877114D03*
X1354699Y880263D03*
X1360999Y867665D03*
Y870814D03*
Y873964D03*
X1367298Y883413D03*
X1354699Y892862D03*
X1360999D03*
X1367298D03*
X1360999Y883413D03*
X1357850Y889713D03*
X1364148Y889712D03*
X1357849Y883413D03*
X1367298Y889712D03*
X1354699D03*
X1357849Y886562D03*
X1364148D03*
X1357849Y892862D03*
X1360999Y889712D03*
X1354699Y883413D03*
X1360999Y886562D03*
X1364148Y892862D03*
Y883413D03*
X1367298Y886562D03*
X1354699D03*
X1356126Y1348187D03*
X1352726D03*
X1356126Y1360099D03*
X1352726D03*
X1356126Y1396583D03*
X1352726D03*
Y1408495D03*
X1356126D03*
X1370447Y829871D03*
Y839320D03*
X1383046Y845619D03*
X1379896D03*
X1373597D03*
Y842470D03*
X1370447Y848769D03*
X1379896D03*
Y839320D03*
X1373597Y848769D03*
X1376747D03*
X1373597Y833021D03*
X1370447D03*
X1373597Y836170D03*
X1370447D03*
X1373598Y839319D03*
X1370447Y842470D03*
Y845619D03*
X1383046Y842470D03*
X1376747Y836170D03*
Y842470D03*
X1379896Y833021D03*
X1383046Y839320D03*
X1376747Y845619D03*
Y839320D03*
X1379896Y855068D03*
Y861367D03*
X1376747Y858218D03*
Y851918D03*
X1373597Y861367D03*
X1376747Y855068D03*
X1373597Y858218D03*
X1376747Y861367D03*
X1383046Y851918D03*
X1373597D03*
X1373598Y855067D03*
X1379896Y851918D03*
X1370447D03*
Y858218D03*
X1383046D03*
Y861367D03*
X1370447Y855068D03*
Y861367D03*
X1383046Y873964D03*
X1376747Y880263D03*
X1370447Y877114D03*
X1373598Y873965D03*
X1370447Y873964D03*
X1379896Y877114D03*
X1373597Y880263D03*
X1383046Y877114D03*
X1370447Y880263D03*
X1376747Y873964D03*
X1383046Y880263D03*
X1370447Y870814D03*
X1376747D03*
X1373597D03*
X1376747Y867665D03*
Y877114D03*
X1373597Y867665D03*
X1379896D03*
X1383046Y870814D03*
X1379896Y880263D03*
X1373597Y877114D03*
X1379896Y873964D03*
X1383046Y892862D03*
X1379896Y886562D03*
X1370447Y883413D03*
X1373598Y889713D03*
X1376747Y886562D03*
X1383046Y883413D03*
X1376747Y889712D03*
X1383046D03*
X1379896D03*
X1373597Y883413D03*
Y886562D03*
X1370447Y892862D03*
X1376747D03*
X1370447Y889712D03*
X1373597Y892862D03*
X1383046Y886562D03*
X1379896Y892862D03*
X1376747Y883413D03*
X1464770Y1348187D03*
X1461370D03*
X1464770Y1360099D03*
X1461370D03*
X1473610Y1372385D03*
X1477010D03*
X1473610Y1384297D03*
X1477010D03*
X1489250Y1348187D03*
X1485850D03*
Y1360099D03*
X1489250D03*
X1498090Y1372385D03*
Y1384297D03*
X1485850Y1396583D03*
X1489250D03*
Y1408495D03*
X1485850D03*
X1513730Y1348187D03*
X1510330D03*
Y1360099D03*
X1513730D03*
X1501490Y1372385D03*
Y1384297D03*
X1510330Y1396583D03*
X1513730D03*
X1510330Y1408495D03*
X1513730D03*
X1525970Y1372385D03*
X1522570D03*
X1525970Y1384297D03*
X1522570D03*
X1538210Y1348187D03*
X1534810D03*
X1538210Y1360099D03*
X1534810D03*
X1547050Y1372385D03*
Y1384297D03*
X1538210Y1396583D03*
X1534810D03*
X1538210Y1408495D03*
X1534810D03*
X1559290Y1348187D03*
X1562690D03*
X1559290Y1360099D03*
X1562690D03*
X1550450Y1372385D03*
Y1384297D03*
X1562690Y1396583D03*
X1559290D03*
Y1408495D03*
X1562690D03*
X1574930Y1372385D03*
X1571530D03*
Y1384297D03*
X1574930D03*
X1587170Y1348187D03*
X1583770D03*
X1587170Y1360099D03*
X1583770D03*
Y1396583D03*
X1587170D03*
X1583770Y1408495D03*
X1587170D03*
X1611398Y1348187D03*
Y1360099D03*
X1614798Y1348187D03*
Y1360099D03*
X1627038Y1372385D03*
X1623638D03*
X1627038Y1384297D03*
X1623638D03*
X1641634Y1215452D03*
X1639278Y1348187D03*
X1635878D03*
X1639278Y1360099D03*
X1635878D03*
X1639278Y1396583D03*
X1635878D03*
Y1408495D03*
X1639278D03*
X1660358Y1348187D03*
Y1360099D03*
X1648118Y1372385D03*
X1651518D03*
X1648118Y1384297D03*
X1651518D03*
X1660358Y1396583D03*
Y1408495D03*
X1663758Y1348187D03*
Y1360099D03*
X1675998Y1372385D03*
X1672598D03*
Y1384297D03*
X1675998D03*
X1663758Y1396583D03*
Y1408495D03*
X1688238Y1348187D03*
X1684838D03*
X1688238Y1360099D03*
X1684838D03*
Y1396583D03*
X1688238D03*
Y1408495D03*
X1684838D03*
X1709318Y1348187D03*
Y1360099D03*
X1697078Y1372385D03*
X1700478D03*
X1697078Y1384297D03*
X1700478D03*
X1709318Y1396583D03*
Y1408495D03*
X1712718Y1348187D03*
Y1360099D03*
X1721558Y1372385D03*
X1724958D03*
Y1384297D03*
X1721558D03*
X1712718Y1396583D03*
Y1408495D03*
X1733798Y1348187D03*
X1737198D03*
X1733798Y1360099D03*
X1737198D03*
Y1396583D03*
X1733798D03*
X1737198Y1408495D03*
X1733798D03*
G54D29*
X116731Y1052235D03*
X106619Y1056423D03*
X102431Y1066535D03*
X106619Y1076647D03*
X116731Y1080835D03*
Y1249086D03*
X106619Y1253274D03*
X102431Y1263386D03*
X106619Y1273498D03*
X116731Y1277686D03*
X126843Y1056423D03*
Y1076647D03*
X131031Y1066535D03*
X126843Y1253274D03*
X131031Y1263386D03*
X126843Y1273498D03*
X342840Y1056423D03*
X338652Y1066535D03*
X342840Y1076647D03*
Y1253274D03*
X338652Y1263386D03*
X342840Y1273498D03*
X352952Y1052235D03*
Y1080835D03*
Y1249086D03*
Y1277686D03*
X363064Y1056423D03*
Y1076647D03*
X367252Y1066535D03*
X363064Y1253274D03*
X367252Y1263386D03*
X363064Y1273498D03*
X563706Y1056423D03*
X559518Y1066535D03*
X563706Y1076647D03*
Y1253274D03*
X559518Y1263386D03*
X563706Y1273498D03*
X583930Y1056423D03*
X573818Y1052235D03*
X583930Y1076647D03*
X588118Y1066535D03*
X573818Y1080835D03*
X583930Y1253274D03*
X573818Y1249086D03*
X588118Y1263386D03*
X573818Y1277686D03*
X583930Y1273498D03*
X760433Y1480906D03*
X756274Y1490945D03*
X760433Y1500984D03*
X780511Y1480906D03*
X770472Y1476747D03*
Y1505143D03*
X780511Y1500984D03*
X799926Y1056423D03*
X795738Y1066535D03*
X799926Y1076647D03*
Y1253274D03*
X795738Y1263386D03*
X799926Y1273498D03*
X784670Y1490945D03*
X810040Y378544D03*
X805881Y388583D03*
X810040Y398622D03*
X810038Y1052235D03*
Y1080835D03*
Y1249086D03*
Y1277686D03*
X820079Y374385D03*
X830118Y378544D03*
X820079Y402781D03*
X830118Y398622D03*
X820150Y1056423D03*
Y1076647D03*
X824338Y1066535D03*
X820150Y1253274D03*
X824338Y1263386D03*
X820150Y1273498D03*
X834277Y388583D03*
X1010827Y378544D03*
X1006668Y388583D03*
X1010827Y398622D03*
X1020866Y374385D03*
Y402781D03*
X1020793Y1056423D03*
X1016605Y1066535D03*
X1020793Y1076647D03*
Y1253274D03*
X1016605Y1263386D03*
X1020793Y1273498D03*
X1030905Y378544D03*
X1035064Y388583D03*
X1030905Y398622D03*
X1041017Y1056423D03*
X1030905Y1052235D03*
X1041017Y1076647D03*
X1030905Y1080835D03*
X1041017Y1253274D03*
X1030905Y1249086D03*
Y1277686D03*
X1041017Y1273498D03*
X1045205Y1066535D03*
Y1263386D03*
X1060433Y1480906D03*
X1056274Y1490945D03*
X1060433Y1500984D03*
X1070472Y1476747D03*
Y1505143D03*
X1080511Y1480906D03*
X1084670Y1490945D03*
X1080511Y1500984D03*
X1252825Y1066535D03*
Y1263386D03*
X1267125Y1052235D03*
X1257013Y1056423D03*
Y1076647D03*
X1267125Y1080835D03*
Y1249086D03*
X1257013Y1253274D03*
Y1273498D03*
X1267125Y1277686D03*
X1277237Y1056423D03*
Y1076647D03*
X1281425Y1066535D03*
X1277237Y1253274D03*
X1281425Y1263386D03*
X1277237Y1273498D03*
X1477879Y1056423D03*
X1473691Y1066535D03*
X1477879Y1076647D03*
Y1253274D03*
X1473691Y1263386D03*
X1477879Y1273498D03*
X1498103Y1056423D03*
X1487991Y1052235D03*
X1498103Y1076647D03*
X1487991Y1080835D03*
X1498103Y1253274D03*
X1487991Y1249086D03*
Y1277686D03*
X1498103Y1273498D03*
X1502291Y1066535D03*
Y1263386D03*
X1709912Y1066535D03*
Y1263386D03*
X1724212Y1052235D03*
X1714100Y1056423D03*
Y1076647D03*
X1724212Y1080835D03*
Y1249086D03*
X1714100Y1253274D03*
Y1273498D03*
X1724212Y1277686D03*
X1734324Y1056423D03*
Y1076647D03*
X1738512Y1066535D03*
X1734324Y1253274D03*
X1738512Y1263386D03*
X1734324Y1273498D03*
G54D45*
X710406Y-26826D03*
Y-36826D03*
D03*
Y-26826D03*
X735406D03*
Y-36826D03*
D03*
Y-26826D03*
X830406Y-76006D03*
D03*
Y-66006D03*
D03*
X855406Y-76006D03*
D03*
Y-66006D03*
D03*
X939542Y-36798D03*
Y-26798D03*
D03*
Y-36798D03*
X964386Y-75978D03*
D03*
Y-65978D03*
D03*
X964542Y-36798D03*
Y-26798D03*
D03*
Y-36798D03*
X989386Y-75978D03*
D03*
Y-65978D03*
D03*
X993906Y-46826D03*
Y-36826D03*
D03*
Y-26826D03*
X1018906Y-46826D03*
Y-36826D03*
D03*
Y-26826D03*
X1063906Y-76006D03*
Y-86006D03*
Y-76006D03*
Y-66006D03*
X1088906Y-76006D03*
Y-86006D03*
Y-76006D03*
Y-66006D03*
X1217686Y-85978D03*
Y-75978D03*
D03*
Y-65978D03*
X1223042Y-46928D03*
Y-36928D03*
Y-26928D03*
Y-36928D03*
X1242686Y-85978D03*
Y-75978D03*
D03*
Y-65978D03*
X1248042Y-46928D03*
Y-36928D03*
Y-26928D03*
Y-36928D03*
X1280406Y-46956D03*
Y-36956D03*
D03*
Y-26956D03*
X1305406Y-46956D03*
Y-36956D03*
D03*
Y-26956D03*
X1320406Y-76006D03*
Y-86006D03*
Y-76006D03*
Y-66006D03*
X1345406Y-76006D03*
Y-86006D03*
Y-76006D03*
Y-66006D03*
X1474186Y-85978D03*
Y-75978D03*
D03*
Y-65978D03*
X1499186Y-85978D03*
Y-75978D03*
D03*
Y-65978D03*
X1509542Y-47058D03*
Y-37058D03*
Y-27058D03*
Y-37058D03*
X1534542Y-47058D03*
Y-37058D03*
Y-27058D03*
Y-37058D03*
X1564906Y-47086D03*
Y-37086D03*
D03*
Y-27086D03*
X1574906Y-76006D03*
Y-86006D03*
Y-76006D03*
Y-66006D03*
X1589906Y-47086D03*
Y-37086D03*
D03*
Y-27086D03*
X1599906Y-76006D03*
Y-86006D03*
Y-76006D03*
Y-66006D03*
X1728686Y-85978D03*
Y-75978D03*
D03*
Y-65978D03*
X1753686Y-85978D03*
Y-75978D03*
D03*
Y-65978D03*
X1794042Y-47188D03*
Y-37188D03*
Y-27188D03*
Y-37188D03*
X1819042Y-47188D03*
Y-37188D03*
Y-27188D03*
Y-37188D03*
G54D10*
X3704Y5374D03*
X3017Y24773D03*
Y44773D03*
Y64773D03*
Y84773D03*
Y104773D03*
Y124773D03*
Y144773D03*
Y164773D03*
Y184773D03*
Y204773D03*
Y224773D03*
Y244773D03*
Y264773D03*
Y284773D03*
Y304773D03*
X3221Y324773D03*
X3035Y978036D03*
Y998036D03*
Y1018036D03*
Y1038036D03*
Y1058036D03*
Y1078036D03*
Y1098036D03*
Y1118036D03*
Y1138036D03*
Y1158036D03*
Y1178036D03*
Y1198036D03*
Y1238036D03*
Y1258036D03*
Y1278036D03*
Y1298036D03*
Y1318036D03*
Y1338036D03*
Y1358036D03*
Y1378036D03*
Y1398036D03*
Y1418036D03*
Y1438036D03*
Y1458036D03*
Y1478036D03*
Y1498036D03*
Y1538036D03*
Y1558036D03*
X15972Y3000D03*
X10971Y333342D03*
X17964Y349298D03*
Y369298D03*
Y389298D03*
Y409298D03*
Y429298D03*
Y449298D03*
Y469298D03*
Y489298D03*
Y509298D03*
Y529298D03*
Y549298D03*
Y569298D03*
Y589298D03*
Y609298D03*
Y629298D03*
Y649298D03*
Y669298D03*
Y689298D03*
Y709298D03*
Y729298D03*
Y749298D03*
Y769298D03*
Y789298D03*
Y809298D03*
Y829298D03*
Y849298D03*
Y869298D03*
Y889298D03*
Y909298D03*
Y929298D03*
X9554Y961954D03*
X17964Y949298D03*
X6161Y1075991D03*
X6108Y1070611D03*
Y1065318D03*
X6059Y1091964D03*
X6055Y1086546D03*
X6053Y1081305D03*
X8042Y1522199D03*
X7922Y1532494D03*
X26956Y4469D03*
X28317Y24773D03*
Y44773D03*
X35638Y53597D03*
X36692Y641817D03*
X27934Y1204311D03*
X30934D03*
X27934Y1215511D03*
X30934D03*
X27934Y1212711D03*
Y1209911D03*
Y1207111D03*
X30934Y1212711D03*
Y1209911D03*
Y1207111D03*
X21544Y1479662D03*
X33536Y1467485D03*
X21544Y1489648D03*
X42192Y641817D03*
X51449Y822718D03*
X47949D03*
X44960Y1190619D03*
X49638Y1203884D03*
X40996Y1467703D03*
X40195Y1511279D03*
X55638Y53597D03*
X66371Y482134D03*
Y484634D03*
X60233Y521804D03*
X68202Y522129D03*
X60233Y524304D03*
X56540Y531378D03*
Y528878D03*
X68202Y527129D03*
Y524629D03*
Y529629D03*
X62789Y608311D03*
X66510Y628242D03*
X60849Y826818D03*
X64649D03*
X58949Y821018D03*
X64849Y840418D03*
X60249D03*
X74432Y5374D03*
X73745Y24773D03*
Y44773D03*
X73509Y110445D03*
Y115401D03*
X83911Y117557D03*
X80660Y103783D03*
X73509Y129574D03*
Y124618D03*
X83911Y122513D03*
Y131731D03*
Y136687D03*
X69816Y475946D03*
Y478446D03*
X78033Y478586D03*
Y481086D03*
Y476086D03*
Y483586D03*
X72549Y838818D03*
X93334Y3000D03*
X95943Y377953D03*
X113334Y3000D03*
X129318Y4469D03*
X130679Y24773D03*
Y44773D03*
X138000Y53597D03*
X146196Y390223D03*
X138194Y397335D03*
X146196Y395179D03*
Y404396D03*
Y409352D03*
X138194Y402291D03*
X135794Y416465D03*
Y411509D03*
X146196Y418569D03*
Y423525D03*
X135794Y425682D03*
Y430638D03*
X146196Y432743D03*
Y437699D03*
X135794Y439855D03*
Y444811D03*
Y468609D03*
Y473565D03*
X146196Y489895D03*
X135794Y487738D03*
X146196Y480677D03*
Y475721D03*
X135794Y482782D03*
X146196Y494851D03*
X135794Y512743D03*
Y517699D03*
X146196Y519855D03*
X135794Y526916D03*
Y531872D03*
X146196Y524811D03*
Y538984D03*
Y534028D03*
X158000Y53597D03*
X176794Y5374D03*
X176107Y24773D03*
Y44773D03*
X195697Y3000D03*
X183022Y103783D03*
X215697Y3000D03*
X231681Y4469D03*
X229745Y1446675D03*
X224753D03*
Y1462631D03*
X229745Y1457675D03*
X224753D03*
X229745Y1451631D03*
Y1462631D03*
X224753Y1451631D03*
X233042Y24773D03*
Y44773D03*
X240363Y53597D03*
X260363D03*
X279156Y5374D03*
X278469Y24773D03*
Y44773D03*
X265945Y440098D03*
Y437598D03*
Y435098D03*
Y432598D03*
Y430098D03*
X294959Y11097D03*
X285384Y103783D03*
X298059Y3000D03*
X301943Y332017D03*
X318059Y3000D03*
X318497Y466528D03*
Y471484D03*
X328899Y473640D03*
Y487813D03*
Y478596D03*
X318497Y480701D03*
Y485657D03*
X328899Y492769D03*
Y517774D03*
X318497Y510661D03*
Y515617D03*
X328899Y522730D03*
X318497Y524835D03*
X328899Y536903D03*
Y531947D03*
X318497Y529791D03*
X328899Y572769D03*
X318497Y565657D03*
Y560701D03*
X328899Y567813D03*
X318497Y579830D03*
Y574874D03*
X328899Y581987D03*
X318497Y589047D03*
X328899Y586943D03*
X318497Y594003D03*
X328899Y596160D03*
X318497Y603221D03*
X328899Y601116D03*
Y610333D03*
X318497Y608177D03*
X328899Y615289D03*
X334043Y4469D03*
X335404Y24773D03*
Y44773D03*
X342725Y53597D03*
X348737Y375386D03*
X354486Y377173D03*
X357173Y392183D03*
X357218Y396866D03*
X361234Y402867D03*
X358042Y442518D03*
Y439718D03*
X362725Y53597D03*
X361767Y392228D03*
X376992Y395248D03*
X368587Y409016D03*
X364551Y409032D03*
X361811Y396866D03*
X375919Y449118D03*
Y446318D03*
X367919Y449118D03*
Y446318D03*
X376099Y458309D03*
Y454309D03*
Y462309D03*
X369282Y468088D03*
Y465288D03*
X367816Y1310586D03*
Y1315542D03*
X388059Y3000D03*
X381518Y5374D03*
X388487Y24069D03*
X380831Y24773D03*
X383612Y30618D03*
X380831Y44773D03*
X387746Y103783D03*
X389237Y371070D03*
X385237Y370976D03*
X396373Y407104D03*
X385584Y450041D03*
Y452841D03*
Y455641D03*
X387587Y1296675D03*
X387644Y1302089D03*
X389458Y1365466D03*
X389188Y1369033D03*
X388600Y1395500D03*
X389985Y1405762D03*
X408059Y3000D03*
X396373Y409904D03*
X395577Y455641D03*
Y450041D03*
Y452841D03*
X397315Y479560D03*
X400914Y762675D03*
X408300Y755487D03*
X407965Y770196D03*
X408400Y795200D03*
Y792200D03*
X406600Y789000D03*
X402376Y842677D03*
X399876D03*
X402376Y850677D03*
X399876D03*
X395959Y1352153D03*
X403029Y1379716D03*
X403111Y1384920D03*
X408212Y1379695D03*
X394657Y1377875D03*
X403111Y1390103D03*
X408212Y1390083D03*
X410152Y1410928D03*
X398112Y1403741D03*
X415453Y455039D03*
X419040Y533690D03*
Y528390D03*
Y530990D03*
Y536290D03*
Y538890D03*
X423266Y631438D03*
X420266D03*
X417666D03*
X420266Y637038D03*
Y634238D03*
X417666Y637038D03*
Y634238D03*
X423266Y637038D03*
Y634238D03*
Y642638D03*
X420266D03*
X417666D03*
X423266Y639838D03*
X420266D03*
X417666D03*
X415696Y762466D03*
X424649Y842644D03*
X422149D03*
Y850644D03*
X424649D03*
X422149Y858644D03*
X424649D03*
X414280Y1362561D03*
X413437Y1379736D03*
Y1384899D03*
X413395Y1390062D03*
X428059Y3000D03*
X433724Y433975D03*
X432310Y436164D03*
X428740Y533690D03*
X442704Y533790D03*
X428740Y528390D03*
Y530990D03*
X442704Y528490D03*
Y531090D03*
X428740Y536290D03*
Y538890D03*
X442704Y536390D03*
Y538990D03*
X436369Y622883D03*
X441612Y631011D03*
X435881Y1394934D03*
Y1398800D03*
X448059Y3000D03*
X452404Y533690D03*
Y528390D03*
Y530990D03*
Y536290D03*
Y538890D03*
X468059Y3000D03*
X468850Y537507D03*
X461849Y668016D03*
X459349D03*
X466849D03*
X469349D03*
X464349D03*
X469349Y678016D03*
X466849D03*
X459349D03*
X461849D03*
X464349D03*
X484043Y4469D03*
X485404Y24773D03*
Y44773D03*
X482193Y472784D03*
Y468784D03*
Y476784D03*
X484341Y700528D03*
Y705484D03*
X492725Y53597D03*
X499278Y641817D03*
X493778D03*
X512725Y53597D03*
X523457Y482134D03*
Y484634D03*
X517319Y521804D03*
X513626Y528578D03*
Y531378D03*
X517319Y524304D03*
X519875Y608311D03*
X523596Y628242D03*
X531518Y5374D03*
X530831Y24773D03*
Y44773D03*
X537747Y103783D03*
X535119Y483886D03*
Y481086D03*
Y478586D03*
X526902Y478446D03*
Y475946D03*
X535119Y476086D03*
X525288Y522129D03*
Y524629D03*
Y527129D03*
Y529929D03*
X542275Y760782D03*
X532449Y782389D03*
X534672Y785037D03*
X536641Y838649D03*
X550421Y3000D03*
X542599Y782389D03*
X542546Y784911D03*
X554357Y784889D03*
X551524D03*
X570421Y3000D03*
X562231Y784911D03*
X558294D03*
X560263Y829989D03*
X568503Y936807D03*
X565003D03*
X586405Y4469D03*
X587766Y24773D03*
Y44773D03*
X583501Y800831D03*
X577903Y940907D03*
X581703D03*
X576003Y935107D03*
X581903Y954507D03*
X577303D03*
X595087Y53597D03*
X603282Y390223D03*
Y395179D03*
Y404396D03*
Y409352D03*
X595280Y402291D03*
Y397335D03*
X592880Y416465D03*
Y411509D03*
X603282Y418569D03*
Y423525D03*
X592880Y425682D03*
X603282Y432743D03*
Y437699D03*
X592880Y439855D03*
Y430638D03*
Y444811D03*
Y468609D03*
Y473565D03*
X603282Y489895D03*
X592880Y487738D03*
X603282Y480677D03*
Y475721D03*
X592880Y482782D03*
X603282Y494851D03*
X592880Y517699D03*
X603282Y519855D03*
X592880Y526916D03*
Y531872D03*
X603282Y524811D03*
Y538984D03*
Y534028D03*
X589603Y952907D03*
X615087Y53597D03*
X633248Y44884D03*
X640109Y103783D03*
X690073Y44662D03*
X697387Y53619D03*
X717387D03*
X723031Y440098D03*
Y437598D03*
Y435098D03*
Y432598D03*
Y430098D03*
X736242Y5374D03*
X735555Y24773D03*
Y44773D03*
X742471Y103783D03*
X755145Y3000D03*
X759029Y332017D03*
X775145Y3000D03*
X775584Y466528D03*
X775583Y471484D03*
Y480701D03*
Y485657D03*
Y515617D03*
Y510661D03*
Y524835D03*
Y529791D03*
Y560701D03*
Y565657D03*
Y579830D03*
Y574874D03*
Y589047D03*
Y594003D03*
Y603221D03*
Y608177D03*
X791129Y4469D03*
X792490Y24773D03*
Y44773D03*
X799811Y53597D03*
X785985Y473640D03*
Y487813D03*
Y478596D03*
Y492769D03*
Y517774D03*
Y522730D03*
Y531947D03*
Y536903D03*
Y572769D03*
Y567813D03*
Y581987D03*
Y586943D03*
Y601116D03*
Y596160D03*
Y615289D03*
Y610333D03*
X806318Y1401661D03*
X806874Y1447457D03*
X812474D03*
X806874Y1452587D03*
Y1457717D03*
X812474D03*
X815096Y1464387D03*
X812009Y1473432D03*
Y1470432D03*
X815096Y1467387D03*
X812096Y1479587D03*
Y1476587D03*
X815096Y1473387D03*
Y1479587D03*
Y1476587D03*
Y1470387D03*
X819811Y53597D03*
X829791Y839020D03*
X825721Y836666D03*
X823234Y867680D03*
X825774Y895553D03*
X816648Y1377608D03*
X817974Y1447457D03*
Y1452587D03*
Y1457717D03*
X818096Y1464387D03*
X821096D03*
X818096Y1473387D03*
X821096D03*
X824096D03*
X818096Y1479587D03*
X821096D03*
X824096D03*
X818096Y1476587D03*
X821096D03*
X824096D03*
X818096Y1467387D03*
Y1470387D03*
X821096D03*
Y1467387D03*
X824096D03*
Y1470387D03*
X838606Y5374D03*
X837919Y24773D03*
Y44773D03*
X844833Y103783D03*
X833185Y456309D03*
Y452309D03*
Y448309D03*
X850145Y3000D03*
X857973Y404867D03*
X862522Y400229D03*
X862566Y404867D03*
X857928Y400184D03*
X862020Y410899D03*
X862882Y468791D03*
Y465991D03*
X854882D03*
Y468791D03*
X861468Y491303D03*
X859071Y1447459D03*
X864671D03*
X859071Y1452589D03*
Y1457719D03*
X864671D03*
X864644Y1464759D03*
X861644D03*
X855644D03*
X858644D03*
Y1467759D03*
X855644Y1470759D03*
X858644D03*
X864644Y1467759D03*
Y1470759D03*
X861644Y1467759D03*
Y1470759D03*
X855644Y1467759D03*
Y1473759D03*
X858644D03*
X864644D03*
X861644D03*
X855644Y1476759D03*
X858644D03*
X864644D03*
X861644D03*
X872736Y383125D03*
X872318Y408589D03*
X866128Y417532D03*
X869342Y417399D03*
X880910Y471982D03*
Y469182D03*
Y466382D03*
X870882Y465991D03*
Y468791D03*
X878610Y747171D03*
X871294Y771809D03*
X871624Y1213314D03*
X874624D03*
X871624Y1221714D03*
Y1218914D03*
Y1216114D03*
X874624Y1221714D03*
Y1218914D03*
Y1216114D03*
X871624Y1224514D03*
X874624D03*
X870171Y1447459D03*
Y1452589D03*
Y1457719D03*
X867644Y1464759D03*
X870644D03*
X867644Y1467759D03*
X870644D03*
X867644Y1470759D03*
X870644D03*
X867644Y1473759D03*
X870644D03*
X867644Y1476759D03*
X870644D03*
X884736Y383125D03*
X893736D03*
X888736D03*
X891699Y420445D03*
Y423245D03*
X890903Y469182D03*
Y471982D03*
Y466382D03*
X896431Y534093D03*
X897118Y857891D03*
Y864189D03*
Y854742D03*
X893968Y864189D03*
Y857891D03*
Y854742D03*
X897118Y873638D03*
Y870488D03*
Y867338D03*
X893968Y870488D03*
Y873638D03*
Y867338D03*
X887669Y876787D03*
X888650Y1199622D03*
X893328Y1212887D03*
X912278Y343881D03*
X910779Y471380D03*
X903431Y534093D03*
X912462Y695770D03*
X912864Y848442D03*
Y845293D03*
Y842143D03*
X909714Y845293D03*
Y842143D03*
X900267Y864189D03*
X909714Y854742D03*
X906565Y857891D03*
X909714D03*
X906565Y864189D03*
X909714D03*
X906565Y854742D03*
X900267Y857891D03*
Y854742D03*
X912864Y851592D03*
Y857891D03*
Y854742D03*
X909714Y873638D03*
Y870488D03*
X906565Y873638D03*
Y870488D03*
Y867338D03*
X900267Y873638D03*
Y870488D03*
Y867338D03*
X909714D03*
X912171Y1447459D03*
X906671D03*
X901071D03*
X912171Y1457719D03*
Y1452589D03*
X906671Y1457719D03*
X901071D03*
Y1452589D03*
X908370Y1464583D03*
X905370D03*
X899370D03*
X902370D03*
X911370D03*
X905370Y1476583D03*
X908370D03*
X902370D03*
X899370D03*
X905370Y1473583D03*
X908370D03*
X902370D03*
X899370D03*
X902370Y1467583D03*
X899370Y1470583D03*
X902370D03*
X908370Y1467583D03*
Y1470583D03*
X905370Y1467583D03*
Y1470583D03*
X899370Y1467583D03*
X911370Y1476583D03*
Y1473583D03*
Y1467583D03*
Y1470583D03*
X930145Y3000D03*
X921847Y346622D03*
X927636Y452505D03*
X929050Y450316D03*
X928612Y835844D03*
X922313Y851592D03*
X929611Y858669D03*
X914370Y1464583D03*
Y1476583D03*
Y1473583D03*
Y1467583D03*
Y1470583D03*
X941129Y4469D03*
X942490Y24773D03*
Y44773D03*
X931620Y584417D03*
X931594Y599420D03*
X931647Y593271D03*
X931578Y590669D03*
X933810Y972433D03*
X935601Y1221714D03*
Y1218914D03*
Y1216114D03*
Y1213314D03*
X938601Y1221714D03*
Y1218914D03*
Y1216114D03*
Y1213314D03*
X935601Y1224514D03*
X938601D03*
X949811Y53597D03*
X956365Y641817D03*
X950865D03*
X950567Y927654D03*
X952627Y1199622D03*
X957305Y1212887D03*
X969811Y53597D03*
X976763Y307303D03*
X969623Y405614D03*
X963577Y426391D03*
X974406Y521804D03*
Y524304D03*
X970713Y531378D03*
Y528878D03*
X976962Y608311D03*
X980683Y628242D03*
X972278Y934429D03*
X988606Y5374D03*
X987919Y24773D03*
Y44773D03*
X994833Y103783D03*
X993132Y310942D03*
X993243Y321325D03*
X987055Y320273D03*
X993920Y335454D03*
X993420Y337954D03*
X992206Y478586D03*
Y481086D03*
Y483886D03*
X980544Y482134D03*
Y484634D03*
X992206Y476086D03*
X983989Y475946D03*
Y478446D03*
X982375Y522129D03*
Y527129D03*
Y524629D03*
Y529929D03*
X1007508Y3000D03*
X1004635Y300276D03*
X1008635D03*
X998667Y322239D03*
X1000420Y348954D03*
X1010119Y933822D03*
X1006619D03*
X1013683Y-44304D03*
Y-39348D03*
Y-29348D03*
Y-34304D03*
X1027508Y3000D03*
X1021895Y771974D03*
X1019519Y937922D03*
X1023319D03*
X1017619Y932122D03*
X1023519Y951522D03*
X1018919D03*
X1043492Y4469D03*
X1041496Y300276D03*
X1031354Y322905D03*
X1031219Y949922D03*
X1044853Y24773D03*
Y44773D03*
X1052174Y53597D03*
X1046674Y340031D03*
X1045966Y346808D03*
X1052367Y402291D03*
Y397335D03*
X1049967Y416465D03*
Y411509D03*
Y425682D03*
Y439855D03*
Y430638D03*
Y444811D03*
Y468609D03*
Y473565D03*
Y487738D03*
Y482782D03*
Y512743D03*
Y517699D03*
Y526916D03*
Y531872D03*
X1072174Y53597D03*
X1060369Y390223D03*
Y395179D03*
Y404396D03*
Y409352D03*
Y418569D03*
Y423525D03*
Y432743D03*
Y437699D03*
Y489895D03*
Y480677D03*
Y475721D03*
Y494851D03*
Y519855D03*
Y524811D03*
Y538984D03*
Y534028D03*
X1083683Y-78528D03*
Y-83484D03*
Y-73484D03*
Y-68528D03*
X1090280Y44773D03*
X1083483Y1523433D03*
X1097195Y103783D03*
X1147214Y44773D03*
X1154535Y53597D03*
X1174535D03*
X1176858Y306534D03*
X1180118Y430098D03*
Y440098D03*
Y437598D03*
Y435098D03*
Y432598D03*
X1193330Y5374D03*
X1192643Y24773D03*
Y44773D03*
X1199557Y103783D03*
X1192500Y322400D03*
X1199615Y950670D03*
X1201794Y985289D03*
X1212232Y3000D03*
X1221337Y332017D03*
X1232232Y3000D03*
X1232670Y466528D03*
Y471484D03*
Y480701D03*
Y485657D03*
Y515617D03*
Y510661D03*
Y524835D03*
Y529791D03*
Y565657D03*
Y560701D03*
Y579830D03*
Y589047D03*
Y574874D03*
Y603221D03*
Y594003D03*
Y608177D03*
X1248216Y4469D03*
X1249577Y24773D03*
Y44773D03*
X1243072Y473640D03*
Y487813D03*
Y478596D03*
Y492769D03*
Y522730D03*
Y517774D03*
Y536903D03*
Y531947D03*
Y567813D03*
Y572769D03*
Y586943D03*
Y581987D03*
Y601116D03*
Y596160D03*
Y610333D03*
Y615289D03*
X1256898Y53597D03*
X1266219Y374300D03*
X1268659Y377173D03*
X1276898Y53597D03*
X1275940Y392228D03*
X1271346Y392183D03*
X1275407Y402867D03*
X1271391Y396866D03*
X1275984D03*
X1282760Y409016D03*
X1278724Y409032D03*
X1272215Y442518D03*
Y439718D03*
X1282092Y449118D03*
Y446318D03*
X1283455Y468088D03*
Y465288D03*
X1300183Y-44434D03*
Y-29478D03*
Y-34434D03*
Y-39478D03*
X1302232Y3000D03*
X1295692Y5374D03*
X1303229Y23274D03*
X1295005Y24773D03*
X1297785Y30618D03*
X1295005Y44773D03*
X1301919Y103783D03*
X1303158Y371043D03*
X1299410Y370976D03*
X1291165Y395248D03*
X1290092Y449118D03*
Y446318D03*
X1299757Y450041D03*
Y452841D03*
Y455641D03*
X1290272Y458309D03*
Y454309D03*
Y462309D03*
X1310546Y409904D03*
Y407104D03*
X1309750Y455641D03*
Y450041D03*
Y452841D03*
X1311488Y479560D03*
X1309856Y899161D03*
X1305761D03*
X1313756D03*
X1322232Y3000D03*
X1320903Y370995D03*
X1333331Y370905D03*
X1329064Y370951D03*
X1329626Y455039D03*
X1340183Y-83484D03*
Y-78528D03*
Y-68528D03*
Y-73484D03*
X1342232Y3000D03*
X1338287Y370905D03*
X1347897Y433975D03*
X1346483Y436164D03*
X1362232Y3000D03*
X1382232D03*
X1373748Y397758D03*
X1375375Y428995D03*
X1398216Y4469D03*
X1399577Y24773D03*
Y44773D03*
X1397550Y390484D03*
X1387814Y397136D03*
X1389295Y408443D03*
X1386809Y414173D03*
X1388788Y428348D03*
X1406898Y53597D03*
X1416830Y407134D03*
X1411400Y398032D03*
X1413889Y415642D03*
X1413452Y641817D03*
X1407952D03*
X1426898Y53597D03*
X1431493Y521804D03*
X1427800Y528578D03*
X1431493Y524304D03*
X1427800Y531378D03*
X1422176Y1491198D03*
X1423806Y1524252D03*
X1445692Y5374D03*
X1445005Y24773D03*
Y44773D03*
X1440568Y369566D03*
X1449619Y363290D03*
X1438588Y380589D03*
X1437631Y482134D03*
Y484634D03*
X1449293Y476086D03*
X1441076Y475946D03*
Y478446D03*
X1449293Y478586D03*
Y481086D03*
Y483886D03*
X1439462Y522129D03*
Y529929D03*
Y527129D03*
Y524629D03*
X1434049Y608311D03*
X1437770Y628242D03*
X1464594Y3000D03*
X1462675Y14334D03*
X1451920Y103783D03*
X1455979Y391756D03*
X1458212Y403374D03*
X1473364Y410724D03*
X1472403Y417338D03*
X1469293Y428815D03*
X1484594Y3000D03*
X1498446Y912370D03*
X1497208Y909740D03*
X1500578Y4469D03*
X1501939Y24773D03*
Y44773D03*
X1509260Y53597D03*
X1509454Y402291D03*
Y397335D03*
X1507054Y416465D03*
Y411509D03*
Y425682D03*
Y439855D03*
Y430638D03*
Y444811D03*
Y468609D03*
Y473565D03*
Y487738D03*
Y482782D03*
Y517699D03*
Y512743D03*
Y526916D03*
Y531872D03*
X1507034Y888133D03*
X1507358Y909740D03*
X1507305Y912262D03*
X1501400Y966000D03*
X1529260Y53597D03*
X1517456Y390223D03*
Y395179D03*
Y404396D03*
Y409352D03*
Y418569D03*
Y423525D03*
Y432743D03*
Y437699D03*
Y489895D03*
Y480677D03*
Y475721D03*
Y494851D03*
Y519855D03*
Y538984D03*
Y524811D03*
Y534028D03*
X1516283Y912240D03*
X1519116D03*
X1523053Y912262D03*
X1525022Y957340D03*
X1547367Y44773D03*
X1554282Y103783D03*
X1594683Y-83484D03*
Y-78528D03*
Y-68528D03*
Y-73484D03*
X1584683Y-44564D03*
Y-29608D03*
Y-34564D03*
Y-39608D03*
X1604301Y44773D03*
X1611622Y53597D03*
X1631622D03*
X1637205Y440098D03*
Y437598D03*
Y435098D03*
Y432598D03*
Y430098D03*
X1650417Y5374D03*
X1649730Y24773D03*
Y44773D03*
X1656644Y103783D03*
X1669319Y3001D03*
X1673203Y332017D03*
X1689319Y3001D03*
X1689757Y466528D03*
Y471484D03*
Y480701D03*
Y485657D03*
Y515617D03*
Y510661D03*
Y524835D03*
Y529791D03*
Y565657D03*
Y560701D03*
Y589047D03*
Y574874D03*
Y579830D03*
Y603221D03*
Y594003D03*
Y608177D03*
X1705303Y4470D03*
X1706664Y24774D03*
Y44774D03*
X1700159Y473640D03*
Y487813D03*
Y478596D03*
Y492769D03*
Y517774D03*
Y522730D03*
Y536903D03*
Y531947D03*
Y572769D03*
Y567813D03*
Y586943D03*
Y581987D03*
Y601116D03*
Y596160D03*
Y610333D03*
Y615289D03*
X1713985Y53598D03*
X1725746Y377173D03*
X1723964Y370935D03*
X1733985Y53598D03*
X1733027Y392228D03*
X1728433Y392183D03*
X1739847Y409016D03*
X1735811Y409032D03*
X1732494Y402867D03*
X1728478Y396866D03*
X1733071D03*
X1729302Y439718D03*
Y442518D03*
X1739179Y449118D03*
Y446318D03*
X1740542Y468088D03*
Y465288D03*
X1752778Y5374D03*
X1752091Y24773D03*
Y44773D03*
X1756497Y370976D03*
X1748252Y395248D03*
X1756844Y450041D03*
Y452841D03*
Y455641D03*
X1747179Y449118D03*
Y446318D03*
X1747359Y454309D03*
Y458309D03*
Y462309D03*
X1765559Y3001D03*
X1759006Y103783D03*
X1760497Y371070D03*
X1767633Y409904D03*
Y407104D03*
X1766837Y450041D03*
Y452841D03*
Y455641D03*
X1768575Y479560D03*
X1773600Y888100D03*
X1773614Y895275D03*
X1773600Y902800D03*
X1786713Y455039D03*
X1788400Y888100D03*
X1781000Y888087D03*
X1788396Y895066D03*
X1788300Y902800D03*
X1780665Y902796D03*
X1781263Y964660D03*
X1784763D03*
X1779581Y1222200D03*
Y1219400D03*
Y1216600D03*
Y1213800D03*
X1782581Y1222200D03*
Y1219400D03*
Y1216600D03*
Y1213800D03*
X1779581Y1225000D03*
X1782581D03*
X1804984Y433975D03*
X1803570Y436164D03*
X1794163Y968760D03*
X1797963D03*
X1792263Y962960D03*
X1798163Y982360D03*
X1793563D03*
X1805863Y980760D03*
X1796607Y1200108D03*
X1801285Y1213373D03*
X1822983Y346053D03*
Y366053D03*
Y386053D03*
Y406053D03*
Y426053D03*
Y446053D03*
Y466053D03*
Y486053D03*
Y506053D03*
Y526053D03*
Y546053D03*
Y566053D03*
Y586053D03*
Y606053D03*
Y626053D03*
Y646053D03*
Y666053D03*
Y686053D03*
Y706053D03*
Y726053D03*
Y746053D03*
Y766053D03*
Y786053D03*
Y806053D03*
Y826053D03*
Y846053D03*
Y866053D03*
Y886053D03*
Y906053D03*
Y926053D03*
Y946053D03*
X1825559Y3001D03*
X1836543Y4470D03*
X1837904Y24774D03*
Y44774D03*
Y64774D03*
Y84774D03*
Y104774D03*
Y124774D03*
Y144774D03*
Y164774D03*
Y184774D03*
Y204774D03*
Y224774D03*
Y244774D03*
Y264774D03*
Y284774D03*
Y304774D03*
X1837728Y324733D03*
X1830094Y333210D03*
X1830472Y960970D03*
X1837937Y973244D03*
Y993244D03*
Y1013244D03*
Y1033244D03*
Y1053244D03*
Y1073244D03*
X1824733Y1102830D03*
X1837937Y1093244D03*
X1825832Y1097589D03*
X1837937Y1113244D03*
Y1133244D03*
Y1153244D03*
Y1173244D03*
Y1193244D03*
Y1213244D03*
Y1253244D03*
Y1273244D03*
Y1293244D03*
Y1313244D03*
Y1333244D03*
Y1353244D03*
Y1373244D03*
Y1393244D03*
Y1433244D03*
Y1453244D03*
Y1473244D03*
Y1493244D03*
Y1513244D03*
Y1533244D03*
Y1553244D03*
Y1573244D03*
G54D14*
X20408Y51296D03*
Y55296D03*
X9057Y138939D03*
X19184Y144728D03*
X15184D03*
X15520Y195176D03*
X18320D03*
X13020D03*
X10520D03*
X12880Y203393D03*
X10380D03*
X19068Y206838D03*
X16568D03*
X13606Y1476707D03*
X19365Y1494298D03*
X24316Y67527D03*
Y63527D03*
Y59527D03*
X23184Y144728D03*
X35650Y487982D03*
Y478982D03*
Y483982D03*
Y499982D03*
X25819Y531726D03*
Y536726D03*
Y552726D03*
Y540726D03*
X30410Y1218497D03*
Y1220997D03*
Y1234797D03*
Y1232297D03*
Y1227897D03*
Y1225397D03*
Y1241697D03*
Y1239197D03*
X25674Y1486291D03*
X32195Y1511279D03*
X32079Y1521641D03*
X31237Y1532096D03*
X46240Y109410D03*
X45988Y102323D03*
X46240Y116496D03*
X46931Y130670D03*
X49236Y121658D03*
X46932Y137756D03*
X49839Y546830D03*
X44195Y1511279D03*
X39237Y1532096D03*
X64098Y102323D03*
Y109410D03*
Y116496D03*
Y123583D03*
Y130670D03*
Y137756D03*
X69139Y236611D03*
X68841Y248891D03*
X66224Y473045D03*
X58224D03*
X53643Y472905D03*
X59670Y500086D03*
X64495Y527449D03*
X61695D03*
X60554Y1612002D03*
X66291Y1633801D03*
X74139Y236611D03*
X71639D03*
X71341Y248891D03*
X73841D03*
X74326Y480705D03*
X71995Y532749D03*
X74795D03*
X74291Y1633801D03*
X86291D03*
X119582Y102249D03*
X111582D03*
X115582D03*
X115382Y195176D03*
X112882D03*
X117882D03*
X115242Y203393D03*
X112742D03*
X120682Y195176D03*
X118930Y206838D03*
X121430D03*
X148602Y109410D03*
Y116496D03*
X148350Y102323D03*
X148774Y124576D03*
X149827Y130670D03*
X149822Y137756D03*
X166460Y116496D03*
Y109410D03*
Y102323D03*
Y123583D03*
Y130670D03*
Y137756D03*
X174001Y236611D03*
X176501D03*
X171501D03*
X176203Y248891D03*
X173703D03*
X171203D03*
X185169Y389154D03*
Y396240D03*
X186448Y404911D03*
X186589Y426299D03*
X185402Y412571D03*
X186900Y445847D03*
X185169Y467539D03*
Y474626D03*
X185430Y480828D03*
X187380Y498834D03*
X185169Y518760D03*
Y511673D03*
Y525847D03*
X191125Y602400D03*
Y598400D03*
Y594400D03*
Y606400D03*
Y614400D03*
X203591Y91951D03*
X213944Y102249D03*
X215244Y195176D03*
X215104Y203393D03*
X203280Y389154D03*
Y396240D03*
Y403327D03*
Y410413D03*
Y417500D03*
Y424586D03*
Y431673D03*
Y438760D03*
Y445847D03*
Y467539D03*
Y474626D03*
Y488799D03*
Y481713D03*
Y495886D03*
Y511673D03*
Y518760D03*
Y525847D03*
Y532933D03*
Y540020D03*
Y547106D03*
Y554193D03*
Y602205D03*
Y595118D03*
X221944Y102249D03*
X217944D03*
X220244Y195176D03*
X217744D03*
X223044D03*
X223792Y206838D03*
X221292D03*
X217604Y203393D03*
X228267Y392718D03*
Y408718D03*
Y400718D03*
Y404718D03*
Y412718D03*
X250964Y109410D03*
X250712Y102323D03*
X250964Y116496D03*
X251136Y124576D03*
X252189Y130670D03*
X252184Y137756D03*
X268822Y116496D03*
Y109410D03*
Y102323D03*
Y130670D03*
Y123583D03*
Y137756D03*
X276363Y236611D03*
X278863D03*
X273863D03*
X276065Y248891D03*
X273565D03*
X278565D03*
X274205Y466027D03*
X274347Y475262D03*
Y489435D03*
Y482666D03*
X274163Y495088D03*
X274205Y509626D03*
X274820Y522134D03*
X274898Y514608D03*
X275463Y529136D03*
X275302Y535677D03*
X274586Y565574D03*
X274205Y559665D03*
X274233Y574338D03*
X274332Y616358D03*
X292500Y410394D03*
Y403307D03*
X284295Y430760D03*
X284316Y433570D03*
X284132Y437072D03*
X284173Y439963D03*
X284417Y443180D03*
X284437Y454744D03*
X284379Y452018D03*
X292316Y458406D03*
Y465492D03*
Y472579D03*
Y479665D03*
Y486752D03*
Y493839D03*
Y523799D03*
Y516713D03*
Y509626D03*
Y537973D03*
Y530886D03*
Y559665D03*
Y566752D03*
Y573839D03*
Y588012D03*
Y580925D03*
Y595099D03*
Y602185D03*
Y616358D03*
Y609272D03*
X324306Y102249D03*
X320306D03*
X316306D03*
X322606Y195176D03*
X325406D03*
X320106D03*
X317606D03*
X323654Y206838D03*
X319966Y203393D03*
X317466D03*
X326154Y206838D03*
X319857Y321649D03*
X324291Y556775D03*
X353074Y102323D03*
X353326Y109410D03*
Y116496D03*
X353498Y124576D03*
X354551Y130670D03*
X354546Y137756D03*
X371184Y116496D03*
Y109410D03*
Y102323D03*
Y130670D03*
Y123583D03*
Y137756D03*
X376225Y236611D03*
X375927Y248891D03*
X373101Y779608D03*
X376300Y779800D03*
X370214Y959812D03*
Y967812D03*
X381225Y236611D03*
X378725D03*
X378427Y248891D03*
X380927D03*
X379800Y778000D03*
X387692Y790056D03*
X393547D03*
X386614Y868286D03*
X385512Y955356D03*
X390150Y955312D03*
Y959905D03*
X385467Y959950D03*
X409268Y408240D03*
X409386Y420393D03*
X400900Y755400D03*
Y770100D03*
X407193Y883566D03*
X396182Y955858D03*
X402682Y948536D03*
X402815Y951750D03*
X404004Y1198321D03*
Y1200821D03*
X407469Y1495035D03*
X407854Y1492118D03*
X406377Y1499142D03*
X411768Y408240D03*
X414268D03*
X411847Y424240D03*
X414386Y420393D03*
X411886D03*
X411847Y426740D03*
X415700Y755400D03*
Y770200D03*
X422430Y834800D03*
X422379Y867229D03*
X420661Y1119422D03*
X423141Y1113822D03*
Y1119422D03*
X418181Y1113822D03*
Y1119422D03*
X420661Y1113822D03*
X417469Y1200821D03*
Y1198321D03*
X439804Y536682D03*
Y539182D03*
X430934Y1200821D03*
Y1198321D03*
X430657Y1563562D03*
X446179Y447101D03*
X448726Y653288D03*
Y646480D03*
Y648980D03*
Y655788D03*
X450244Y1090268D03*
Y1093068D03*
X455269Y1119422D03*
X450309Y1113822D03*
Y1119422D03*
X452789Y1113822D03*
Y1119422D03*
X455269Y1113822D03*
X474307Y102249D03*
X470307D03*
X466307D03*
X470107Y195176D03*
X467607D03*
X472607D03*
X475407D03*
X473655Y206838D03*
X467467Y203393D03*
X469967D03*
X463104Y536582D03*
Y539082D03*
X476155Y206838D03*
X492736Y478982D03*
X482905Y531726D03*
X482737Y537215D03*
X482905Y552726D03*
Y540726D03*
X488728Y1119422D03*
X483768Y1113822D03*
X486248D03*
Y1119422D03*
X483768D03*
X488728Y1113822D03*
X477206Y1198321D03*
X490671D03*
Y1200821D03*
X477206D03*
X503075Y102323D03*
X503327Y109410D03*
Y116496D03*
X506653Y121652D03*
X504552Y130670D03*
X504547Y137756D03*
X493485Y439903D03*
X492736Y487982D03*
Y483982D03*
Y499982D03*
X506925Y546830D03*
X504136Y1198321D03*
Y1200821D03*
X521185Y116496D03*
Y109410D03*
Y102323D03*
Y130670D03*
Y123583D03*
Y137756D03*
X508729Y469905D03*
X521310Y470045D03*
X513310D03*
X516756Y500086D03*
X518781Y527449D03*
X521581D03*
X518812Y665867D03*
X515831Y1090568D03*
Y1093068D03*
X518376Y1113822D03*
Y1119422D03*
X520856Y1113822D03*
Y1119422D03*
X515896Y1113822D03*
Y1119422D03*
X526226Y236611D03*
X531226D03*
X528726D03*
X528428Y248891D03*
X530928D03*
X525928D03*
X531412Y480705D03*
X528612D03*
X529481Y532849D03*
X532281D03*
X533486Y664052D03*
X538442D03*
X524941Y661387D03*
X530796D03*
X572669Y102249D03*
X568669D03*
X572469Y195176D03*
X572329Y203393D03*
X567559Y812850D03*
X576669Y102249D03*
X574969Y195176D03*
X577769D03*
X578517Y206838D03*
X576017D03*
X605437Y102323D03*
X605689Y109410D03*
Y116496D03*
X605861Y124576D03*
X606914Y130670D03*
X606909Y137756D03*
X623547Y109410D03*
Y116496D03*
Y102323D03*
Y123583D03*
Y130670D03*
Y137756D03*
X633588Y236611D03*
X631088D03*
X628588D03*
X630790Y248891D03*
X633290D03*
X628290D03*
X642255Y389154D03*
Y396240D03*
X643534Y404911D03*
X642488Y412571D03*
X643675Y426299D03*
X643986Y445847D03*
X642255Y467539D03*
Y474626D03*
X642516Y480828D03*
X644466Y498834D03*
X642255Y518760D03*
Y511673D03*
Y525847D03*
X648211Y602400D03*
Y598400D03*
Y594400D03*
Y606400D03*
Y614400D03*
X660366Y389154D03*
Y403327D03*
Y410413D03*
Y396240D03*
Y417500D03*
Y424586D03*
Y431673D03*
Y438760D03*
Y445847D03*
Y467539D03*
Y474626D03*
Y488799D03*
Y481713D03*
Y495886D03*
Y511673D03*
Y518760D03*
Y525847D03*
Y532933D03*
Y540020D03*
Y554193D03*
Y547106D03*
Y602205D03*
Y595118D03*
X679031Y102249D03*
X672331Y195176D03*
X674831D03*
X680131D03*
X672191Y203393D03*
X674691D03*
X678379Y206838D03*
X680879D03*
X685353Y392718D03*
Y408718D03*
Y400718D03*
Y404718D03*
Y412718D03*
X707799Y102323D03*
X708051Y109410D03*
Y116496D03*
X708223Y124576D03*
X709276Y130670D03*
X709271Y137756D03*
X725909Y102323D03*
Y116496D03*
Y109410D03*
Y130670D03*
Y123583D03*
Y137756D03*
X733450Y236611D03*
X730950D03*
X733152Y248891D03*
X730652D03*
X731291Y466027D03*
X731433Y475262D03*
Y489435D03*
Y482666D03*
X731249Y495088D03*
X731984Y514608D03*
X731906Y522134D03*
X731291Y509626D03*
X732549Y529136D03*
X732388Y535677D03*
X731291Y559665D03*
X731672Y565574D03*
X731319Y574338D03*
X731418Y616358D03*
X735950Y236611D03*
X735652Y248891D03*
X749586Y410394D03*
Y403307D03*
X741259Y439963D03*
X741381Y430760D03*
X741402Y433570D03*
X741218Y437072D03*
X741503Y443180D03*
X741523Y454744D03*
X741465Y452018D03*
X749402Y458406D03*
Y465492D03*
Y472579D03*
Y479665D03*
Y486752D03*
Y493839D03*
Y523799D03*
Y516713D03*
Y509626D03*
Y537973D03*
Y530886D03*
Y559665D03*
Y566752D03*
Y573839D03*
Y588012D03*
Y580925D03*
Y602185D03*
Y595099D03*
Y609272D03*
Y616358D03*
X751140Y1581335D03*
X740640Y1586885D03*
X748924Y1617709D03*
X735878Y1617010D03*
X763040Y91951D03*
X781393Y102249D03*
X777393D03*
X773393D03*
X779693Y195176D03*
X777193D03*
X782493D03*
X774693D03*
X780741Y206838D03*
X783241D03*
X777053Y203393D03*
X774553D03*
X776943Y321649D03*
X778985Y442498D03*
X778881Y446510D03*
X779029Y450510D03*
X777033Y1595215D03*
X781545Y1602835D03*
X774658Y1601012D03*
X792564Y406410D03*
X784586Y421000D03*
Y418500D03*
Y413500D03*
Y416000D03*
X784665Y564843D03*
X787447Y1593586D03*
X791610Y1593708D03*
X810161Y102323D03*
X810413Y109410D03*
Y116496D03*
X810585Y124576D03*
X811638Y130670D03*
X811633Y137756D03*
X828271Y116496D03*
Y109410D03*
Y102323D03*
Y130670D03*
Y123583D03*
Y137756D03*
X835812Y236611D03*
X838312D03*
X833312D03*
X833014Y248891D03*
X838014D03*
X835514D03*
X867093Y570703D03*
Y582828D03*
Y558703D03*
Y562703D03*
Y566703D03*
Y578703D03*
X872440Y1230083D03*
Y1227583D03*
Y1234483D03*
Y1236983D03*
Y1243883D03*
Y1241383D03*
Y1248283D03*
Y1250783D03*
X889436Y715970D03*
X905094Y424581D03*
X902594D03*
X907594D03*
X905212Y436734D03*
X902712D03*
X907712D03*
X907173Y440581D03*
Y443081D03*
X909024Y578394D03*
Y574394D03*
X909714Y838994D03*
X931393Y102249D03*
X923393D03*
X927393D03*
X925359Y180347D03*
X927859D03*
X925219Y188564D03*
X927719D03*
X919606Y231000D03*
X919577Y245669D03*
Y233858D03*
X919682Y236921D03*
X919577Y259843D03*
Y255118D03*
X919729Y274580D03*
X930359Y180347D03*
X933159D03*
X931407Y192009D03*
X933907D03*
X941505Y463442D03*
X939827Y531104D03*
X939992Y536726D03*
Y540726D03*
Y552726D03*
X936417Y1234483D03*
Y1236983D03*
Y1230083D03*
Y1227583D03*
Y1243883D03*
Y1241383D03*
Y1248283D03*
Y1250783D03*
X956460Y-35982D03*
X953207Y-35996D03*
X956445Y-38497D03*
X953192Y-38511D03*
X950167Y-37191D03*
X960161Y102323D03*
X960413Y109410D03*
Y116496D03*
X961638Y130670D03*
X961633Y137756D03*
X950315Y464851D03*
X949823Y487982D03*
X949876Y478486D03*
X949823Y483982D03*
Y499982D03*
X978036Y-77691D03*
X978051Y-75176D03*
X975011Y-76371D03*
X978271Y109410D03*
Y102323D03*
Y116496D03*
Y130670D03*
Y123583D03*
X963360Y121459D03*
X978271Y137756D03*
X977150Y328472D03*
Y335472D03*
X967816Y472905D03*
X972397Y472954D03*
X973843Y500086D03*
X978668Y527449D03*
X975868D03*
X964012Y546830D03*
X978857Y1360945D03*
X981289Y-77677D03*
X981304Y-75162D03*
X985812Y236611D03*
X988312D03*
X983312D03*
X983014Y248891D03*
X988014D03*
X985514D03*
X980397Y473045D03*
X985699Y480705D03*
X988499D03*
X989068Y532949D03*
X986268D03*
X981857Y1360945D03*
X978944Y1413859D03*
X981944D03*
X1007611Y1561247D03*
Y1558247D03*
Y1555247D03*
Y1552247D03*
X1004611Y1561247D03*
Y1558247D03*
Y1555247D03*
Y1552247D03*
X1015402Y91951D03*
X1025755Y102249D03*
X1027055Y195176D03*
X1033755Y102249D03*
X1029755D03*
X1032055Y195176D03*
X1029555D03*
X1034855D03*
X1033103Y206838D03*
X1035603D03*
X1029415Y203393D03*
X1062523Y102323D03*
X1062775Y109410D03*
Y116496D03*
X1062947Y124576D03*
X1064000Y130670D03*
X1063995Y137756D03*
X1080633Y102323D03*
Y116496D03*
Y109410D03*
Y130670D03*
Y123583D03*
Y137756D03*
X1085674Y236611D03*
X1088174D03*
X1090674D03*
X1090376Y248891D03*
X1087876D03*
X1085376D03*
X1077855Y327478D03*
X1077252Y323521D03*
Y318565D03*
X1077855Y332434D03*
X1099342Y389154D03*
Y396240D03*
X1100621Y404911D03*
X1099575Y412571D03*
X1100762Y426299D03*
X1101073Y445847D03*
X1099342Y467539D03*
Y474626D03*
X1099603Y480828D03*
X1101553Y498834D03*
X1099342Y518760D03*
Y511673D03*
Y525847D03*
X1105298Y598400D03*
Y602400D03*
Y594400D03*
Y614400D03*
Y606400D03*
X1117764Y91951D03*
X1117453Y389154D03*
Y396240D03*
Y403327D03*
Y410413D03*
Y417500D03*
Y424586D03*
Y431673D03*
Y438760D03*
Y445847D03*
Y467539D03*
Y474626D03*
Y488799D03*
Y481713D03*
Y495886D03*
Y511673D03*
Y518760D03*
Y525847D03*
Y532933D03*
Y540020D03*
Y554193D03*
Y547106D03*
Y602205D03*
Y595118D03*
X1136117Y102249D03*
X1132117D03*
X1128117D03*
X1134417Y195176D03*
X1131917D03*
X1137217D03*
X1129417D03*
X1137965Y206838D03*
X1131777Y203393D03*
X1135465Y206838D03*
X1142440Y404718D03*
Y412718D03*
X1125287Y592897D03*
X1142440Y392718D03*
Y400718D03*
Y408718D03*
X1164885Y102323D03*
X1165137Y109410D03*
Y116496D03*
X1165309Y124576D03*
X1166362Y130670D03*
X1166357Y137756D03*
X1182995Y116496D03*
Y109410D03*
Y102323D03*
Y130670D03*
Y123583D03*
Y137756D03*
X1188036Y236611D03*
X1187738Y248891D03*
X1188378Y466027D03*
X1188520Y475262D03*
Y489435D03*
Y482666D03*
X1188336Y495088D03*
X1189071Y514608D03*
X1188993Y522134D03*
X1188378Y509626D03*
X1189475Y535677D03*
X1189636Y529136D03*
X1188378Y559665D03*
X1188759Y565574D03*
X1188406Y574338D03*
X1188505Y616358D03*
X1190536Y236611D03*
X1193036D03*
X1192738Y248891D03*
X1190238D03*
X1198468Y430760D03*
X1198489Y433570D03*
X1198305Y437072D03*
X1198346Y439963D03*
X1198552Y452018D03*
X1198590Y443180D03*
X1198610Y454744D03*
X1220126Y91951D03*
X1206673Y410394D03*
Y403307D03*
X1206489Y458406D03*
Y465492D03*
Y472579D03*
Y479665D03*
Y486752D03*
Y493839D03*
Y523799D03*
Y516713D03*
Y509626D03*
Y537973D03*
Y530886D03*
Y566752D03*
Y559665D03*
Y580925D03*
Y588012D03*
Y573839D03*
Y602185D03*
Y595099D03*
Y616358D03*
Y609272D03*
X1231336Y-87691D03*
X1234589Y-87777D03*
X1231351Y-85176D03*
X1234604Y-85262D03*
X1228311Y-86371D03*
X1236692Y-48727D03*
X1236707Y-46212D03*
X1233667Y-47421D03*
X1238479Y102249D03*
X1230479D03*
X1234479D03*
X1236779Y195176D03*
X1234279D03*
X1239579D03*
X1231779D03*
X1234139Y203393D03*
X1231639D03*
X1237827Y206838D03*
X1234100Y322924D03*
X1239945Y-48727D03*
X1239960Y-46212D03*
X1240327Y206838D03*
X1241752Y564843D03*
X1267499Y116496D03*
X1267247Y102323D03*
X1267499Y109410D03*
X1267671Y124576D03*
X1268724Y130670D03*
X1268719Y137756D03*
X1259500Y330000D03*
X1285357Y116496D03*
Y109410D03*
Y102323D03*
Y123583D03*
Y130670D03*
Y137756D03*
X1281834Y374839D03*
X1290398Y236611D03*
X1295398D03*
X1292898D03*
X1290100Y248891D03*
X1292600D03*
X1295100D03*
X1301500Y329000D03*
X1292731Y331820D03*
X1300400Y339619D03*
Y344575D03*
X1290066Y804246D03*
X1319000Y566500D03*
Y582500D03*
Y613000D03*
Y629000D03*
Y657500D03*
Y673500D03*
Y704500D03*
Y720500D03*
X1305412Y799061D03*
X1318178Y1198321D03*
Y1200821D03*
X1325941Y408240D03*
X1328441D03*
X1323441D03*
X1326059Y420393D03*
X1326020Y424240D03*
X1323559Y420393D03*
X1328559D03*
X1326020Y426740D03*
X1335802Y896011D03*
X1332355Y1113822D03*
Y1119422D03*
X1334835Y1113822D03*
Y1119422D03*
X1331643Y1200821D03*
Y1198321D03*
X1344768Y769675D03*
X1337315Y1113822D03*
Y1119422D03*
X1345108Y1200821D03*
Y1198321D03*
X1361039Y327099D03*
Y332055D03*
X1364039Y334973D03*
Y339929D03*
X1361039Y342847D03*
X1364039Y350721D03*
X1361039Y347803D03*
X1364039Y355677D03*
X1360352Y447101D03*
X1364148Y896011D03*
X1364418Y1090568D03*
Y1093068D03*
X1366963Y1119422D03*
Y1113822D03*
X1364483Y1119422D03*
Y1113822D03*
X1380480Y102249D03*
X1384480D03*
X1384280Y195176D03*
X1381780D03*
X1384140Y203393D03*
X1381640D03*
X1384253Y346826D03*
X1384447Y356871D03*
X1384174Y362641D03*
X1379896Y870814D03*
Y883413D03*
X1383046Y899161D03*
X1369443Y1119422D03*
Y1113822D03*
X1388480Y102249D03*
X1389580Y195176D03*
X1386780D03*
X1390328Y206838D03*
X1387828D03*
X1385943Y323222D03*
X1385971Y327688D03*
X1386143Y331982D03*
X1386057Y341200D03*
X1385971Y336791D03*
X1386286Y350218D03*
X1397079Y531726D03*
Y536726D03*
Y552726D03*
Y540726D03*
X1397942Y1119422D03*
X1400422D03*
Y1113822D03*
X1397942D03*
X1391380Y1200821D03*
Y1198321D03*
X1417248Y102323D03*
X1416347Y384373D03*
X1406910Y487982D03*
Y478982D03*
Y483982D03*
Y499982D03*
X1410000Y689000D03*
Y705000D03*
Y733000D03*
Y749000D03*
X1402902Y1119422D03*
Y1113822D03*
X1404845Y1198321D03*
Y1200821D03*
X1404239Y1547755D03*
X1403747Y1570433D03*
X1417500Y109410D03*
Y116496D03*
X1421700Y122900D03*
X1418725Y130670D03*
X1418720Y137756D03*
X1427484Y470045D03*
X1422903Y469905D03*
X1430930Y500086D03*
X1432955Y527449D03*
X1421099Y546830D03*
X1427000Y774500D03*
Y790500D03*
Y818500D03*
Y834500D03*
X1430005Y1090568D03*
Y1093068D03*
X1432550Y1119422D03*
Y1113822D03*
X1430070Y1119422D03*
Y1113822D03*
X1418310Y1198321D03*
Y1200821D03*
X1435358Y116496D03*
Y109410D03*
Y102323D03*
Y130670D03*
Y123583D03*
Y137756D03*
X1440399Y236611D03*
X1442899D03*
X1445399D03*
X1440101Y248891D03*
X1442601D03*
X1445101D03*
X1435484Y470045D03*
X1442786Y480705D03*
X1445586D03*
X1435755Y527449D03*
X1443555Y532949D03*
X1446355D03*
X1435030Y1119422D03*
Y1113822D03*
X1437293Y1546125D03*
X1436801Y1568803D03*
X1451215Y323193D03*
X1451330Y327588D03*
X1451272Y340971D03*
X1451344Y336620D03*
X1451300Y332225D03*
X1451387Y345609D03*
X1451186Y350447D03*
X1472489Y91951D03*
X1479500Y706500D03*
Y750500D03*
X1487836Y-87777D03*
X1491089D03*
X1487851Y-85262D03*
X1491104D03*
X1484811Y-86371D03*
X1490842Y102249D03*
X1486842D03*
X1482842D03*
X1486642Y195176D03*
X1489142D03*
X1484142D03*
X1491942D03*
X1492690Y206838D03*
X1490190D03*
X1484002Y203393D03*
X1486502D03*
X1484796Y320359D03*
X1484968Y325025D03*
X1484876Y329377D03*
X1488255Y342921D03*
X1484682Y338394D03*
X1497760Y336543D03*
X1487926Y347387D03*
X1496500Y792000D03*
Y836000D03*
X1500480Y295727D03*
X1523192Y-48857D03*
X1526445D03*
X1523207Y-46342D03*
X1526460D03*
X1520167Y-47451D03*
X1519610Y102323D03*
X1519862Y109410D03*
Y116496D03*
X1520034Y124576D03*
X1521087Y130670D03*
X1521082Y137756D03*
X1527876Y939439D03*
X1537720Y116496D03*
Y109410D03*
Y102323D03*
Y130670D03*
Y123583D03*
Y137756D03*
X1542761Y236611D03*
X1545261D03*
X1542463Y248891D03*
X1544963D03*
X1541534Y322850D03*
X1547761Y236611D03*
X1547463Y248891D03*
X1547972Y304906D03*
X1556151Y318596D03*
X1556294Y327814D03*
X1556437Y332022D03*
X1556380Y336917D03*
X1556498Y340958D03*
X1556353Y345636D03*
X1556429Y389154D03*
Y396240D03*
X1557708Y404911D03*
X1556662Y412571D03*
X1557849Y426299D03*
X1558160Y445847D03*
X1556429Y467539D03*
Y474626D03*
X1556690Y480828D03*
X1558640Y498834D03*
X1556429Y518760D03*
Y511673D03*
Y525847D03*
X1562385Y598400D03*
Y602400D03*
Y594400D03*
Y614400D03*
Y606400D03*
X1574851Y91951D03*
X1574845Y338843D03*
X1574540Y389154D03*
Y396240D03*
Y403327D03*
Y410413D03*
Y417500D03*
Y424586D03*
Y438760D03*
Y431673D03*
Y445847D03*
Y467539D03*
Y474626D03*
Y488799D03*
Y481713D03*
Y495886D03*
Y511673D03*
Y518760D03*
Y540020D03*
Y525847D03*
Y532933D03*
Y547106D03*
Y554193D03*
Y602205D03*
Y595118D03*
X1593204Y102249D03*
X1585204D03*
X1589204D03*
X1586504Y195176D03*
X1594304D03*
X1589004D03*
X1591504D03*
X1586364Y203393D03*
X1588864D03*
X1595052Y206838D03*
X1592552D03*
X1593290Y339876D03*
X1597006Y290417D03*
X1599527Y392718D03*
Y408718D03*
Y400718D03*
Y404718D03*
Y412718D03*
X1621972Y102323D03*
X1622224Y109410D03*
Y116496D03*
X1622396Y124576D03*
X1623449Y130670D03*
X1623444Y137756D03*
X1640082Y116496D03*
Y109410D03*
Y102323D03*
Y130670D03*
Y123583D03*
Y137756D03*
X1644825Y248891D03*
X1632230Y330400D03*
X1645123Y236611D03*
X1650123D03*
X1647623D03*
X1647325Y248891D03*
X1649825D03*
X1655555Y430760D03*
X1655576Y433570D03*
X1655392Y437072D03*
X1655433Y439963D03*
X1655677Y443180D03*
X1655697Y454744D03*
X1655639Y452018D03*
X1645465Y466027D03*
X1645607Y475262D03*
Y489435D03*
Y482666D03*
X1645423Y495088D03*
X1646158Y514608D03*
X1646080Y522134D03*
X1645465Y509626D03*
X1646562Y535677D03*
X1646723Y529136D03*
X1645465Y559665D03*
X1645846Y565574D03*
X1645493Y574338D03*
X1645592Y616358D03*
X1677213Y91951D03*
X1663760Y410394D03*
Y403307D03*
X1663576Y458406D03*
Y465492D03*
Y472579D03*
Y479665D03*
Y486752D03*
Y493839D03*
Y523799D03*
Y516713D03*
Y509626D03*
Y537973D03*
Y530886D03*
Y559665D03*
Y566752D03*
Y580925D03*
Y588012D03*
Y573839D03*
Y602185D03*
Y595099D03*
Y616358D03*
Y609272D03*
X1695566Y102249D03*
X1687566D03*
X1691566D03*
X1691366Y195176D03*
X1688866D03*
X1691226Y203393D03*
X1688726D03*
X1691117Y321649D03*
X1696666Y195176D03*
X1693866D03*
X1697414Y206838D03*
X1694914D03*
X1698839Y564843D03*
X1724334Y102323D03*
X1724586Y109410D03*
Y116496D03*
X1724758Y124576D03*
X1725811Y130670D03*
X1725806Y137756D03*
X1715705Y328692D03*
X1712734Y340534D03*
X1742336Y-87777D03*
X1739311Y-86371D03*
X1734826Y376499D03*
X1745589Y-87777D03*
X1742351Y-85262D03*
X1745604D03*
X1742444Y102323D03*
Y116496D03*
Y109410D03*
Y130670D03*
Y123583D03*
Y137756D03*
X1752485Y236611D03*
X1749985D03*
X1747485D03*
X1747187Y248891D03*
X1749687D03*
X1752187D03*
X1747561Y385161D03*
X1758583Y1581027D03*
X1750685Y1618504D03*
X1756422Y1640303D03*
X1770680Y926322D03*
X1763818Y926241D03*
X1765294Y1575434D03*
X1759092Y1588137D03*
X1767142Y1588219D03*
X1764422Y1640303D03*
X1779575Y91951D03*
X1790533Y303750D03*
X1783028Y408240D03*
X1785528D03*
X1780528D03*
X1783107Y424240D03*
X1780646Y420393D03*
X1785646D03*
X1783146D03*
X1783107Y426740D03*
X1780397Y1237469D03*
Y1230569D03*
Y1228069D03*
Y1234969D03*
Y1241869D03*
Y1244369D03*
Y1248769D03*
Y1251269D03*
X1776422Y1640303D03*
X1804667Y-47581D03*
X1804993Y297591D03*
X1807692Y-49001D03*
X1810945Y-48987D03*
X1807707Y-46486D03*
X1810960Y-46472D03*
X1817439Y447101D03*
G54D31*
X106586Y1204932D03*
X563673D03*
X1020434Y1205579D03*
X1477846Y1204932D03*
G54D39*
X190325Y368760D03*
Y455492D03*
Y503760D03*
Y583957D03*
Y636752D03*
X647411Y368760D03*
Y455492D03*
Y503760D03*
Y583957D03*
Y636752D03*
X1104498Y368760D03*
Y455492D03*
Y503760D03*
Y583957D03*
Y636752D03*
X1561585Y368760D03*
Y455492D03*
Y503760D03*
Y583957D03*
Y636752D03*
G54D43*
X515573Y692515D03*
X518299Y692384D03*
X520799D03*
X529493Y692443D03*
Y697443D03*
Y699943D03*
X529501Y702622D03*
X526993Y692443D03*
X529493Y694943D03*
X524493Y692443D03*
X1809078Y2165771D03*
X1806706Y2180760D03*
X1812366Y2063809D03*
X1822066Y2054109D03*
X1812366D03*
X1813087Y2087512D03*
X1825427Y2104853D03*
X1817378Y2165771D03*
X1815006Y2180760D03*
X1841295Y2065122D03*
X1832995D03*
X1833649Y2057507D03*
X1830872Y2083503D03*
X1840875Y2083215D03*
X1837649Y2072324D03*
X1829349D03*
X1833727Y2104853D03*
X1835862Y2121040D03*
X1833506Y2185252D03*
X1852032Y2052576D03*
X1854559Y2077931D03*
X1851762Y2121040D03*
X1854796Y2170548D03*
X1846496D03*
X1855978Y2185118D03*
X1847678D03*
X1859032Y2052576D03*
X1870505Y2064156D03*
X1860338Y2071384D03*
X1874505Y2078973D03*
X1860234Y2157701D03*
X1867072Y2174962D03*
X1864547Y2185020D03*
X1890039Y2066092D03*
X1878805Y2064156D03*
X1886128Y2075919D03*
X1882805Y2078973D03*
X1876497Y2070684D03*
X1884535Y2155415D03*
X1882972Y2174962D03*
X1882111Y2179074D03*
X1874932Y2180585D03*
X1881852Y2196600D03*
X1886699Y2183170D03*
X1876697D03*
X1905939Y2066092D03*
X1893118Y2054585D03*
X1905944Y2055424D03*
X1898342Y2062143D03*
X1901295Y2072745D03*
X1892835Y2155415D03*
X1902872Y2178531D03*
X1894572D03*
X1893087Y2168011D03*
X1896403Y2185019D03*
X1917195Y2072745D03*
X1917550Y2158451D03*
X1909250D03*
X1922010Y2151829D03*
X1913710D03*
X1921855Y2172152D03*
X1936295Y2074343D03*
X1935195Y2155918D03*
X1936377Y2163810D03*
X1924735Y2178131D03*
X1936212Y2173508D03*
X1930155Y2172152D03*
X1931738Y2182647D03*
X1923438D03*
X1941040Y2070124D03*
X1951095Y2155918D03*
X1946077Y2163810D03*
X1969128Y2161283D03*
X1959428D03*
X1969128Y2151583D03*
X1959428D03*
G54D51*
X909360Y230906D03*
Y274606D03*
G54D22*
X51043Y144095D03*
X57933Y66811D03*
X160295D03*
X153405Y144095D03*
X183435Y630650D03*
X190325Y374862D03*
X262657Y66811D03*
X255767Y144095D03*
X279360Y630650D03*
X286250Y374862D03*
X358129Y144095D03*
X365019Y66811D03*
X508130Y144095D03*
X515020Y66811D03*
X617382D03*
X610492Y144095D03*
X647411Y374862D03*
X640521Y630650D03*
X719744Y66811D03*
X712854Y144095D03*
X736446Y630650D03*
X743336Y374862D03*
X815216Y144095D03*
X822106Y66811D03*
X972106D03*
X965216Y144095D03*
X1074468Y66811D03*
X1067578Y144095D03*
X1104498Y374862D03*
X1097608Y630650D03*
X1169940Y144095D03*
X1176830Y66811D03*
X1200423Y374862D03*
X1193533Y630650D03*
X1272302Y144095D03*
X1279192Y66811D03*
X1429193D03*
X1422303Y144095D03*
X1531555Y66811D03*
X1524665Y144095D03*
X1561585Y374862D03*
X1554695Y630650D03*
X1627027Y144095D03*
X1633917Y66811D03*
X1657510Y374862D03*
X1650620Y630650D03*
X1736279Y66811D03*
X1729389Y144095D03*
G54D25*
X46248Y1760941D03*
Y1750941D03*
Y1806941D03*
Y1796941D03*
X143208Y1084547D03*
Y1092027D03*
X146948Y1077066D03*
Y1084547D03*
Y1092027D03*
X143208Y1095767D03*
X146948D03*
X143208Y1110728D03*
Y1118208D03*
X146948Y1110728D03*
Y1118208D03*
X146949Y1166830D03*
X154429Y1073326D03*
X161909D03*
X154429Y1092027D03*
X161909Y1077066D03*
X165649Y1080807D03*
Y1088287D03*
X161909D03*
Y1092027D03*
X154429Y1077066D03*
X158169Y1080807D03*
X150689D03*
X158169Y1084547D03*
X150689D03*
X158169Y1088287D03*
X154429D03*
X150689D03*
X165649Y1084547D03*
X158169Y1099507D03*
X150689D03*
X158169Y1103247D03*
X150689D03*
X161909Y1095767D03*
X165649Y1099507D03*
Y1103247D03*
X154429Y1106988D03*
X150689D03*
X154429Y1095767D03*
X158169Y1110728D03*
Y1114468D03*
X154429D03*
X150689D03*
X158169Y1129429D03*
X165649Y1166830D03*
Y1170570D03*
Y1178050D03*
Y1174310D03*
X163779Y1213582D03*
X160039D03*
X214271Y1114468D03*
X238582Y1078936D03*
X242322Y1082677D03*
X238582Y1097637D03*
X246062Y1254724D03*
X238582D03*
Y1250984D03*
X234842Y1247243D03*
X242322Y1243503D03*
Y1247243D03*
X246062Y1250984D03*
X249803Y1082677D03*
X257283D03*
X249803Y1101377D03*
X253543Y1250984D03*
Y1254724D03*
X249803Y1247243D03*
X253543Y1239763D03*
X249803D03*
X257283Y1247243D03*
X261023Y1250984D03*
Y1239763D03*
Y1254724D03*
X279724Y1082677D03*
Y1086417D03*
X275984Y1078936D03*
X264763Y1082677D03*
X275984Y1097637D03*
X274114Y1121948D03*
X277854Y1133169D03*
Y1125688D03*
X274114Y1204232D03*
X279724Y1247243D03*
X272244Y1243503D03*
Y1247243D03*
X264763D03*
X268503Y1250984D03*
X264763Y1243503D03*
X272244Y1239763D03*
X275984Y1250984D03*
X279724Y1243503D03*
X268503Y1254724D03*
X275984D03*
X294684Y1082677D03*
Y1090157D03*
X294685Y1086417D03*
X290944Y1078936D03*
X287204Y1082677D03*
X283464Y1093897D03*
X290944Y1097637D03*
X294685Y1247243D03*
Y1243503D03*
X283464Y1250984D03*
X287204Y1247243D03*
Y1243503D03*
Y1239763D03*
X290944Y1250984D03*
X283464Y1254724D03*
X290944D03*
X302164Y1082677D03*
X302165Y1086417D03*
X309644Y1082677D03*
X309645Y1086417D03*
X298425Y1097637D03*
X305905D03*
X300295Y1155610D03*
X309645Y1247243D03*
Y1243503D03*
X298425Y1250984D03*
X302165Y1247243D03*
Y1243503D03*
Y1239763D03*
X305905Y1250984D03*
X298425Y1254724D03*
X305905D03*
X320866Y1086417D03*
X317126D03*
X317125Y1082677D03*
X324606Y1086417D03*
X320866Y1093897D03*
X324606D03*
Y1105117D03*
Y1097637D03*
X320866Y1105117D03*
Y1097637D03*
X313385D03*
X324606Y1112598D03*
Y1120078D03*
X320866Y1112598D03*
Y1120078D03*
X317125Y1108858D03*
X320866Y1127558D03*
Y1135039D03*
X322736Y1140649D03*
X324606Y1127558D03*
Y1135039D03*
X326476Y1140649D03*
X322736Y1155610D03*
X326476Y1148129D03*
Y1155610D03*
X322736Y1148129D03*
X326476Y1170570D03*
Y1178051D03*
Y1185531D03*
X320866Y1250984D03*
X313385D03*
X317125Y1247243D03*
Y1243503D03*
X313385Y1254724D03*
X317125Y1239763D03*
X320866Y1254724D03*
X333286Y1728583D03*
Y1738583D03*
X333212Y1774624D03*
Y1784624D03*
X438162Y1348187D03*
Y1360099D03*
Y1384297D03*
Y1372385D03*
X450402Y1348187D03*
Y1360099D03*
Y1384297D03*
Y1372385D03*
Y1396583D03*
Y1408495D03*
X462642Y1348187D03*
X474882D03*
X462642Y1360099D03*
X474882D03*
X462642Y1384297D03*
X474882D03*
X462642Y1372385D03*
X474882D03*
Y1396583D03*
X462642D03*
X474882Y1408495D03*
X462642D03*
X487122Y1348187D03*
Y1360099D03*
Y1372385D03*
Y1384297D03*
Y1396583D03*
Y1408495D03*
X499362Y1348187D03*
Y1360099D03*
Y1372385D03*
Y1384297D03*
Y1396583D03*
Y1408495D03*
X511602Y1348187D03*
Y1360099D03*
Y1372385D03*
Y1384297D03*
Y1396583D03*
Y1408495D03*
X536082Y1348187D03*
X523842D03*
X536082Y1360099D03*
X523842D03*
Y1384297D03*
Y1372385D03*
X536082Y1384297D03*
Y1372385D03*
Y1396583D03*
X523842D03*
X536082Y1408495D03*
X523842D03*
X548322Y1348187D03*
Y1360099D03*
Y1384297D03*
Y1372385D03*
Y1396583D03*
Y1408495D03*
X560562Y1348187D03*
Y1360099D03*
Y1384297D03*
Y1372385D03*
Y1396583D03*
Y1408495D03*
X600295Y1084547D03*
Y1092027D03*
X604035Y1077066D03*
Y1084547D03*
Y1092027D03*
X600295Y1095767D03*
X604035D03*
X600295Y1110728D03*
Y1118208D03*
X604035Y1110728D03*
Y1118208D03*
X604036Y1166830D03*
X611516Y1073326D03*
X618996D03*
Y1088287D03*
Y1092027D03*
X611516Y1077066D03*
X615256Y1080807D03*
X607776D03*
X615256Y1084547D03*
X607776D03*
X615256Y1088287D03*
X611516D03*
X607776D03*
X611516Y1092027D03*
X618996Y1077066D03*
X611516Y1106988D03*
X607776D03*
X611516Y1095767D03*
X615256Y1099507D03*
X607776D03*
X615256Y1103247D03*
X607776D03*
X618996Y1095767D03*
X615256Y1110728D03*
Y1114468D03*
X611516D03*
X607776D03*
X615256Y1129429D03*
X617126Y1213582D03*
X620866D03*
X620083Y1728286D03*
Y1738286D03*
X619711Y1775438D03*
Y1785438D03*
X626476Y1088287D03*
X622736Y1080807D03*
Y1084547D03*
Y1088287D03*
Y1099507D03*
Y1103247D03*
Y1166830D03*
Y1170570D03*
Y1174310D03*
Y1178050D03*
X636288Y1372385D03*
Y1384297D03*
Y1396583D03*
X624048D03*
X636288Y1408495D03*
X624048D03*
X648528Y1348187D03*
Y1360099D03*
Y1372385D03*
Y1384297D03*
Y1396583D03*
Y1408495D03*
X660768Y1348187D03*
Y1360099D03*
Y1372385D03*
Y1384297D03*
Y1396583D03*
Y1408495D03*
X671358Y1114468D03*
X673008Y1348187D03*
X685248D03*
X673008Y1360099D03*
X685248D03*
Y1372385D03*
Y1384297D03*
X673008Y1372385D03*
Y1384297D03*
X685248Y1396583D03*
X673008D03*
X685248Y1408495D03*
X673008D03*
X695669Y1078936D03*
X699409Y1082677D03*
X695669Y1097637D03*
X699409Y1247243D03*
Y1243503D03*
X691929Y1247243D03*
X695669Y1250984D03*
Y1254724D03*
X697488Y1348187D03*
Y1360099D03*
Y1384297D03*
Y1372385D03*
Y1396583D03*
Y1408495D03*
X706890Y1082677D03*
X714370D03*
X706890Y1101377D03*
X703149Y1254724D03*
Y1250984D03*
X718110D03*
Y1239763D03*
X714370Y1247243D03*
X710630Y1254724D03*
Y1250984D03*
Y1239763D03*
X706890Y1247243D03*
Y1239763D03*
X718110Y1254724D03*
X709728Y1348187D03*
Y1360099D03*
Y1384297D03*
Y1372385D03*
Y1396583D03*
Y1408495D03*
X721850Y1082677D03*
X733071Y1078936D03*
Y1097637D03*
X731201Y1121948D03*
X734941Y1125688D03*
Y1133169D03*
X731201Y1204232D03*
X729331Y1243503D03*
X721850D03*
X729331Y1239763D03*
Y1247243D03*
X733071Y1250984D03*
Y1254724D03*
X725590D03*
Y1250984D03*
X721850Y1247243D03*
X734208Y1348187D03*
X721968D03*
X734208Y1360099D03*
X721968D03*
Y1384297D03*
Y1372385D03*
X734208D03*
Y1384297D03*
X721968Y1396489D03*
X734208D03*
X721968Y1408401D03*
X734208D03*
X744291Y1082677D03*
X748031Y1078936D03*
X736811Y1086417D03*
Y1082677D03*
X748031Y1097637D03*
X740551Y1093897D03*
X736811Y1243503D03*
Y1247243D03*
X744291Y1243503D03*
Y1239763D03*
X748031Y1254724D03*
Y1250984D03*
X744291Y1247243D03*
X740551Y1254724D03*
Y1250984D03*
X746448Y1348187D03*
Y1360099D03*
Y1372385D03*
Y1384297D03*
X759251Y1082677D03*
X751772Y1086417D03*
X751771Y1090157D03*
Y1082677D03*
X759252Y1086417D03*
X766732D03*
X766731Y1082677D03*
X762992Y1097637D03*
X755512D03*
X757382Y1155610D03*
X755512Y1250984D03*
Y1254724D03*
X759252Y1247243D03*
Y1243503D03*
X762992Y1250984D03*
Y1254724D03*
X766732Y1247243D03*
Y1243503D03*
X759252Y1239763D03*
X751772Y1247243D03*
Y1243503D03*
X758688Y1348187D03*
Y1360099D03*
Y1372385D03*
Y1384297D03*
X774213Y1086417D03*
X774212Y1082677D03*
X781693Y1086417D03*
X777953D03*
X770472Y1097637D03*
X777953Y1093897D03*
Y1105117D03*
X781693Y1093897D03*
Y1097637D03*
X777953D03*
X781693Y1105117D03*
Y1112598D03*
X777953Y1120078D03*
X781693D03*
X774212Y1108858D03*
X777953Y1112598D03*
X783563Y1140649D03*
X779823D03*
X781693Y1127558D03*
X777953D03*
Y1135039D03*
X781693D03*
X783563Y1155610D03*
Y1148129D03*
X779823Y1155610D03*
Y1148129D03*
X783563Y1170570D03*
Y1185531D03*
Y1178051D03*
X770472Y1250984D03*
Y1254724D03*
X777953Y1250984D03*
X774212Y1247243D03*
Y1243503D03*
Y1239763D03*
X777953Y1254724D03*
X770928Y1348187D03*
Y1360099D03*
X907279Y1738990D03*
Y1728990D03*
X907073Y1776014D03*
Y1786014D03*
X1057381Y1092027D03*
Y1084547D03*
Y1095767D03*
Y1118208D03*
Y1110728D03*
X1068602Y1073326D03*
X1072342Y1088287D03*
Y1084547D03*
Y1080807D03*
X1061121Y1092027D03*
X1068602D03*
X1064862Y1088287D03*
X1068602D03*
X1061121Y1084547D03*
X1064862D03*
Y1080807D03*
X1061121Y1077066D03*
X1068602D03*
X1072342Y1099507D03*
Y1103247D03*
X1061121Y1095767D03*
X1068602D03*
X1064862Y1106988D03*
X1068602D03*
X1064862Y1103247D03*
Y1099507D03*
X1072342Y1114468D03*
Y1110728D03*
X1061121Y1118208D03*
X1064862Y1114468D03*
X1068602D03*
X1061121Y1110728D03*
X1072342Y1129429D03*
X1061122Y1166830D03*
X1074212Y1213582D03*
X1076082Y1073326D03*
X1083562Y1088287D03*
X1079822D03*
Y1084547D03*
Y1080807D03*
X1076082Y1092027D03*
Y1088287D03*
Y1077066D03*
X1079822Y1103247D03*
Y1099507D03*
X1076082Y1095767D03*
X1079822Y1170570D03*
Y1166830D03*
Y1174310D03*
Y1178050D03*
X1077952Y1213582D03*
X1128444Y1114468D03*
X1152755Y1078936D03*
X1156495Y1082677D03*
X1152755Y1097637D03*
Y1254724D03*
Y1250984D03*
X1149015Y1247243D03*
X1156495Y1243503D03*
Y1247243D03*
X1163976Y1082677D03*
X1171456D03*
X1163976Y1101377D03*
Y1239763D03*
Y1247243D03*
X1167716Y1239763D03*
Y1250984D03*
Y1254724D03*
X1171456Y1247243D03*
X1160235Y1250984D03*
Y1254724D03*
X1178936Y1082677D03*
X1188287Y1121948D03*
Y1204232D03*
X1175196Y1254724D03*
Y1239763D03*
Y1250984D03*
X1178936Y1247243D03*
X1182676Y1250984D03*
Y1254724D03*
X1186417Y1247243D03*
Y1239763D03*
X1178936Y1243503D03*
X1186417D03*
X1190157Y1078936D03*
X1201377Y1082677D03*
X1205117Y1078936D03*
X1193897Y1082677D03*
Y1086417D03*
X1190157Y1097637D03*
X1197637Y1093897D03*
X1205117Y1097637D03*
X1192027Y1133169D03*
Y1125688D03*
X1190157Y1254724D03*
Y1250984D03*
X1197637D03*
Y1254724D03*
X1201377Y1247243D03*
X1205117Y1250984D03*
Y1254724D03*
X1201377Y1239763D03*
Y1243503D03*
X1193897Y1247243D03*
Y1243503D03*
X1216337Y1082677D03*
X1216338Y1086417D03*
X1208857Y1082677D03*
X1208858Y1086417D03*
X1208857Y1090157D03*
X1212598Y1097637D03*
X1220078D03*
X1214468Y1155610D03*
X1212598Y1250984D03*
Y1254724D03*
X1216338Y1247243D03*
Y1243503D03*
X1220078Y1250984D03*
Y1254724D03*
X1216338Y1239763D03*
X1208858Y1247243D03*
Y1243503D03*
X1223817Y1082677D03*
X1223818Y1086417D03*
X1231298Y1082677D03*
X1235039Y1086417D03*
X1231299D03*
X1227558Y1097637D03*
X1235039Y1093897D03*
Y1097637D03*
Y1105117D03*
X1231298Y1108858D03*
X1235039Y1112598D03*
Y1120078D03*
X1236909Y1140649D03*
X1235039Y1127558D03*
Y1135039D03*
X1236909Y1148129D03*
Y1155610D03*
X1223818Y1247243D03*
Y1243503D03*
X1227558Y1250984D03*
Y1254724D03*
X1235039Y1250984D03*
X1231298Y1247243D03*
Y1243503D03*
Y1239763D03*
X1235039Y1254724D03*
X1238779Y1086417D03*
Y1093897D03*
Y1097637D03*
Y1105117D03*
Y1112598D03*
Y1120078D03*
X1240649Y1140649D03*
X1238779Y1127558D03*
Y1135039D03*
X1240649Y1148129D03*
Y1155610D03*
Y1170570D03*
Y1178051D03*
Y1185531D03*
X1514468Y1084547D03*
Y1092027D03*
Y1095767D03*
Y1110728D03*
Y1118208D03*
X1525689Y1073326D03*
Y1077066D03*
X1518208D03*
X1529429Y1080807D03*
X1521949D03*
X1529429Y1084547D03*
X1521949D03*
X1518208D03*
X1529429Y1088287D03*
X1525689D03*
X1521949D03*
X1525689Y1092027D03*
X1518208D03*
X1521949Y1103247D03*
X1525689Y1106988D03*
X1521949D03*
X1525689Y1095767D03*
X1518208D03*
X1529429Y1099507D03*
X1521949D03*
X1529429Y1103247D03*
Y1110728D03*
X1518208D03*
X1529429Y1114468D03*
X1525689D03*
X1521949D03*
X1518208Y1118208D03*
X1529429Y1129429D03*
X1518209Y1166830D03*
X1533169Y1073326D03*
X1540649Y1088287D03*
X1533169Y1077066D03*
X1536909Y1080807D03*
Y1084547D03*
Y1088287D03*
X1533169D03*
Y1092027D03*
Y1095767D03*
X1536909Y1099507D03*
Y1103247D03*
Y1166830D03*
Y1170570D03*
Y1174310D03*
X1535039Y1176180D03*
Y1213582D03*
X1531299D03*
X1585531Y1114468D03*
X1609842Y1078936D03*
Y1097637D03*
Y1254724D03*
Y1250984D03*
X1606102Y1247243D03*
X1613582Y1082677D03*
X1621063D03*
Y1101377D03*
X1613582Y1243503D03*
Y1247243D03*
X1621063Y1239763D03*
Y1247243D03*
X1624803Y1239763D03*
Y1250984D03*
Y1254724D03*
X1617322Y1250984D03*
Y1254724D03*
X1636023Y1082677D03*
X1628543D03*
X1632283Y1254724D03*
X1628543Y1247243D03*
X1632283Y1239763D03*
Y1250984D03*
X1636023Y1247243D03*
X1639763Y1250984D03*
Y1254724D03*
X1643504Y1247243D03*
Y1239763D03*
X1636023Y1243503D03*
X1643504D03*
X1658464Y1082677D03*
X1650984D03*
Y1086417D03*
X1647244Y1078936D03*
Y1097637D03*
X1654724Y1093897D03*
X1645374Y1121948D03*
X1649114Y1133169D03*
Y1125688D03*
X1645374Y1204232D03*
X1647244Y1254724D03*
Y1250984D03*
X1654724D03*
Y1254724D03*
X1658464Y1247243D03*
Y1239763D03*
Y1243503D03*
X1650984Y1247243D03*
Y1243503D03*
X1662204Y1078936D03*
X1673424Y1082677D03*
X1673425Y1086417D03*
X1665944Y1082677D03*
X1665945Y1086417D03*
X1665944Y1090157D03*
X1662204Y1097637D03*
X1669685D03*
X1671555Y1155610D03*
X1665945Y1247243D03*
Y1243503D03*
X1662204Y1250984D03*
Y1254724D03*
X1669685Y1250984D03*
Y1254724D03*
X1673425Y1247243D03*
Y1243503D03*
Y1239763D03*
X1680904Y1082677D03*
X1680905Y1086417D03*
X1688385Y1082677D03*
X1692126Y1086417D03*
X1688386D03*
X1677165Y1097637D03*
X1684645D03*
X1692126Y1093897D03*
Y1097637D03*
Y1105117D03*
X1688385Y1108858D03*
X1692126Y1112598D03*
Y1120078D03*
Y1127558D03*
Y1135039D03*
X1684645Y1250984D03*
Y1254724D03*
X1692126Y1250984D03*
X1688385Y1247243D03*
Y1243503D03*
Y1239763D03*
X1692126Y1254724D03*
X1677165Y1250984D03*
Y1254724D03*
X1680905Y1247243D03*
Y1243503D03*
X1695866Y1086417D03*
Y1093897D03*
Y1097637D03*
Y1105117D03*
Y1112598D03*
Y1120078D03*
X1697736Y1140649D03*
X1693996D03*
X1695866Y1127558D03*
Y1135039D03*
X1697736Y1148129D03*
X1693996D03*
X1697736Y1155610D03*
X1693996D03*
X1697736Y1170570D03*
Y1178051D03*
Y1185531D03*
G54D37*
X145078Y1250984D03*
X148818Y1243503D03*
Y1250984D03*
X145078Y1243503D03*
X161909Y1125688D03*
X158169Y1151869D03*
X154429D03*
Y1166830D03*
X160039Y1194881D03*
Y1202362D03*
Y1209842D03*
Y1217322D03*
X156299Y1250984D03*
X160039Y1247243D03*
X152559D03*
X156299Y1239763D03*
X163779Y1250984D03*
X156299Y1254724D03*
X163779D03*
X178740Y1075196D03*
X171259D03*
X178740Y1078936D03*
X174999Y1086417D03*
Y1082677D03*
X171259Y1078936D03*
X182480Y1086417D03*
Y1082677D03*
X174999Y1093897D03*
X182480D03*
X171259Y1097637D03*
X182480D03*
X174999D03*
X178740Y1101376D03*
Y1105117D03*
X173129Y1129428D03*
X169389D03*
X180610Y1170570D03*
X174999Y1209842D03*
X167519Y1221062D03*
X182480Y1236023D03*
Y1232283D03*
X174999D03*
Y1236023D03*
X182480Y1239763D03*
Y1247243D03*
X178740Y1250984D03*
Y1239763D03*
X174999Y1243503D03*
X178740Y1254724D03*
X171259D03*
X167519Y1247243D03*
X186220Y1075196D03*
X193700D03*
X189960Y1086417D03*
Y1082677D03*
X193700Y1078936D03*
X186220D03*
X197440Y1086417D03*
Y1082677D03*
X193700Y1105117D03*
X197440Y1093897D03*
X189960Y1097637D03*
X186220Y1105117D03*
X197440Y1097637D03*
X193700Y1101376D03*
X186220D03*
X188090Y1178051D03*
Y1193011D03*
X197440Y1236023D03*
Y1232283D03*
X189960Y1236023D03*
Y1232283D03*
X197440Y1247243D03*
X193700Y1254724D03*
X186220D03*
X189960Y1239763D03*
X186220Y1250984D03*
X189960Y1247243D03*
X193700Y1250984D03*
X201181Y1075196D03*
X208661D03*
Y1078936D03*
X212401Y1086417D03*
Y1082677D03*
X204921Y1086417D03*
Y1082677D03*
X201181Y1078936D03*
X204921Y1097637D03*
X208661Y1101376D03*
X212401Y1097637D03*
X208661Y1105117D03*
X212401Y1093897D03*
X201181Y1101376D03*
X204921Y1093897D03*
X201181Y1105117D03*
X204921Y1232283D03*
X212401D03*
Y1236023D03*
X204921D03*
X208661Y1250984D03*
X201181Y1239763D03*
X212401D03*
Y1247243D03*
X201181Y1254724D03*
X204921Y1239763D03*
X201181Y1250984D03*
X204921Y1247243D03*
X208661Y1254724D03*
X213969Y1445013D03*
Y1456013D03*
X223622Y1075196D03*
X231102D03*
X216141D03*
X227362Y1086417D03*
Y1082677D03*
X219881Y1086417D03*
Y1082677D03*
X223622Y1078936D03*
X231102D03*
X216141D03*
Y1101376D03*
X231102D03*
X227362Y1093897D03*
X219881Y1097637D03*
X223621Y1101376D03*
Y1105117D03*
X216141D03*
X219881Y1093897D03*
X227362Y1097637D03*
X231102Y1105117D03*
X219881Y1232283D03*
Y1236023D03*
X227362Y1232283D03*
Y1236023D03*
X223622Y1254724D03*
X231102D03*
X227362Y1247243D03*
X219881Y1239763D03*
X223622Y1250984D03*
X219881Y1247243D03*
X231102Y1250984D03*
X227362Y1239763D03*
X216141Y1250984D03*
Y1254724D03*
X227249Y1445013D03*
Y1456013D03*
X234841Y1093897D03*
X246062Y1105117D03*
X242321Y1097637D03*
X234841D03*
X238582Y1101376D03*
X246062D03*
X238582Y1105117D03*
X242321Y1093897D03*
X246062Y1221062D03*
X234842Y1239763D03*
Y1243503D03*
X242322Y1239763D03*
X257283Y1101377D03*
X253543Y1105117D03*
Y1101376D03*
X261023Y1105117D03*
Y1101376D03*
X249803Y1221062D03*
X253543D03*
X261023D03*
X257283D03*
X249803Y1243503D03*
X257283D03*
X272244Y1101377D03*
X279724D03*
X264763D03*
X264762Y1097637D03*
X268503Y1105117D03*
X272243Y1097637D03*
X275984Y1105117D03*
X279723Y1093897D03*
X272243D03*
X279723Y1097637D03*
X268503Y1101376D03*
X275984D03*
X264762Y1093897D03*
X277854Y1121948D03*
Y1129429D03*
X264763Y1221062D03*
X279724Y1239763D03*
X275984D03*
X264763D03*
X287204Y1086417D03*
X283464Y1097637D03*
X294684Y1101377D03*
X283464Y1101376D03*
X294684Y1093897D03*
X287203D03*
X294684Y1097637D03*
X283464Y1105117D03*
X290944Y1101376D03*
Y1105117D03*
X287203Y1097637D03*
X294684Y1123818D03*
Y1116338D03*
Y1131299D03*
X289074Y1144389D03*
X294685Y1198621D03*
Y1213582D03*
Y1206102D03*
Y1236023D03*
X290944Y1224803D03*
X294685Y1232283D03*
X290944Y1228543D03*
X294685Y1239763D03*
X302164Y1090157D03*
X305904D03*
X309644D03*
X302165Y1101377D03*
X309645D03*
X298425Y1105117D03*
Y1101376D03*
X309644Y1097637D03*
X302164D03*
X305905Y1105117D03*
X309644Y1093897D03*
X305905Y1101376D03*
X302164Y1093897D03*
X309645Y1123818D03*
X309644Y1108858D03*
X309645Y1116338D03*
X302165Y1120078D03*
X305905Y1112598D03*
X298425Y1116338D03*
X305905Y1120078D03*
X302165Y1112598D03*
X298425Y1123818D03*
X309645Y1131299D03*
X307775Y1140649D03*
X298425Y1135039D03*
Y1127558D03*
X305905Y1127559D03*
Y1135039D03*
X302165D03*
Y1127559D03*
X298425Y1131299D03*
X300295Y1151869D03*
Y1144389D03*
X307775Y1148129D03*
Y1155610D03*
Y1159350D03*
X298425Y1198621D03*
X305905Y1202362D03*
X302165D03*
X298425Y1213582D03*
X305905Y1209842D03*
Y1217322D03*
X302165Y1209842D03*
X298425Y1206102D03*
X302165Y1217322D03*
Y1232283D03*
X309645D03*
X298425Y1224803D03*
Y1228543D03*
X309645Y1236023D03*
X305905Y1228543D03*
Y1224803D03*
X302165Y1236023D03*
X305905Y1239763D03*
X317125Y1090157D03*
X320866D03*
X324606D03*
X317126Y1105117D03*
X317125Y1101377D03*
X313385D03*
X317125Y1093897D03*
X320866Y1101377D03*
X324606D03*
X317125Y1097637D03*
X318996Y1136909D03*
X317125Y1131299D03*
X318996Y1144389D03*
Y1151869D03*
X322736Y1166830D03*
X318996Y1159350D03*
Y1166830D03*
X326476D03*
X318996Y1189271D03*
Y1181791D03*
Y1174310D03*
X317125Y1198621D03*
X320866D03*
X313385Y1202362D03*
X324606Y1198621D03*
X317125Y1202362D03*
Y1206102D03*
Y1213582D03*
Y1217322D03*
Y1209842D03*
X324606Y1213582D03*
X313385Y1209842D03*
X320866Y1213582D03*
X324606Y1206102D03*
X313385Y1217322D03*
X317125Y1236023D03*
X313385Y1224803D03*
X324606Y1228543D03*
X317125Y1232283D03*
X313385Y1228543D03*
X320866D03*
Y1243503D03*
X313385Y1239763D03*
X320866Y1247243D03*
X324606D03*
X602165Y1228543D03*
Y1243503D03*
Y1250984D03*
X618996Y1125688D03*
Y1133169D03*
X615256Y1151869D03*
X611516D03*
Y1166830D03*
X617126Y1202362D03*
Y1194881D03*
Y1209842D03*
Y1217322D03*
X605905Y1228543D03*
X609646Y1232283D03*
X617126Y1236023D03*
Y1232283D03*
X609646Y1236023D03*
X613386Y1239763D03*
X620866Y1254724D03*
Y1250984D03*
X617126Y1247243D03*
X609646D03*
X613386Y1254724D03*
Y1250984D03*
X605905Y1243503D03*
Y1254724D03*
Y1250984D03*
X626476Y1073326D03*
X635827Y1075196D03*
X628346D03*
X626476Y1077066D03*
X628346Y1078936D03*
X635827D03*
X632086Y1082677D03*
Y1086417D03*
Y1097637D03*
X626476Y1099507D03*
X628346Y1097637D03*
X635827Y1105117D03*
X632086Y1093897D03*
X635827Y1101376D03*
X630216Y1129428D03*
X626476D03*
X630216Y1136909D03*
X626476D03*
X632086Y1209842D03*
X624606Y1221062D03*
X632086Y1232283D03*
Y1236023D03*
X624606Y1232283D03*
Y1236023D03*
X632086Y1243503D03*
X635827Y1239763D03*
Y1254724D03*
Y1250984D03*
X628346Y1254724D03*
X624606Y1247243D03*
X643307Y1075196D03*
X650787D03*
Y1078936D03*
X647047Y1082677D03*
Y1086417D03*
X643307Y1078936D03*
X639567Y1086417D03*
Y1082677D03*
X650787Y1105117D03*
X639567Y1097637D03*
X643307Y1105117D03*
X647047Y1097637D03*
X639567Y1093897D03*
X643307Y1101376D03*
X650787D03*
X637697Y1170570D03*
X645177Y1178051D03*
Y1193011D03*
X639567Y1236023D03*
X647047D03*
X639567Y1232283D03*
X647047D03*
X639567Y1239763D03*
Y1247243D03*
X647047Y1239763D03*
X650787Y1254724D03*
Y1250984D03*
X647047Y1247243D03*
X643307Y1254724D03*
Y1250984D03*
X658268Y1075196D03*
X665748D03*
X669488Y1086417D03*
X665748Y1078936D03*
X669488Y1082677D03*
X654527D03*
Y1086417D03*
X662008Y1082677D03*
Y1086417D03*
X658268Y1078936D03*
X662008Y1097637D03*
X654527Y1093897D03*
X669488D03*
X665748Y1105117D03*
X654527Y1097637D03*
X662008Y1093897D03*
X669488Y1097637D03*
X665748Y1101376D03*
X658268Y1105117D03*
Y1101376D03*
X654527Y1236023D03*
Y1232283D03*
Y1247243D03*
X662008Y1239763D03*
X658268D03*
X669488D03*
X665748Y1250984D03*
Y1254724D03*
X669488Y1247243D03*
X662008D03*
X658268Y1254724D03*
Y1250984D03*
X680709Y1075196D03*
X673228D03*
X684449Y1082677D03*
Y1086417D03*
X673228Y1078936D03*
X680709D03*
X676968Y1082677D03*
Y1086417D03*
X673228Y1105117D03*
X684449Y1093897D03*
X676968D03*
X684449Y1097637D03*
X676968D03*
X680708Y1105117D03*
X673228Y1101376D03*
X680708D03*
X676968Y1239763D03*
X680709Y1254724D03*
Y1250984D03*
X676968Y1247243D03*
X673228Y1254724D03*
Y1250984D03*
X684449Y1247243D03*
Y1239763D03*
X688189Y1075196D03*
Y1078936D03*
Y1105117D03*
X695669Y1101376D03*
X699408Y1097637D03*
X695669Y1105117D03*
X691928Y1093897D03*
Y1097637D03*
X699408Y1093897D03*
X688189Y1101376D03*
Y1254724D03*
Y1250984D03*
X699409Y1239763D03*
X691929D03*
Y1243503D03*
X714370Y1101377D03*
X703149Y1105117D03*
X718110D03*
Y1101376D03*
X710630Y1105117D03*
X703149Y1101376D03*
X710630D03*
X718110Y1228543D03*
Y1224803D03*
X714370Y1243503D03*
X706890D03*
X729331Y1101377D03*
X721850D03*
X725590Y1101376D03*
X733071Y1105117D03*
X725590D03*
X721849Y1097637D03*
Y1093897D03*
X729330Y1097637D03*
X733071Y1101376D03*
X729330Y1093897D03*
X734941Y1121948D03*
Y1129429D03*
X725590Y1228543D03*
X733071D03*
X721850Y1236023D03*
X733071Y1224803D03*
X721850Y1232283D03*
X725590Y1224803D03*
X729331Y1236023D03*
Y1232283D03*
X733071Y1239763D03*
X721850D03*
X744291Y1086417D03*
X740551Y1097637D03*
X736811Y1101377D03*
X736810Y1097637D03*
X748031Y1105117D03*
X744290Y1093897D03*
X740551Y1105117D03*
X744290Y1097637D03*
X736810Y1093897D03*
X740551Y1101376D03*
X748031D03*
X746161Y1144389D03*
X744291Y1236023D03*
X736811Y1232283D03*
X744291D03*
X736811Y1236023D03*
X740551Y1224803D03*
Y1228543D03*
X736811Y1239763D03*
X766731Y1090157D03*
X759251D03*
X762991D03*
X751771Y1101377D03*
X759252D03*
X766732D03*
X751771Y1097637D03*
X762992Y1101376D03*
Y1105117D03*
X755512D03*
X759251Y1097637D03*
Y1093897D03*
X766731Y1097637D03*
X755512Y1101376D03*
X766731Y1093897D03*
X751771D03*
X766731Y1108858D03*
X766732Y1116338D03*
Y1123818D03*
X755512D03*
X759252Y1112598D03*
X751771Y1123818D03*
X762992Y1112598D03*
X755512Y1116338D03*
X751771D03*
X759252Y1120078D03*
X762992D03*
X764862Y1140649D03*
X766732Y1131299D03*
X755512Y1127558D03*
Y1135039D03*
X751771Y1131299D03*
X762992Y1135039D03*
X755512Y1131299D03*
X762992Y1127559D03*
X759252Y1135039D03*
Y1127559D03*
X764862Y1155610D03*
Y1148129D03*
X757382Y1144389D03*
Y1151869D03*
X764862Y1159350D03*
X762992Y1239763D03*
X751772D03*
X774212Y1090157D03*
X781693D03*
X777953D03*
X774212Y1101377D03*
X774213Y1105117D03*
X770472Y1101377D03*
X781693D03*
X777953D03*
X774212Y1097637D03*
Y1093897D03*
Y1131299D03*
X776083Y1151869D03*
Y1144389D03*
X783563Y1166830D03*
X776083D03*
Y1159350D03*
X779823Y1166830D03*
X776083Y1174310D03*
Y1181791D03*
Y1196751D03*
X774212Y1198621D03*
Y1213582D03*
Y1206102D03*
X777953Y1243503D03*
X770472Y1239763D03*
X1059251Y1243503D03*
Y1250984D03*
X1072342Y1151869D03*
X1068602D03*
Y1166830D03*
X1074212Y1194881D03*
Y1202362D03*
Y1217322D03*
Y1209842D03*
X1070472Y1250984D03*
Y1254724D03*
X1066732Y1247243D03*
X1074212D03*
X1070472Y1239763D03*
X1062991Y1250984D03*
Y1254724D03*
Y1243503D03*
X1083562Y1073326D03*
Y1077066D03*
X1089172Y1082677D03*
Y1086417D03*
Y1097637D03*
Y1093897D03*
X1083562Y1099507D03*
Y1136909D03*
X1087302D03*
X1083562Y1129428D03*
X1087302D03*
X1076082Y1133169D03*
Y1125688D03*
X1089172Y1209842D03*
X1081692Y1221062D03*
X1089172Y1232283D03*
Y1236023D03*
X1077952Y1250984D03*
Y1254724D03*
X1081692Y1247243D03*
X1085432Y1254724D03*
X1089172Y1243503D03*
X1092913Y1075196D03*
X1107873D03*
X1100393D03*
X1092913Y1078936D03*
X1104133Y1086417D03*
Y1082677D03*
X1107873Y1078936D03*
X1100393D03*
X1096653Y1082677D03*
Y1086417D03*
X1092913Y1105117D03*
X1104133Y1097637D03*
X1096653D03*
X1100393Y1105117D03*
Y1101376D03*
X1096653Y1093897D03*
X1092913Y1101376D03*
X1107873Y1105117D03*
Y1101376D03*
X1094783Y1170570D03*
X1102263Y1178051D03*
Y1193011D03*
X1104133Y1236023D03*
Y1232283D03*
X1096653Y1236023D03*
Y1232283D03*
X1092913Y1250984D03*
Y1254724D03*
Y1239763D03*
X1100393Y1250984D03*
Y1254724D03*
X1104133Y1247243D03*
X1107873Y1250984D03*
Y1254724D03*
X1104133Y1239763D03*
X1096653Y1247243D03*
Y1239763D03*
X1115354Y1075196D03*
X1122834D03*
X1115354Y1078936D03*
X1119094Y1082677D03*
Y1086417D03*
X1122834Y1078936D03*
X1111613Y1082677D03*
Y1086417D03*
X1119094Y1097637D03*
X1115354Y1101376D03*
X1111613Y1093897D03*
Y1097637D03*
X1122834Y1105117D03*
X1119094Y1093897D03*
X1122834Y1101376D03*
X1115354Y1105117D03*
X1119094Y1232283D03*
X1111613D03*
X1119094Y1236023D03*
X1111613D03*
X1115354Y1250984D03*
Y1254724D03*
X1119094Y1247243D03*
X1122834Y1254724D03*
Y1250984D03*
X1115354Y1239763D03*
X1119094D03*
X1111613Y1247243D03*
X1130314Y1075196D03*
X1137795D03*
X1126574Y1086417D03*
Y1082677D03*
X1130314Y1078936D03*
X1134054Y1082677D03*
Y1086417D03*
X1137795Y1078936D03*
X1126574Y1093897D03*
X1130314Y1105117D03*
X1134054Y1093897D03*
X1130314Y1101376D03*
X1134054Y1097637D03*
X1137794Y1105117D03*
X1126574Y1097637D03*
X1137794Y1101376D03*
X1134054Y1236023D03*
Y1232283D03*
X1126574D03*
Y1236023D03*
Y1247243D03*
Y1239763D03*
X1130314Y1250984D03*
Y1254724D03*
X1134054Y1247243D03*
X1137795Y1250984D03*
Y1254724D03*
X1134054Y1239763D03*
X1145275Y1075196D03*
X1141535Y1082677D03*
Y1086417D03*
X1145275Y1078936D03*
Y1105117D03*
X1141535Y1093897D03*
X1145275Y1101376D03*
X1141535Y1097637D03*
X1149014D03*
X1156494Y1093897D03*
X1152755Y1101376D03*
X1156494Y1097637D03*
X1149014Y1093897D03*
X1152755Y1105117D03*
X1141535Y1236023D03*
Y1232283D03*
Y1239763D03*
Y1247243D03*
X1149015Y1243503D03*
Y1239763D03*
X1156495D03*
X1145275Y1250984D03*
Y1254724D03*
X1171456Y1101377D03*
X1160235Y1105117D03*
Y1101376D03*
X1167716Y1105117D03*
Y1101376D03*
X1163976Y1243503D03*
X1171456D03*
X1178936Y1101377D03*
X1186417D03*
X1178935Y1097637D03*
X1186416Y1093897D03*
X1182676Y1105117D03*
X1175196D03*
X1178935Y1093897D03*
X1182676Y1101376D03*
X1175196D03*
X1186416Y1097637D03*
X1178936Y1239763D03*
X1201377Y1086417D03*
X1197637Y1097637D03*
X1193897Y1101377D03*
X1201376Y1093897D03*
X1193896Y1097637D03*
X1197637Y1105117D03*
X1205117D03*
X1197637Y1101376D03*
X1205117D03*
X1190157D03*
X1193896Y1093897D03*
X1201376Y1097637D03*
X1190157Y1105117D03*
X1192027Y1121948D03*
Y1129429D03*
X1203247Y1144389D03*
X1205117Y1228543D03*
Y1224803D03*
X1190157Y1239763D03*
X1193897D03*
X1216337Y1090157D03*
X1220077D03*
X1216338Y1101377D03*
X1208857D03*
X1220078Y1105117D03*
X1216337Y1093897D03*
X1212598Y1101376D03*
Y1105117D03*
X1208857Y1093897D03*
X1216337Y1097637D03*
X1220078Y1101376D03*
X1208857Y1097637D03*
X1212598Y1123818D03*
X1208857Y1116338D03*
X1212598D03*
X1216338Y1120078D03*
Y1112598D03*
X1208857Y1123818D03*
X1220078Y1112598D03*
Y1120078D03*
X1221948Y1140649D03*
X1212598Y1127558D03*
Y1135039D03*
X1216338Y1127559D03*
Y1135039D03*
X1212598Y1131299D03*
X1208857D03*
X1220078Y1135039D03*
Y1127559D03*
X1221948Y1155610D03*
X1214468Y1151869D03*
Y1144389D03*
X1221948Y1148129D03*
Y1159350D03*
X1212598Y1198621D03*
X1208858D03*
X1216338Y1202362D03*
X1220078D03*
Y1217322D03*
Y1209842D03*
X1212598Y1206102D03*
X1216338Y1217322D03*
X1212598Y1213582D03*
X1208858Y1206102D03*
Y1213582D03*
X1216338Y1209842D03*
X1220078Y1224803D03*
X1212598Y1228543D03*
X1208858Y1232283D03*
X1216338Y1236023D03*
Y1232283D03*
X1212598Y1224803D03*
X1220078Y1228543D03*
X1208858Y1236023D03*
X1220078Y1239763D03*
X1208858D03*
X1223817Y1090157D03*
X1231298D03*
X1235039D03*
X1223818Y1101377D03*
X1231298D03*
X1231299Y1105117D03*
X1227558Y1101377D03*
X1231298Y1093897D03*
X1235039Y1101377D03*
X1223817Y1093897D03*
Y1097637D03*
X1231298D03*
X1223817Y1108858D03*
X1223818Y1116338D03*
Y1123818D03*
X1233169Y1136909D03*
X1223818Y1131299D03*
X1231298D03*
X1233169Y1144389D03*
Y1151869D03*
X1236909Y1166830D03*
X1233169Y1159350D03*
Y1166830D03*
Y1189271D03*
Y1181791D03*
Y1174310D03*
Y1196751D03*
X1231298Y1198621D03*
Y1202362D03*
X1235039Y1198621D03*
X1227558Y1202362D03*
X1231298Y1206102D03*
Y1213582D03*
X1235039D03*
X1231298Y1209842D03*
X1227558D03*
X1231298Y1217322D03*
X1227558D03*
X1231298Y1232283D03*
X1227558Y1228543D03*
Y1224803D03*
X1223818Y1236023D03*
X1231298D03*
X1235039Y1228543D03*
X1223818Y1232283D03*
X1235039Y1243503D03*
X1227558Y1239763D03*
X1235039Y1247243D03*
X1238779Y1090157D03*
Y1101377D03*
X1243149Y1136909D03*
X1240649Y1166830D03*
X1238779Y1198621D03*
Y1206102D03*
Y1213582D03*
Y1228543D03*
Y1247243D03*
X1511968Y1170570D03*
Y1178050D03*
X1529429Y1151869D03*
X1525689D03*
Y1166830D03*
X1516338Y1228543D03*
X1523819Y1232283D03*
X1520078Y1228543D03*
X1523819Y1236023D03*
X1516338Y1243503D03*
Y1250984D03*
X1527559D03*
Y1254724D03*
X1523819Y1247243D03*
X1527559Y1239763D03*
X1520078Y1250984D03*
Y1254724D03*
Y1243503D03*
X1540649Y1073326D03*
Y1077066D03*
X1546259Y1082677D03*
Y1086417D03*
X1540649Y1099507D03*
X1546259Y1097637D03*
Y1093897D03*
X1533169Y1125688D03*
X1544389Y1129428D03*
X1540649D03*
X1544389Y1136909D03*
X1533169Y1133169D03*
X1540649Y1136909D03*
X1531299Y1194881D03*
Y1202362D03*
Y1217322D03*
Y1209842D03*
X1546259D03*
X1538779Y1221062D03*
X1546259Y1232283D03*
X1538779Y1236023D03*
X1531299Y1232283D03*
X1546259Y1236023D03*
X1531299D03*
X1538779Y1232283D03*
X1531299Y1247243D03*
X1535039Y1250984D03*
Y1254724D03*
X1538779Y1247243D03*
X1542519Y1254724D03*
X1546259Y1243503D03*
X1557480Y1075196D03*
X1550000D03*
X1561220Y1086417D03*
Y1082677D03*
X1557480Y1078936D03*
X1553740Y1082677D03*
Y1086417D03*
X1550000Y1078936D03*
X1557480Y1101376D03*
Y1105117D03*
X1561220Y1097637D03*
X1550000Y1101376D03*
Y1105117D03*
X1553740Y1093897D03*
Y1097637D03*
X1551870Y1170570D03*
X1559350Y1178051D03*
Y1193011D03*
X1553740Y1232283D03*
Y1236023D03*
X1561220D03*
Y1232283D03*
X1550000Y1250984D03*
Y1254724D03*
Y1239763D03*
X1557480Y1250984D03*
Y1254724D03*
X1561220Y1247243D03*
Y1239763D03*
X1553740Y1247243D03*
Y1239763D03*
X1572441Y1075196D03*
X1564960D03*
Y1078936D03*
X1572441D03*
X1576181Y1082677D03*
Y1086417D03*
X1568700Y1082677D03*
Y1086417D03*
X1564960Y1105117D03*
X1576181Y1097637D03*
X1568700D03*
X1576181Y1093897D03*
X1568700D03*
X1572441Y1101376D03*
Y1105117D03*
X1564960Y1101376D03*
X1568700Y1236023D03*
Y1232283D03*
X1564960Y1250984D03*
Y1254724D03*
X1572441Y1250984D03*
Y1254724D03*
X1576181Y1247243D03*
X1572441Y1239763D03*
X1576181D03*
X1568700Y1247243D03*
X1579921Y1075196D03*
X1587401D03*
X1594882D03*
X1583661Y1086417D03*
Y1082677D03*
X1579921Y1078936D03*
X1587401D03*
X1591141Y1082677D03*
Y1086417D03*
X1594882Y1078936D03*
X1594881Y1105117D03*
X1591141Y1097637D03*
X1583661Y1093897D03*
X1594881Y1101376D03*
X1583661Y1097637D03*
X1587401Y1105117D03*
X1579921Y1101376D03*
X1591141Y1093897D03*
X1587401Y1101376D03*
X1579921Y1105117D03*
X1583661Y1247243D03*
X1579921Y1254724D03*
Y1250984D03*
X1583661Y1239763D03*
X1587401Y1250984D03*
Y1254724D03*
X1591141Y1247243D03*
X1594882Y1250984D03*
Y1254724D03*
X1591141Y1239763D03*
X1602362Y1075196D03*
X1598622Y1082677D03*
Y1086417D03*
X1602362Y1078936D03*
X1606101Y1093897D03*
X1602362Y1101376D03*
X1598622Y1097637D03*
Y1093897D03*
X1602362Y1105117D03*
X1609842Y1101376D03*
Y1105117D03*
X1606101Y1097637D03*
X1598622Y1239763D03*
Y1247243D03*
X1606102Y1243503D03*
Y1239763D03*
X1602362Y1250984D03*
Y1254724D03*
X1617322Y1105117D03*
Y1101376D03*
X1613581Y1093897D03*
Y1097637D03*
X1624803Y1101376D03*
Y1105117D03*
X1613582Y1239763D03*
X1621063Y1243503D03*
X1639763Y1101376D03*
X1636022Y1093897D03*
X1636023Y1101377D03*
X1643504D03*
X1628543D03*
X1639763Y1105117D03*
X1632283D03*
Y1101376D03*
X1636022Y1097637D03*
X1643503D03*
Y1093897D03*
X1632283Y1228543D03*
X1639763Y1224803D03*
X1636023Y1236023D03*
X1643504Y1232283D03*
X1632283Y1224803D03*
X1643504Y1236023D03*
X1636023Y1232283D03*
X1639763Y1228543D03*
X1628543Y1243503D03*
X1636023Y1239763D03*
X1658464Y1086417D03*
X1658463Y1097637D03*
X1647244Y1101376D03*
X1654724Y1097637D03*
X1650984Y1101377D03*
X1658463Y1093897D03*
X1654724Y1105117D03*
X1650983Y1093897D03*
X1647244Y1105117D03*
X1654724Y1101376D03*
X1650983Y1097637D03*
X1649114Y1121948D03*
Y1129429D03*
X1660334Y1144389D03*
X1654724Y1228543D03*
X1647244D03*
X1658464Y1232283D03*
X1654724Y1224803D03*
X1658464Y1236023D03*
X1650984D03*
X1647244Y1224803D03*
X1650984Y1232283D03*
X1647244Y1239763D03*
X1650984D03*
X1673424Y1090157D03*
X1665944Y1093897D03*
X1662204Y1105117D03*
X1669685D03*
X1673424Y1097637D03*
X1669685Y1101376D03*
X1673425Y1101377D03*
X1665944D03*
X1673424Y1093897D03*
X1665944Y1097637D03*
X1662204Y1101376D03*
X1673425Y1112598D03*
X1665944Y1123818D03*
X1673425Y1120078D03*
X1669685Y1123818D03*
X1665944Y1116338D03*
X1669685D03*
X1665944Y1131299D03*
X1671555Y1136909D03*
X1669685Y1127558D03*
Y1135039D03*
Y1131299D03*
X1673425Y1127559D03*
Y1135039D03*
X1671555Y1151869D03*
Y1144389D03*
X1665945Y1239763D03*
X1677164Y1090157D03*
X1680904D03*
X1688385D03*
X1692126D03*
Y1101377D03*
X1684645D03*
X1677165Y1105117D03*
X1680905Y1101377D03*
X1688385D03*
X1688386Y1105117D03*
X1680904Y1097637D03*
X1677165Y1101376D03*
X1688385Y1097637D03*
X1680904Y1093897D03*
X1688385D03*
X1677165Y1120078D03*
Y1112598D03*
X1680904Y1108858D03*
X1680905Y1116338D03*
Y1123818D03*
X1690256Y1136909D03*
X1679035Y1140649D03*
X1680905Y1131299D03*
X1688385D03*
X1677165Y1135039D03*
Y1127559D03*
X1690256Y1144389D03*
X1679035Y1148129D03*
Y1155610D03*
X1690256Y1151869D03*
Y1159350D03*
X1679035D03*
X1690256Y1166830D03*
Y1174310D03*
Y1189271D03*
Y1181791D03*
X1688385Y1198621D03*
Y1213582D03*
Y1206102D03*
X1692126Y1243503D03*
X1684645Y1239763D03*
X1677165D03*
X1695866Y1090157D03*
Y1101377D03*
X1700236Y1136909D03*
X1693996Y1166830D03*
X1697736D03*
G54D46*
X718503Y-38525D03*
X718500Y-33320D03*
Y-30420D03*
X718488Y-36010D03*
X721756Y-38539D03*
X724781Y-37219D03*
X721741Y-36024D03*
X838503Y-77705D03*
X841756Y-77719D03*
X838500Y-72500D03*
X838488Y-75190D03*
X841741Y-75204D03*
X844781Y-76399D03*
X838500Y-69600D03*
X1005256Y-48539D03*
X1002003D03*
X1005241Y-46024D03*
X1001988D03*
X1008281Y-47219D03*
X1002000Y-40834D03*
X1005256Y-38239D03*
X1002003Y-38225D03*
X1002000Y-43334D03*
X1005241Y-35724D03*
X1002000Y-32720D03*
X1001988Y-35710D03*
X1002000Y-30120D03*
X1008281Y-36919D03*
X1075256Y-77419D03*
X1072003Y-77405D03*
X1071988Y-85290D03*
X1075241D03*
X1072000Y-82600D03*
X1072003Y-87805D03*
X1075256D03*
X1072000Y-80100D03*
Y-72000D03*
Y-69400D03*
X1075241Y-74904D03*
X1071988Y-74890D03*
X1078281Y-86399D03*
Y-76099D03*
X1291756Y-48669D03*
X1288503D03*
X1291741Y-46154D03*
X1288488D03*
X1294781Y-47349D03*
X1288500Y-40964D03*
X1291756Y-38369D03*
X1288503Y-38355D03*
X1288500Y-43464D03*
X1291741Y-35854D03*
X1288500Y-32950D03*
X1288488Y-35840D03*
X1288500Y-30350D03*
X1294781Y-37049D03*
X1328500Y-80100D03*
X1331756Y-77419D03*
X1328503Y-77405D03*
X1331756Y-87805D03*
X1328503D03*
X1328500Y-82600D03*
X1331741Y-85290D03*
X1328488D03*
X1334781Y-86499D03*
X1331741Y-74904D03*
X1328500Y-72000D03*
X1328488Y-74890D03*
X1328500Y-69400D03*
X1334781Y-76099D03*
X1576256Y-48799D03*
X1573003D03*
X1576241Y-46284D03*
X1572988D03*
X1579281Y-47479D03*
X1573000Y-41094D03*
X1576256Y-38499D03*
X1573003Y-38485D03*
X1573000Y-43594D03*
X1576241Y-35984D03*
X1573000Y-33080D03*
X1572988Y-35970D03*
X1573000Y-30480D03*
X1579281Y-37179D03*
X1583000Y-80014D03*
X1586256Y-77419D03*
X1583003Y-77405D03*
X1586256Y-87719D03*
X1583003D03*
X1583000Y-82514D03*
X1586241Y-85204D03*
X1582988D03*
X1589281Y-86399D03*
X1586241Y-74904D03*
X1583000Y-72000D03*
X1582988Y-74890D03*
X1583000Y-69400D03*
X1589281Y-76099D03*
G54D26*
X56348Y1727941D03*
Y1737941D03*
X56248Y1750941D03*
X56348Y1773941D03*
X56248Y1760941D03*
X56348Y1783941D03*
X56248Y1806941D03*
Y1796941D03*
X308448Y1737941D03*
Y1727941D03*
Y1750941D03*
Y1760941D03*
Y1773941D03*
Y1783941D03*
X308348Y1796941D03*
Y1806941D03*
X343286Y1738583D03*
Y1728583D03*
X343112Y1751624D03*
X343212Y1774624D03*
X343112Y1761624D03*
X343212Y1784624D03*
Y1797624D03*
Y1807624D03*
X595386Y1728583D03*
Y1738583D03*
X595312Y1751624D03*
Y1774624D03*
Y1761624D03*
Y1784624D03*
Y1807624D03*
Y1797624D03*
X630083Y1738286D03*
Y1728286D03*
X629861Y1751765D03*
X629711Y1775438D03*
X629861Y1761765D03*
X629711Y1785438D03*
X629475Y1798845D03*
Y1808845D03*
X882183Y1728286D03*
Y1738286D03*
X881911Y1751765D03*
X881761Y1775438D03*
X881911Y1761765D03*
X881761Y1785438D03*
X881525Y1798845D03*
Y1808845D03*
X917279Y1738990D03*
Y1728990D03*
X917163Y1752566D03*
Y1762566D03*
X917073Y1786014D03*
Y1776014D03*
X917166Y1800435D03*
Y1810435D03*
X1169329Y1728990D03*
Y1738990D03*
X1169263Y1752566D03*
Y1762566D03*
X1169123Y1776014D03*
Y1786014D03*
X1169216Y1800435D03*
Y1810435D03*
G54D42*
X318448Y1727941D03*
Y1737941D03*
Y1773941D03*
Y1783941D03*
X605312Y1751624D03*
Y1761624D03*
Y1807624D03*
Y1797624D03*
X891911Y1751765D03*
Y1761765D03*
X891525Y1808845D03*
Y1798845D03*
X1179263Y1752566D03*
Y1762566D03*
X1179216Y1800435D03*
Y1810435D03*
G54D35*
X145078Y1198621D03*
Y1191141D03*
X148818D03*
Y1198621D03*
X145078Y1221062D03*
X148818D03*
Y1213582D03*
X145078D03*
Y1206102D03*
X148818D03*
X145078Y1228543D03*
X148818D03*
Y1247243D03*
X145078D03*
X148818Y1239763D03*
X145078D03*
X156299Y1187401D03*
X163779D03*
X152559D03*
X156299Y1202362D03*
Y1194881D03*
X152559Y1202362D03*
Y1194881D03*
X163779D03*
Y1202362D03*
X156299Y1217322D03*
Y1209842D03*
X152559D03*
X163779D03*
Y1217322D03*
X152559D03*
X160039Y1236023D03*
X163779Y1224803D03*
X156299D03*
Y1228543D03*
X163779D03*
X160039Y1232283D03*
X152559Y1236023D03*
Y1232283D03*
Y1250984D03*
Y1254724D03*
X160039D03*
X156299Y1243503D03*
Y1247243D03*
X163779Y1243503D03*
X160039Y1250984D03*
X163779Y1247243D03*
X174999Y1075196D03*
X182480D03*
X174999Y1078936D03*
X182480D03*
X178740Y1082677D03*
Y1086417D03*
X167519Y1187401D03*
X174999Y1198621D03*
Y1191141D03*
X167519Y1194881D03*
X171259Y1198621D03*
Y1191141D03*
X167519Y1202362D03*
Y1209842D03*
X171259Y1213582D03*
Y1206102D03*
X174999D03*
X167519Y1217322D03*
X174999Y1213582D03*
X167519Y1232283D03*
Y1236023D03*
Y1254724D03*
Y1250984D03*
X178740Y1247243D03*
X182480Y1254724D03*
Y1250984D03*
X171259Y1247243D03*
X174999Y1250984D03*
X171259Y1243503D03*
X174999Y1254724D03*
X178740Y1243503D03*
X189960Y1075196D03*
X197440D03*
X186220Y1082677D03*
Y1086417D03*
X189960Y1078936D03*
X193700Y1086417D03*
Y1082677D03*
X197440Y1078936D03*
Y1254724D03*
Y1250984D03*
X193700Y1247243D03*
Y1243503D03*
X189960Y1254724D03*
Y1250984D03*
X186220Y1247243D03*
Y1243503D03*
X204921Y1075196D03*
X212401D03*
Y1078936D03*
X208661Y1082677D03*
X201181D03*
Y1086417D03*
X208661D03*
X204921Y1078936D03*
X227362Y1075196D03*
X219881D03*
Y1078936D03*
X216141Y1086417D03*
X231102Y1082677D03*
Y1086417D03*
X223622Y1082677D03*
X227362Y1078936D03*
X216141Y1082677D03*
X223622Y1086417D03*
X231102Y1228543D03*
Y1224803D03*
X234841Y1075195D03*
X242321Y1075196D03*
Y1078936D03*
X246061Y1082677D03*
X238581Y1082676D03*
X234841Y1078935D03*
X246061Y1086417D03*
X238581Y1086416D03*
X238582Y1224803D03*
Y1228543D03*
X242322Y1236023D03*
Y1232283D03*
X246062Y1228543D03*
X234842Y1232283D03*
X246062Y1224803D03*
X234842Y1236023D03*
X249802Y1075196D03*
X257282D03*
X249802Y1078936D03*
X261022Y1086417D03*
X253542Y1082676D03*
X257282Y1078936D03*
X253542Y1086416D03*
X261022Y1082677D03*
X261023Y1224803D03*
X253543Y1228543D03*
X249803Y1232283D03*
X257283D03*
Y1236023D03*
X261023Y1228543D03*
X253543Y1224803D03*
X249803Y1236023D03*
X261023Y1243503D03*
Y1247243D03*
X279723Y1075196D03*
X264762D03*
X272243D03*
X275982Y1082677D03*
Y1086417D03*
X268502Y1082676D03*
X272243Y1078936D03*
X268502Y1086416D03*
X279723Y1078936D03*
X264762D03*
X264763Y1232283D03*
X268503Y1224803D03*
X275984D03*
X272244Y1236023D03*
X279724Y1232283D03*
Y1236023D03*
X275984Y1228543D03*
X272244Y1232283D03*
X268503Y1228543D03*
X264763Y1236023D03*
Y1254724D03*
Y1250984D03*
X268503Y1243503D03*
Y1247243D03*
X272244Y1254724D03*
Y1250984D03*
X275984Y1243503D03*
Y1247243D03*
X279724Y1250984D03*
Y1254724D03*
X287203Y1075196D03*
X294684D03*
X290943Y1086417D03*
X287203Y1078936D03*
X290943Y1082677D03*
X283463Y1082676D03*
Y1086416D03*
X294684Y1078936D03*
X287204Y1232283D03*
X283464Y1224803D03*
Y1228543D03*
X287204Y1236023D03*
Y1254724D03*
X283464Y1243503D03*
Y1247243D03*
X287204Y1250984D03*
X302164Y1075196D03*
X309644D03*
X305904Y1082677D03*
X302164Y1078936D03*
X305904Y1086417D03*
X309644Y1078936D03*
X298424Y1086416D03*
Y1082676D03*
X317124Y1075196D03*
X324606Y1082676D03*
X317124Y1078936D03*
X313384Y1082677D03*
Y1086417D03*
X320866Y1082676D03*
X313385Y1120078D03*
X324606Y1123818D03*
Y1108858D03*
X320866D03*
X317125Y1112598D03*
X324606Y1116338D03*
X313385Y1112598D03*
X317125Y1120078D03*
X320866Y1116338D03*
Y1123818D03*
X313385Y1127558D03*
X317125Y1135039D03*
X313385D03*
X324606Y1131299D03*
X317125Y1127558D03*
X320866Y1131299D03*
X632086Y1075196D03*
Y1078936D03*
X635827Y1086417D03*
Y1082677D03*
X639567Y1075196D03*
X647047D03*
X643307Y1086417D03*
Y1082677D03*
X647047Y1078936D03*
X639567D03*
X650787Y1082677D03*
Y1086417D03*
X662008Y1075196D03*
X654527D03*
X669488D03*
X662008Y1078936D03*
X665748Y1082677D03*
X658268D03*
X654527Y1078936D03*
X665748Y1086417D03*
X658268D03*
X669488Y1078936D03*
Y1232283D03*
X662008D03*
X665748Y1224803D03*
X662008Y1236023D03*
X658268Y1224803D03*
X665748Y1228543D03*
X658268D03*
X669488Y1236023D03*
X662008Y1254724D03*
X665748Y1247243D03*
X669488Y1250984D03*
X658268Y1247243D03*
X662008Y1250984D03*
X665748Y1243503D03*
X669488Y1254724D03*
X658268Y1243503D03*
X676968Y1075196D03*
X684449D03*
X676968Y1078936D03*
X680709Y1086417D03*
X684449Y1078936D03*
X673228Y1086417D03*
Y1082677D03*
X680709D03*
X676968Y1236023D03*
X684449Y1232283D03*
X673228Y1228543D03*
X680709Y1224803D03*
X684449Y1236023D03*
X676968Y1232283D03*
X673228Y1224803D03*
X680709Y1228543D03*
X673228Y1243503D03*
X680709Y1247243D03*
X673228D03*
X684449Y1254724D03*
Y1250984D03*
X676968Y1254724D03*
Y1250984D03*
X680709Y1243503D03*
X699408Y1075196D03*
X691928Y1075195D03*
X688189Y1086417D03*
Y1082677D03*
X691928Y1078935D03*
X699408Y1078936D03*
X695668Y1086416D03*
Y1082676D03*
X688189Y1228543D03*
X691929Y1236023D03*
X699409Y1232283D03*
X688189Y1224803D03*
X699409Y1236023D03*
X691929Y1232283D03*
X695669Y1228543D03*
Y1224803D03*
X699409Y1254724D03*
X691929Y1250984D03*
X688189Y1247243D03*
Y1243503D03*
X691929Y1254724D03*
X695669Y1247243D03*
X699409Y1250984D03*
X695669Y1243503D03*
X706889Y1075196D03*
X714369D03*
X706889Y1078936D03*
X718109Y1086417D03*
X714369Y1078936D03*
X703148Y1082677D03*
X710629Y1086416D03*
X703148Y1086417D03*
X718109Y1082677D03*
X710629Y1082676D03*
X706890Y1236023D03*
X714370D03*
X710630Y1228543D03*
X703149D03*
X714370Y1232283D03*
X703149Y1224803D03*
X710630D03*
X706890Y1232283D03*
Y1250984D03*
X703149Y1243503D03*
X714370Y1254724D03*
Y1250984D03*
X710630Y1247243D03*
X706890Y1254724D03*
X710630Y1243503D03*
X703149Y1247243D03*
X721849Y1075196D03*
X729330D03*
X725589Y1086416D03*
X733069Y1086417D03*
X721849Y1078936D03*
X729330D03*
X733069Y1082677D03*
X725589Y1082676D03*
X736810Y1075196D03*
X744290D03*
Y1078936D03*
X748030Y1086417D03*
X740550Y1086416D03*
Y1082676D03*
X736810Y1078936D03*
X748030Y1082677D03*
X748031Y1224803D03*
Y1228543D03*
Y1247243D03*
Y1243503D03*
X751771Y1075196D03*
X766731D03*
X759251D03*
X762991Y1086417D03*
X766731Y1078936D03*
X755511Y1086416D03*
X759251Y1078936D03*
X755511Y1082676D03*
X762991Y1082677D03*
X751771Y1078936D03*
X762992Y1202362D03*
X755512Y1198621D03*
X759252Y1202362D03*
X751772Y1198621D03*
X762992Y1217322D03*
X751772Y1213582D03*
X762992Y1209842D03*
X755512Y1213582D03*
X751772Y1206102D03*
X759252Y1217322D03*
Y1209842D03*
X755512Y1206102D03*
Y1228543D03*
X751772Y1236023D03*
X762992Y1228543D03*
X751772Y1232283D03*
X766732D03*
Y1236023D03*
X759252Y1232283D03*
X762992Y1224803D03*
X759252Y1236023D03*
X755512Y1224803D03*
X766732Y1250984D03*
X755512Y1243503D03*
X762992D03*
Y1247243D03*
X751772Y1250984D03*
Y1254724D03*
X759252D03*
X766732D03*
X759252Y1250984D03*
X755512Y1247243D03*
X774211Y1075196D03*
X781693Y1082676D03*
X774211Y1078936D03*
X770471Y1086417D03*
Y1082677D03*
X777953Y1082676D03*
X774212Y1112598D03*
X770472D03*
X781693Y1123818D03*
X777953D03*
X781693Y1116338D03*
X777953Y1108858D03*
X770472Y1120078D03*
X781693Y1108858D03*
X777953Y1116338D03*
X774212Y1120078D03*
X770472Y1127558D03*
Y1135039D03*
X781693Y1131299D03*
X774212Y1127558D03*
Y1135039D03*
X777953Y1131299D03*
X781693Y1198621D03*
X774212Y1202362D03*
X770472D03*
X777953Y1198621D03*
Y1206102D03*
X770472Y1209842D03*
X781693Y1213582D03*
X774212Y1209842D03*
X777953Y1221062D03*
X781693D03*
Y1206102D03*
X770472Y1217322D03*
X774212D03*
X777953Y1213582D03*
X770472Y1228543D03*
X781693D03*
X770472Y1224803D03*
X777953Y1228543D03*
X774212Y1232283D03*
Y1236023D03*
X777953Y1239763D03*
X781693D03*
X777953Y1247243D03*
X770472Y1243503D03*
X781693Y1247243D03*
X770472D03*
X774212Y1250984D03*
Y1254724D03*
X1059251Y1198621D03*
Y1191141D03*
Y1221062D03*
Y1206102D03*
Y1213582D03*
Y1228543D03*
Y1247243D03*
Y1239763D03*
X1070472Y1187401D03*
X1066732D03*
X1062991Y1198621D03*
X1066732Y1194881D03*
X1062991Y1191141D03*
X1070472Y1194881D03*
Y1202362D03*
X1066732D03*
X1070472Y1217322D03*
X1066732D03*
X1062991Y1221062D03*
Y1206102D03*
X1070472Y1209842D03*
X1062991Y1213582D03*
X1066732Y1209842D03*
X1070472Y1228543D03*
X1066732Y1236023D03*
Y1232283D03*
X1074212Y1236023D03*
Y1232283D03*
X1070472Y1224803D03*
X1062991Y1228543D03*
X1074212Y1250984D03*
X1066732Y1254724D03*
X1070472Y1247243D03*
X1074212Y1254724D03*
X1062991Y1247243D03*
X1070472Y1243503D03*
X1062991Y1239763D03*
X1066732Y1250984D03*
X1089172Y1075196D03*
Y1078936D03*
X1077952Y1187401D03*
X1081692D03*
X1077952Y1194881D03*
Y1202362D03*
X1089172Y1191141D03*
Y1198621D03*
X1081692Y1202362D03*
X1085432Y1198621D03*
X1081692Y1194881D03*
X1085432Y1191141D03*
X1089172Y1206102D03*
X1077952Y1209842D03*
X1081692D03*
Y1217322D03*
X1089172Y1213582D03*
X1077952Y1217322D03*
X1085432Y1206102D03*
Y1213582D03*
X1081692Y1232283D03*
Y1236023D03*
X1077952Y1224803D03*
Y1228543D03*
Y1243503D03*
X1081692Y1250984D03*
X1077952Y1247243D03*
X1081692Y1254724D03*
X1085432Y1243503D03*
X1089172Y1254724D03*
Y1250984D03*
X1085432Y1247243D03*
X1096653Y1075196D03*
X1104133D03*
X1100393Y1082677D03*
X1104133Y1078936D03*
X1107873Y1082677D03*
Y1086417D03*
X1092913Y1082677D03*
X1100393Y1086417D03*
X1092913D03*
X1096653Y1078936D03*
Y1254724D03*
X1104133D03*
X1092913Y1247243D03*
X1096653Y1250984D03*
X1092913Y1243503D03*
X1107873D03*
X1100393D03*
X1107873Y1247243D03*
X1100393D03*
X1104133Y1250984D03*
X1111613Y1075196D03*
X1119094D03*
X1122834Y1086417D03*
X1119094Y1078936D03*
X1115354Y1082677D03*
X1111613Y1078936D03*
X1115354Y1086417D03*
X1122834Y1082677D03*
X1111613Y1254724D03*
Y1250984D03*
X1126574Y1075196D03*
X1134054D03*
Y1078936D03*
X1126574D03*
X1130314Y1086417D03*
Y1082677D03*
X1137795Y1086417D03*
Y1082677D03*
X1141535Y1075196D03*
X1156494D03*
X1149014Y1075195D03*
X1145275Y1086417D03*
Y1082677D03*
X1141535Y1078936D03*
X1149014Y1078935D03*
X1156494Y1078936D03*
X1152754Y1086416D03*
Y1082676D03*
X1149015Y1236023D03*
Y1232283D03*
X1152755Y1228543D03*
X1145275Y1224803D03*
X1156495Y1232283D03*
Y1236023D03*
X1145275Y1228543D03*
X1152755Y1224803D03*
X1163975Y1075196D03*
X1171455D03*
X1160234Y1086417D03*
X1167715Y1086416D03*
X1163975Y1078936D03*
X1160234Y1082677D03*
X1171455Y1078936D03*
X1167715Y1082676D03*
X1160235Y1224803D03*
X1163976Y1232283D03*
X1167716Y1224803D03*
X1160235Y1228543D03*
X1171456Y1232283D03*
X1163976Y1236023D03*
X1171456D03*
X1167716Y1228543D03*
X1178935Y1075196D03*
X1186416D03*
X1175195Y1086417D03*
X1182675Y1086416D03*
X1175195Y1082677D03*
X1178935Y1078936D03*
X1182675Y1082676D03*
X1186416Y1078936D03*
X1182676Y1228543D03*
X1186417Y1236023D03*
X1178936D03*
X1186417Y1232283D03*
X1175196Y1228543D03*
X1178936Y1232283D03*
X1182676Y1224803D03*
X1175196D03*
X1178936Y1254724D03*
X1175196Y1243503D03*
X1182676Y1247243D03*
X1178936Y1250984D03*
X1186417D03*
X1182676Y1243503D03*
X1186417Y1254724D03*
X1175196Y1247243D03*
X1193896Y1075196D03*
X1201376D03*
X1190155Y1086417D03*
X1205116Y1082677D03*
X1190155D03*
X1197636Y1082676D03*
X1193896Y1078936D03*
X1205116Y1086417D03*
X1201376Y1078936D03*
X1197636Y1086416D03*
X1197637Y1224803D03*
X1193897Y1236023D03*
X1190157Y1228543D03*
X1201377Y1236023D03*
X1190157Y1224803D03*
X1193897Y1232283D03*
X1197637Y1228543D03*
X1201377Y1232283D03*
X1190157Y1243503D03*
X1201377Y1250984D03*
X1197637Y1247243D03*
X1193897Y1250984D03*
X1201377Y1254724D03*
X1197637Y1243503D03*
X1193897Y1254724D03*
X1190157Y1247243D03*
X1216337Y1075196D03*
X1208857D03*
X1212597Y1082676D03*
Y1086416D03*
X1220077Y1086417D03*
X1208857Y1078936D03*
X1216337D03*
X1220077Y1082677D03*
X1231297Y1075196D03*
X1223817D03*
X1231297Y1078936D03*
X1235039Y1082676D03*
X1227557Y1086417D03*
X1223817Y1078936D03*
X1227557Y1082677D03*
X1227558Y1112598D03*
X1235039Y1123818D03*
X1231298Y1120078D03*
Y1112598D03*
X1235039Y1108858D03*
Y1116338D03*
X1227558Y1120078D03*
X1231298Y1135039D03*
X1227558Y1127558D03*
X1235039Y1131299D03*
X1231298Y1127558D03*
X1227558Y1135039D03*
X1238779Y1082676D03*
Y1108858D03*
Y1116338D03*
Y1123818D03*
Y1131299D03*
X1546259Y1075196D03*
Y1078936D03*
X1553740Y1075196D03*
X1561220D03*
X1557480Y1082677D03*
X1553740Y1078936D03*
X1561220D03*
X1550000Y1086417D03*
Y1082677D03*
X1557480Y1086417D03*
X1576181Y1075196D03*
X1568700D03*
Y1078936D03*
X1572441Y1086417D03*
X1564960Y1082677D03*
Y1086417D03*
X1572441Y1082677D03*
X1576181Y1078936D03*
X1572441Y1228543D03*
X1576181Y1236023D03*
X1572441Y1224803D03*
X1576181Y1232283D03*
X1572441Y1247243D03*
X1576181Y1254724D03*
Y1250984D03*
X1572441Y1243503D03*
X1583661Y1075196D03*
X1591141D03*
X1594882Y1082677D03*
X1579921D03*
X1583661Y1078936D03*
X1594882Y1086417D03*
X1587401Y1082677D03*
X1579921Y1086417D03*
X1587401D03*
X1591141Y1078936D03*
X1594882Y1224803D03*
X1591141Y1232283D03*
X1583661Y1236023D03*
X1579921Y1228543D03*
X1583661Y1232283D03*
X1594882Y1228543D03*
X1579921Y1224803D03*
X1587401Y1228543D03*
Y1224803D03*
X1591141Y1236023D03*
X1583661Y1254724D03*
X1579921Y1247243D03*
X1591141Y1254724D03*
X1587401Y1247243D03*
Y1243503D03*
X1594882D03*
X1579921D03*
X1594882Y1247243D03*
X1583661Y1250984D03*
X1591141D03*
X1606101Y1075195D03*
X1598622Y1075196D03*
X1609841Y1086416D03*
X1606101Y1078935D03*
X1609841Y1082676D03*
X1602362Y1082677D03*
Y1086417D03*
X1598622Y1078936D03*
Y1236023D03*
X1606102D03*
X1609842Y1228543D03*
X1606102Y1232283D03*
X1602362Y1224803D03*
X1609842D03*
X1602362Y1228543D03*
X1598622Y1232283D03*
Y1254724D03*
Y1250984D03*
X1609842Y1247243D03*
X1606102Y1250984D03*
Y1254724D03*
X1609842Y1243503D03*
X1602362Y1247243D03*
Y1243503D03*
X1613581Y1075196D03*
X1621062D03*
X1613581Y1078936D03*
X1624802Y1082676D03*
X1617321Y1082677D03*
X1621062Y1078936D03*
X1617321Y1086417D03*
X1624802Y1086416D03*
X1617322Y1228543D03*
X1624803Y1224803D03*
X1617322D03*
X1621063Y1236023D03*
X1613582D03*
X1621063Y1232283D03*
X1624803Y1228543D03*
X1613582Y1232283D03*
X1624803Y1247243D03*
Y1243503D03*
X1621063Y1254724D03*
X1613582Y1250984D03*
X1617322Y1243503D03*
Y1247243D03*
X1613582Y1254724D03*
X1621063Y1250984D03*
X1636022Y1075196D03*
X1643503D03*
X1628542D03*
X1632282Y1082677D03*
X1643503Y1078936D03*
X1628542D03*
X1639762Y1086416D03*
X1632282Y1086417D03*
X1636022Y1078936D03*
X1639762Y1082676D03*
X1628543Y1236023D03*
Y1232283D03*
Y1250984D03*
Y1254724D03*
X1650983Y1075196D03*
X1658463D03*
X1654723Y1086416D03*
Y1082676D03*
X1650983Y1078936D03*
X1647242Y1082677D03*
Y1086417D03*
X1658463Y1078936D03*
X1673424Y1075196D03*
X1665944D03*
X1662203Y1086417D03*
Y1082677D03*
X1669684Y1086416D03*
X1665944Y1078936D03*
X1673424D03*
X1669684Y1082676D03*
X1673425Y1202362D03*
X1665945Y1198621D03*
X1669685D03*
X1665945Y1206102D03*
X1669685Y1213582D03*
X1673425Y1209842D03*
X1669685Y1206102D03*
X1665945Y1213582D03*
X1673425Y1217322D03*
Y1236023D03*
X1662204Y1228543D03*
X1669685D03*
X1673425Y1232283D03*
X1665945D03*
Y1236023D03*
X1662204Y1224803D03*
X1669685D03*
X1673425Y1250984D03*
X1662204Y1247243D03*
X1665945Y1254724D03*
X1673425D03*
X1662204Y1243503D03*
X1665945Y1250984D03*
X1669685Y1247243D03*
Y1243503D03*
X1680904Y1075196D03*
X1688384D03*
X1692126Y1082676D03*
X1684644Y1082677D03*
Y1086417D03*
X1680904Y1078936D03*
X1688384D03*
X1677164Y1086417D03*
Y1082677D03*
X1692126Y1116338D03*
Y1108858D03*
X1684645Y1120078D03*
X1688385D03*
X1684645Y1112598D03*
X1692126Y1123818D03*
X1688385Y1112598D03*
X1684645Y1135039D03*
Y1127558D03*
X1692126Y1131299D03*
X1688385Y1127558D03*
Y1135039D03*
X1684645Y1202362D03*
X1692126Y1198621D03*
X1688385Y1202362D03*
X1677165D03*
X1692126Y1213582D03*
X1684645Y1217322D03*
Y1209842D03*
X1692126Y1206102D03*
X1677165Y1209842D03*
X1692126Y1221062D03*
X1688385Y1209842D03*
X1677165Y1217322D03*
X1688385D03*
X1677165Y1228543D03*
X1680905Y1236023D03*
Y1232283D03*
X1692126Y1228543D03*
X1684645Y1224803D03*
Y1228543D03*
X1677165Y1224803D03*
X1688385Y1232283D03*
Y1236023D03*
X1684645Y1243503D03*
X1677165D03*
X1692126Y1247243D03*
X1684645D03*
X1677165D03*
X1688385Y1254724D03*
Y1250984D03*
X1692126Y1239763D03*
X1680905Y1254724D03*
Y1250984D03*
X1695866Y1082676D03*
Y1123818D03*
Y1116338D03*
Y1108858D03*
Y1131299D03*
Y1198621D03*
Y1221062D03*
Y1213582D03*
Y1206102D03*
Y1228543D03*
Y1239763D03*
Y1247243D03*
G54D58*
X1250055Y1710189D03*
Y1720189D03*
Y1739208D03*
Y1749208D03*
X1250048Y1768377D03*
Y1778377D03*
X1248555Y1797909D03*
Y1807909D03*
X1734069Y1710189D03*
Y1720189D03*
Y1739208D03*
Y1749208D03*
X1734062Y1768377D03*
Y1778377D03*
X1734069Y1797909D03*
Y1807909D03*
G54D20*
X35688Y111255D03*
Y114655D03*
X28388Y121742D03*
X35688Y125428D03*
X28388Y132515D03*
Y118342D03*
X35688Y128828D03*
X28388Y135915D03*
X79512Y1372385D03*
X76112D03*
Y1384297D03*
X79512D03*
X88352Y1348187D03*
X91752D03*
Y1360099D03*
X88352D03*
X100592Y1384297D03*
Y1372385D03*
X91752Y1396583D03*
X88352D03*
X91752Y1408495D03*
X88352D03*
X116232Y1348187D03*
X112832D03*
Y1360099D03*
X116232D03*
X103992Y1372385D03*
Y1384297D03*
X116232Y1396583D03*
X112832D03*
Y1408495D03*
X116232D03*
X130750Y132515D03*
Y121742D03*
Y118342D03*
Y135915D03*
X125072Y1384297D03*
X128472D03*
X125072Y1372385D03*
X128472D03*
X138050Y111255D03*
Y114655D03*
Y128828D03*
Y125428D03*
X140712Y1348187D03*
X137312D03*
Y1360099D03*
X140712D03*
X149552Y1384297D03*
Y1372385D03*
X140712Y1396583D03*
X137312D03*
X140712Y1408495D03*
X137312D03*
X165192Y1348187D03*
X161792D03*
X165192Y1360099D03*
X161792D03*
X152952Y1384297D03*
Y1372385D03*
X165192Y1396583D03*
X161792D03*
X165192Y1408495D03*
X161792D03*
X177432Y1384297D03*
X174032D03*
Y1372385D03*
X177432D03*
X189672Y1348187D03*
X186272D03*
X189672Y1360099D03*
X186272D03*
X198512Y1384297D03*
Y1372385D03*
X186272Y1396583D03*
X189672D03*
Y1408495D03*
X186272D03*
X212980Y390995D03*
Y405168D03*
Y394395D03*
X205680Y401482D03*
Y398082D03*
X212980Y408568D03*
Y419341D03*
Y422741D03*
X205680Y415655D03*
Y412255D03*
Y426428D03*
Y440602D03*
Y429828D03*
X212980Y433515D03*
Y436915D03*
X205680Y444002D03*
X212980Y469381D03*
Y472781D03*
X205680Y490641D03*
Y479868D03*
X212980Y483554D03*
X205680Y476468D03*
X212980Y486954D03*
X205680Y494041D03*
Y524002D03*
X212980Y516915D03*
Y513515D03*
X205680Y520602D03*
Y534775D03*
X212980Y527688D03*
X205680Y538175D03*
X212980Y531088D03*
X201912Y1384297D03*
Y1372385D03*
X240412Y114655D03*
Y111255D03*
X233112Y132515D03*
Y121742D03*
X240412Y125428D03*
X233112Y118342D03*
X240412Y128828D03*
X233112Y135915D03*
X245023Y1372385D03*
X241623D03*
Y1384297D03*
X245023D03*
X264005Y467337D03*
Y470737D03*
X256705Y474424D03*
X264005Y484910D03*
X256705Y488597D03*
X264005Y481510D03*
X256705Y477824D03*
Y491997D03*
X264005Y514871D03*
X256705Y518558D03*
X264005Y511471D03*
X256705Y521958D03*
Y532731D03*
Y536131D03*
X264005Y525644D03*
Y529044D03*
Y561510D03*
X256705Y571997D03*
Y568597D03*
X264005Y564910D03*
X256705Y586171D03*
X264005Y575684D03*
Y579084D03*
X256705Y582771D03*
X264005Y589857D03*
X256705Y600344D03*
X264005Y593257D03*
Y604030D03*
X256705Y596944D03*
Y611117D03*
Y614517D03*
X264005Y607430D03*
X253863Y1348187D03*
X257263D03*
X253863Y1360099D03*
X257263D03*
X253863Y1396583D03*
X257263D03*
Y1408495D03*
X253863D03*
X278343Y1348187D03*
Y1360099D03*
X269503Y1372385D03*
X266103D03*
Y1384297D03*
X269503D03*
X278343Y1396583D03*
Y1408495D03*
X281743Y1348187D03*
Y1360099D03*
X293983Y1372385D03*
X290583Y1384297D03*
X293983D03*
X290583Y1372385D03*
X281743Y1396583D03*
Y1408495D03*
X302823Y1348187D03*
X306223D03*
Y1360099D03*
X302823D03*
Y1396583D03*
X306223D03*
X302823Y1408495D03*
X306223D03*
X327303Y1348187D03*
Y1360099D03*
X315063Y1372385D03*
X318463Y1384297D03*
X315063D03*
X318463Y1372385D03*
X327303Y1396583D03*
Y1408495D03*
X342774Y111255D03*
Y114655D03*
X335474Y118342D03*
Y132515D03*
X342774Y125428D03*
X335474Y121742D03*
X342774Y128828D03*
X335474Y135915D03*
X330703Y1348187D03*
Y1360099D03*
X339543Y1372385D03*
X342943D03*
Y1384297D03*
X339543D03*
X330703Y1396583D03*
Y1408495D03*
X351783Y1348187D03*
X355183D03*
Y1360099D03*
X351783D03*
Y1396583D03*
X355183D03*
X351783Y1408495D03*
X355183D03*
X364023Y1372385D03*
X367423Y1384297D03*
X364023D03*
X367423Y1372385D03*
X440402D03*
Y1384297D03*
X452642Y1348187D03*
X456042D03*
Y1360099D03*
X452642D03*
X443802Y1372385D03*
Y1384297D03*
X452642Y1396583D03*
X456042D03*
X452642Y1408495D03*
X456042D03*
X464882Y1372385D03*
X468282D03*
X464882Y1384297D03*
X468282D03*
X485475Y118342D03*
Y121742D03*
Y132515D03*
Y135915D03*
X480522Y1348187D03*
X477122D03*
X480522Y1360099D03*
X477122D03*
X489362Y1372385D03*
Y1384297D03*
X480522Y1396583D03*
X477122D03*
Y1408495D03*
X480522D03*
X492775Y114655D03*
Y111255D03*
Y128828D03*
Y125428D03*
X501602Y1348187D03*
X505002D03*
X501602Y1360099D03*
X505002D03*
X492762Y1372385D03*
Y1384297D03*
X505002Y1396583D03*
X501602D03*
X505002Y1408495D03*
X501602D03*
X517242Y1372385D03*
X513842D03*
X517242Y1384297D03*
X513842D03*
X529482Y1348187D03*
X526082D03*
X529482Y1360099D03*
X526082D03*
X538322Y1384297D03*
Y1372385D03*
X526082Y1396583D03*
X529482D03*
Y1408495D03*
X526082D03*
X553962Y1348187D03*
X550562D03*
X553962Y1360099D03*
X550562D03*
X541722Y1372385D03*
Y1384297D03*
X553962Y1396583D03*
X550562D03*
X553962Y1408495D03*
X550562D03*
X566202Y1372385D03*
Y1384297D03*
X562802D03*
Y1372385D03*
X587837Y118342D03*
Y121742D03*
Y132515D03*
Y135915D03*
X595137Y111255D03*
Y114655D03*
Y125428D03*
Y128828D03*
X650768Y1348187D03*
Y1360099D03*
X638528Y1372385D03*
X641928D03*
X638528Y1384297D03*
X641928D03*
X650768Y1396583D03*
Y1408495D03*
X670066Y390995D03*
Y405168D03*
X662766Y398082D03*
X670066Y408568D03*
Y394395D03*
X662766Y401482D03*
X670066Y422741D03*
Y419341D03*
X662766Y415655D03*
Y426428D03*
Y412255D03*
Y440602D03*
X670066Y433515D03*
X662766Y429828D03*
X670066Y436915D03*
X662766Y444002D03*
X670066Y469381D03*
Y472781D03*
X662766Y476468D03*
Y490641D03*
X670066Y483554D03*
Y486954D03*
X662766Y479868D03*
Y494041D03*
X670066Y516915D03*
X662766Y520602D03*
Y524002D03*
X670066Y513515D03*
Y527688D03*
X662766Y534775D03*
X670066Y531088D03*
X662766Y538175D03*
X654168Y1348187D03*
Y1360099D03*
X663008Y1372385D03*
X666408D03*
X663008Y1384297D03*
X666408D03*
X654168Y1396583D03*
Y1408495D03*
X678648Y1348187D03*
X675248D03*
X678648Y1360099D03*
X675248D03*
Y1396583D03*
X678648D03*
Y1408495D03*
X675248D03*
X697499Y114655D03*
Y111255D03*
X690199Y132515D03*
X697499Y125428D03*
Y128828D03*
X690199Y121742D03*
Y118342D03*
Y135915D03*
X699728Y1348187D03*
Y1360099D03*
X690888Y1372385D03*
X687488D03*
Y1384297D03*
X690888D03*
X699728Y1396583D03*
Y1408495D03*
X713791Y474424D03*
Y488597D03*
Y477824D03*
Y491997D03*
Y518558D03*
Y521958D03*
Y536131D03*
Y532731D03*
Y571997D03*
Y568597D03*
Y582771D03*
Y586171D03*
Y596944D03*
Y600344D03*
Y611117D03*
Y614517D03*
X703128Y1348187D03*
Y1360099D03*
X715368Y1372385D03*
X711968D03*
X715368Y1384297D03*
X711968D03*
X703128Y1396583D03*
Y1408495D03*
X721091Y470737D03*
Y467337D03*
Y484910D03*
Y481510D03*
Y514871D03*
Y511471D03*
Y525644D03*
Y529044D03*
Y561510D03*
Y564910D03*
Y579084D03*
Y575684D03*
Y593257D03*
Y604030D03*
Y589857D03*
Y607430D03*
X727608Y1348187D03*
X724208D03*
Y1360099D03*
X727608D03*
X724208Y1396489D03*
X727608D03*
X724208Y1408401D03*
X727608D03*
X748688Y1348187D03*
Y1360099D03*
X739848Y1372385D03*
X736448D03*
X739848Y1384297D03*
X736448D03*
X752088Y1348187D03*
Y1360099D03*
X764328Y1372385D03*
X760928D03*
X764328Y1384297D03*
X760928D03*
X776568Y1348187D03*
X773168D03*
Y1360099D03*
X776568D03*
X799861Y114655D03*
Y111255D03*
X792561Y132515D03*
Y118342D03*
X799861Y128828D03*
X792561Y121742D03*
X799861Y125428D03*
X792561Y135915D03*
X919163Y848442D03*
Y851592D03*
X942561Y118342D03*
Y132515D03*
Y121742D03*
Y135915D03*
X945982Y886737D03*
X949861Y111255D03*
Y114655D03*
Y125428D03*
Y128828D03*
X949382Y886737D03*
X1011187Y-33526D03*
Y-30126D03*
Y-43526D03*
Y-40126D03*
X1052223Y111255D03*
Y114655D03*
X1044923Y118342D03*
X1052223Y125428D03*
Y128828D03*
X1044923Y132515D03*
Y121742D03*
Y135915D03*
X1058113Y1372385D03*
X1054713D03*
Y1384297D03*
X1058113D03*
X1066953Y1348187D03*
X1070353D03*
X1066953Y1360099D03*
X1070353D03*
Y1396583D03*
X1066953D03*
Y1408495D03*
X1070353D03*
X1081187Y-79306D03*
Y-82706D03*
Y-72706D03*
Y-69306D03*
X1091433Y1348187D03*
Y1360099D03*
X1079193Y1372385D03*
X1082593D03*
Y1384297D03*
X1079193D03*
X1091433Y1396583D03*
Y1408495D03*
X1094833Y1348187D03*
Y1360099D03*
X1107073Y1372385D03*
X1103673D03*
X1107073Y1384297D03*
X1103673D03*
X1094833Y1396583D03*
Y1408495D03*
X1119853Y398082D03*
Y401482D03*
Y412255D03*
Y426428D03*
Y415655D03*
Y440602D03*
Y429828D03*
Y444002D03*
Y490641D03*
Y476468D03*
Y479868D03*
Y494041D03*
Y524002D03*
Y520602D03*
Y538175D03*
Y534775D03*
X1115913Y1348187D03*
X1119313D03*
X1115913Y1360099D03*
X1119313D03*
X1115913Y1396583D03*
X1119313D03*
X1115913Y1408495D03*
X1119313D03*
X1127153Y390995D03*
Y408568D03*
Y405168D03*
Y394395D03*
Y422741D03*
Y419341D03*
Y436915D03*
Y433515D03*
Y472781D03*
Y469381D03*
Y486954D03*
Y483554D03*
Y516915D03*
Y513515D03*
Y527688D03*
Y531088D03*
X1140393Y1348187D03*
Y1360099D03*
X1128153Y1384297D03*
X1131553D03*
X1128153Y1372385D03*
X1131553D03*
X1140393Y1396583D03*
Y1408495D03*
X1154585Y114655D03*
Y111255D03*
Y128828D03*
X1147285Y118342D03*
Y121742D03*
Y132515D03*
X1154585Y125428D03*
X1147285Y135915D03*
X1143793Y1348187D03*
Y1360099D03*
X1156033Y1384297D03*
X1152633D03*
X1156033Y1372385D03*
X1152633D03*
X1143793Y1396583D03*
Y1408495D03*
X1170878Y474424D03*
Y477824D03*
Y488597D03*
Y491997D03*
Y518558D03*
Y521958D03*
Y532731D03*
Y536131D03*
Y571997D03*
Y568597D03*
Y586171D03*
Y582771D03*
Y596944D03*
Y600344D03*
Y614517D03*
Y611117D03*
X1168273Y1348187D03*
X1164873D03*
Y1360099D03*
X1168273D03*
X1164873Y1396583D03*
X1168273D03*
Y1408495D03*
X1164873D03*
X1178178Y467337D03*
Y470737D03*
Y484910D03*
Y481510D03*
Y511471D03*
Y514871D03*
Y529044D03*
Y525644D03*
Y564910D03*
Y561510D03*
Y579084D03*
Y575684D03*
Y604030D03*
Y593257D03*
Y589857D03*
Y607430D03*
X1177113Y1384297D03*
X1180513D03*
X1177113Y1372385D03*
X1180513D03*
X1225405Y-79278D03*
Y-82678D03*
Y-72678D03*
Y-69278D03*
X1230761Y-33628D03*
Y-30228D03*
Y-43628D03*
Y-40228D03*
X1230326Y1372385D03*
X1233726D03*
X1230326Y1384297D03*
X1233726D03*
X1249647Y118342D03*
Y132515D03*
Y121742D03*
Y135915D03*
X1245966Y1348187D03*
X1242566D03*
Y1360099D03*
X1245966D03*
X1254806Y1372385D03*
Y1384297D03*
X1245966Y1396583D03*
X1242566D03*
Y1408495D03*
X1245966D03*
X1256947Y114655D03*
Y111255D03*
Y128828D03*
Y125428D03*
X1267046Y1348187D03*
X1270446D03*
Y1360099D03*
X1267046D03*
X1258206Y1372385D03*
Y1384297D03*
X1267046Y1396583D03*
X1270446D03*
Y1408495D03*
X1267046D03*
X1279286Y1372385D03*
X1282686D03*
Y1384297D03*
X1279286D03*
X1297687Y-33656D03*
Y-40256D03*
Y-30256D03*
Y-43656D03*
X1291526Y1348187D03*
X1294926D03*
X1291526Y1360099D03*
X1294926D03*
Y1396583D03*
X1291526D03*
Y1408495D03*
X1294926D03*
X1319406Y1348187D03*
X1316006D03*
X1319406Y1360099D03*
X1316006D03*
X1307166Y1372385D03*
X1303766D03*
Y1384297D03*
X1307166D03*
X1319406Y1396583D03*
X1316006D03*
Y1408495D03*
X1319406D03*
X1331646Y1384297D03*
Y1372385D03*
X1328246D03*
Y1384297D03*
X1337687Y-79306D03*
Y-82706D03*
Y-69306D03*
Y-72706D03*
X1343886Y1348187D03*
X1340486D03*
X1343886Y1360099D03*
X1340486D03*
Y1396583D03*
X1343886D03*
Y1408495D03*
X1340486D03*
X1352726Y1384297D03*
X1356126Y1372385D03*
Y1384297D03*
X1352726Y1372385D03*
X1399648Y132515D03*
Y121742D03*
Y118342D03*
Y135915D03*
X1406948Y111255D03*
Y114655D03*
Y128828D03*
Y125428D03*
X1464770Y1372385D03*
X1461370D03*
X1464770Y1384297D03*
X1461370D03*
X1481905Y-79278D03*
Y-82678D03*
Y-69278D03*
Y-72678D03*
X1477010Y1348187D03*
X1473610D03*
Y1360099D03*
X1477010D03*
Y1396583D03*
X1473610D03*
Y1408495D03*
X1477010D03*
X1498090Y1348187D03*
Y1360099D03*
X1489250Y1372385D03*
X1485850D03*
Y1384297D03*
X1489250D03*
X1498090Y1396583D03*
Y1408495D03*
X1509310Y114655D03*
Y111255D03*
X1502010Y121742D03*
X1509310Y125428D03*
Y128828D03*
X1502010Y118342D03*
Y132515D03*
Y135915D03*
X1501490Y1348187D03*
Y1360099D03*
X1510330Y1372385D03*
X1513730D03*
Y1384297D03*
X1510330D03*
X1501490Y1396583D03*
Y1408495D03*
X1517261Y-33758D03*
Y-40358D03*
Y-30358D03*
Y-43758D03*
X1525970Y1348187D03*
X1522570D03*
Y1360099D03*
X1525970D03*
X1522570Y1396583D03*
X1525970D03*
Y1408495D03*
X1522570D03*
X1547050Y1348187D03*
Y1360099D03*
X1538210Y1372385D03*
X1534810D03*
Y1384297D03*
X1538210D03*
X1547050Y1396583D03*
Y1408495D03*
X1550450Y1348187D03*
Y1360099D03*
X1562690Y1372385D03*
X1559290D03*
X1562690Y1384297D03*
X1559290D03*
X1550450Y1396583D03*
Y1408495D03*
X1576940Y398082D03*
Y401482D03*
Y415655D03*
Y412255D03*
Y426428D03*
Y440602D03*
Y429828D03*
Y444002D03*
Y476468D03*
Y490641D03*
Y479868D03*
Y494041D03*
Y520602D03*
Y524002D03*
Y534775D03*
Y538175D03*
X1574930Y1348187D03*
X1571530D03*
X1574930Y1360099D03*
X1571530D03*
Y1396583D03*
X1574930D03*
X1571530Y1408495D03*
X1574930D03*
X1592187Y-79306D03*
Y-82706D03*
X1582187Y-43786D03*
Y-40386D03*
X1584240Y390995D03*
Y408568D03*
Y405168D03*
Y394395D03*
Y419341D03*
Y422741D03*
Y433515D03*
Y436915D03*
Y472781D03*
Y469381D03*
Y483554D03*
Y486954D03*
Y516915D03*
Y513515D03*
Y531088D03*
Y527688D03*
X1587170Y1372385D03*
X1583770D03*
Y1384297D03*
X1587170D03*
X1611672Y111255D03*
Y114655D03*
X1604372Y118342D03*
X1611672Y125428D03*
X1604372Y121742D03*
X1611672Y128828D03*
X1604372Y132515D03*
Y135915D03*
X1611398Y1384297D03*
Y1372385D03*
X1627965Y474424D03*
Y488597D03*
Y477824D03*
Y491997D03*
Y521958D03*
Y518558D03*
Y536131D03*
Y532731D03*
Y571997D03*
Y568597D03*
Y582771D03*
Y586171D03*
Y596944D03*
Y600344D03*
Y614517D03*
Y611117D03*
X1623638Y1348187D03*
X1627038D03*
X1623638Y1360099D03*
X1627038D03*
X1614798Y1372385D03*
Y1384297D03*
X1627038Y1396583D03*
X1623638D03*
X1627038Y1408495D03*
X1623638D03*
X1635265Y470737D03*
Y467337D03*
Y484910D03*
Y481510D03*
Y514871D03*
Y511471D03*
Y529044D03*
Y525644D03*
Y564910D03*
Y561510D03*
Y575684D03*
Y579084D03*
Y593257D03*
Y604030D03*
Y589857D03*
Y607430D03*
X1635878Y1384297D03*
X1639278D03*
Y1372385D03*
X1635878D03*
X1651518Y1348187D03*
X1648118D03*
X1651518Y1360099D03*
X1648118D03*
X1660358Y1384297D03*
Y1372385D03*
X1651518Y1396583D03*
X1648118D03*
Y1408495D03*
X1651518D03*
X1672598Y1348187D03*
X1675998D03*
Y1360099D03*
X1672598D03*
X1663758Y1384297D03*
Y1372385D03*
X1675998Y1396583D03*
X1672598D03*
X1675998Y1408495D03*
X1672598D03*
X1684838Y1384297D03*
X1688238D03*
X1684838Y1372385D03*
X1688238D03*
X1706734Y118342D03*
Y132515D03*
Y121742D03*
Y135915D03*
X1700478Y1348187D03*
X1697078D03*
Y1360099D03*
X1700478D03*
X1709318Y1384297D03*
Y1372385D03*
X1700478Y1396583D03*
X1697078D03*
Y1408495D03*
X1700478D03*
X1714034Y111255D03*
Y114655D03*
Y125428D03*
Y128828D03*
X1721558Y1348187D03*
X1724958D03*
Y1360099D03*
X1721558D03*
X1712718Y1372385D03*
Y1384297D03*
X1721558Y1396583D03*
X1724958D03*
X1721558Y1408495D03*
X1724958D03*
X1736405Y-79278D03*
Y-82678D03*
X1737198Y1384297D03*
X1733798D03*
Y1372385D03*
X1737198D03*
X1801761Y-43888D03*
Y-40488D03*
G54D11*
X13780Y1226024D03*
X79331Y1186654D03*
X390354Y1141024D03*
X536418Y1086654D03*
X854291Y1225118D03*
X993504Y1170748D03*
X1304528Y1141024D03*
X1450591Y1086654D03*
X1761614Y1215000D03*
X1827165Y1235630D03*
G54D44*
X661674Y23622D03*
G54D18*
X23622Y1604724D03*
X62205Y765197D03*
X74016Y333464D03*
X102224Y70866D03*
X409488Y1604724D03*
X433130Y70866D03*
X463387Y286221D03*
X463386Y765197D03*
X785039Y1547638D03*
X890217Y23622D03*
X920473Y765196D03*
X1055905Y1547637D03*
X1118760Y23622D03*
X1347303Y70866D03*
X1377559Y286220D03*
Y765197D03*
X1431457Y1604724D03*
X1575846Y23622D03*
X1766929Y333464D03*
X1778740Y765197D03*
X1795010Y23622D03*
X1817323Y1604724D03*
G54D19*
X28819Y81575D03*
X73307Y61614D03*
X131181Y81575D03*
X175669Y61614D03*
X233543Y81575D03*
X278032Y61614D03*
X335906Y81575D03*
X380394Y61614D03*
X485886Y81595D03*
X530394Y61614D03*
X588248Y81594D03*
X632756Y61614D03*
X690611Y81595D03*
X735118Y61614D03*
X792973Y81595D03*
X837480Y61614D03*
X942973Y81595D03*
X987480Y61614D03*
X1045335Y81595D03*
X1089843Y61614D03*
X1147697Y81595D03*
X1192205Y61614D03*
X1250060Y81595D03*
X1294567Y61614D03*
X1400060Y81595D03*
X1444567Y61614D03*
X1502441Y81575D03*
X1546929Y61614D03*
X1604784Y81595D03*
X1649291Y61614D03*
X1707146Y81595D03*
X1751654Y61614D03*
G54D34*
X109882Y1473977D03*
Y1479095D03*
Y1504685D03*
Y1509804D03*
Y1576339D03*
Y1581457D03*
Y1607048D03*
Y1612166D03*
X127205Y1473977D03*
Y1479095D03*
X118543Y1478308D03*
Y1483426D03*
X127205Y1504685D03*
Y1509804D03*
X118543Y1509016D03*
Y1514134D03*
X127205Y1576339D03*
Y1581457D03*
X118543Y1580670D03*
Y1585788D03*
X127205Y1607048D03*
Y1612166D03*
X118543Y1611378D03*
Y1616496D03*
X144528Y1473977D03*
Y1479095D03*
X135866Y1478308D03*
Y1483426D03*
X144528Y1504685D03*
Y1509804D03*
X135866Y1509016D03*
Y1514134D03*
X144528Y1576339D03*
Y1581457D03*
X135866Y1580670D03*
Y1585788D03*
X144528Y1607048D03*
Y1612166D03*
X135866Y1611378D03*
Y1616496D03*
X161850Y1473977D03*
Y1479095D03*
X153189Y1478308D03*
Y1483426D03*
X161850Y1504685D03*
Y1509804D03*
X153189Y1509016D03*
Y1514134D03*
X161850Y1576339D03*
Y1581457D03*
X153189Y1580670D03*
Y1585788D03*
X161850Y1607048D03*
Y1612166D03*
X153189Y1611378D03*
Y1616496D03*
X170512Y1478308D03*
Y1483426D03*
Y1509016D03*
Y1514134D03*
Y1580670D03*
Y1585788D03*
Y1611378D03*
Y1616496D03*
X283110Y1458622D03*
X291771Y1462953D03*
X283110Y1463741D03*
X291771Y1468071D03*
X283110Y1489331D03*
X291771Y1493662D03*
X283110Y1494449D03*
X291771Y1498780D03*
X283110Y1576339D03*
X291771Y1580670D03*
X283110Y1581457D03*
X291771Y1585788D03*
X283110Y1591693D03*
X291771Y1596024D03*
X283110Y1596811D03*
X291771Y1601142D03*
X300433Y1458622D03*
X309094Y1462953D03*
X300433Y1463741D03*
X309094Y1468071D03*
X300433Y1489331D03*
X309094Y1493662D03*
X300433Y1494449D03*
X309094Y1498780D03*
X300433Y1576339D03*
X309094Y1580670D03*
X300433Y1581457D03*
X309094Y1585788D03*
X300433Y1591693D03*
X309094Y1596024D03*
X300433Y1596811D03*
X309094Y1601142D03*
X317756Y1458622D03*
X326417Y1462953D03*
X317756Y1463741D03*
X326417Y1468071D03*
X317756Y1489331D03*
X326417Y1493662D03*
X317756Y1494449D03*
X326417Y1498780D03*
X317756Y1576339D03*
X326417Y1580670D03*
X317756Y1581457D03*
X326417Y1585788D03*
X317756Y1591693D03*
X326417Y1596024D03*
X317756Y1596811D03*
X326417Y1601142D03*
X335078Y1458622D03*
X343740Y1462953D03*
X335078Y1463741D03*
X343740Y1468071D03*
X335078Y1489331D03*
X343740Y1493662D03*
X335078Y1494449D03*
X343740Y1498780D03*
X335078Y1576339D03*
X343740Y1580670D03*
X335078Y1581457D03*
X343740Y1585788D03*
X335078Y1591693D03*
X343740Y1596024D03*
X335078Y1596811D03*
X343740Y1601142D03*
X456339Y1473977D03*
Y1479095D03*
Y1504685D03*
Y1509804D03*
Y1560985D03*
Y1566103D03*
Y1591693D03*
Y1596811D03*
X473662Y1473977D03*
Y1479095D03*
X465000Y1478308D03*
Y1483426D03*
X473662Y1504685D03*
Y1509804D03*
X465000Y1509016D03*
Y1514134D03*
X473662Y1560985D03*
Y1566103D03*
X465000Y1565315D03*
Y1570434D03*
X473662Y1591693D03*
X465000Y1596024D03*
X473662Y1596811D03*
X465000Y1601142D03*
X490985Y1473977D03*
Y1479095D03*
X482323Y1478308D03*
Y1483426D03*
X490985Y1504685D03*
Y1509804D03*
X482323Y1509016D03*
Y1514134D03*
X490985Y1560985D03*
Y1566103D03*
X482323Y1565315D03*
Y1570434D03*
X490985Y1591693D03*
X482323Y1596024D03*
X490985Y1596811D03*
X482323Y1601142D03*
X499646Y1478308D03*
Y1483426D03*
Y1509016D03*
Y1514134D03*
Y1565315D03*
Y1570434D03*
Y1596024D03*
Y1601142D03*
X508307Y1473977D03*
X516969Y1478308D03*
X508307Y1479095D03*
X516969Y1483426D03*
X508307Y1504685D03*
X516969Y1509016D03*
X508307Y1509804D03*
X516969Y1514134D03*
X508307Y1560985D03*
X516969Y1565315D03*
X508307Y1566103D03*
X516969Y1570434D03*
X508307Y1591693D03*
X516969Y1596024D03*
X508307Y1596811D03*
X516969Y1601142D03*
X629567Y1458622D03*
Y1463741D03*
Y1489331D03*
Y1494449D03*
Y1560985D03*
Y1566103D03*
Y1591693D03*
Y1596811D03*
X646890Y1458622D03*
Y1463741D03*
X638228Y1462953D03*
Y1468071D03*
X646890Y1489331D03*
Y1494449D03*
X638228Y1493662D03*
Y1498780D03*
X646890Y1560985D03*
Y1566103D03*
X638228Y1565315D03*
Y1570434D03*
X646890Y1591693D03*
X638228Y1596024D03*
X646890Y1596811D03*
X638228Y1601142D03*
X664213Y1458622D03*
Y1463741D03*
X655551Y1462953D03*
Y1468071D03*
X664213Y1489331D03*
Y1494449D03*
X655551Y1493662D03*
Y1498780D03*
X664213Y1560985D03*
Y1566103D03*
X655551Y1565315D03*
Y1570434D03*
X664213Y1591693D03*
X655551Y1596024D03*
X664213Y1596811D03*
X655551Y1601142D03*
X681535Y1458622D03*
Y1463741D03*
X672874Y1462953D03*
Y1468071D03*
X681535Y1489331D03*
Y1494449D03*
X672874Y1493662D03*
Y1498780D03*
X681535Y1560985D03*
Y1566103D03*
X672874Y1565315D03*
Y1570434D03*
X681535Y1591693D03*
X672874Y1596024D03*
X681535Y1596811D03*
X672874Y1601142D03*
X690197Y1462953D03*
Y1468071D03*
Y1493662D03*
Y1498780D03*
Y1565315D03*
Y1570434D03*
Y1596024D03*
Y1601142D03*
X1131850Y1473977D03*
X1140511Y1478308D03*
X1131850Y1479095D03*
X1140511Y1483426D03*
X1131850Y1504685D03*
X1140511Y1509016D03*
X1131850Y1509804D03*
X1140511Y1514134D03*
X1131850Y1576339D03*
X1140511Y1580670D03*
X1131850Y1581457D03*
X1140511Y1585788D03*
X1131850Y1607048D03*
X1140511Y1611378D03*
X1131850Y1612166D03*
X1140511Y1616496D03*
X1149173Y1473977D03*
Y1479095D03*
Y1504685D03*
Y1509804D03*
Y1576339D03*
Y1581457D03*
Y1607048D03*
Y1612166D03*
X1166496Y1473977D03*
Y1479095D03*
X1157834Y1478308D03*
Y1483426D03*
X1166496Y1504685D03*
Y1509804D03*
X1157834Y1509016D03*
Y1514134D03*
X1166496Y1576339D03*
Y1581457D03*
X1157834Y1580670D03*
Y1585788D03*
X1166496Y1607048D03*
Y1612166D03*
X1157834Y1611378D03*
Y1616496D03*
X1183818Y1473977D03*
Y1479095D03*
X1175157Y1478308D03*
Y1483426D03*
X1183818Y1504685D03*
Y1509804D03*
X1175157Y1509016D03*
Y1514134D03*
X1183818Y1576339D03*
Y1581457D03*
X1175157Y1580670D03*
Y1585788D03*
X1183818Y1607048D03*
Y1612166D03*
X1175157Y1611378D03*
Y1616496D03*
X1192480Y1478308D03*
Y1483426D03*
Y1509016D03*
Y1514134D03*
Y1580670D03*
Y1585788D03*
Y1611378D03*
Y1616496D03*
X1305079Y1458622D03*
X1313740Y1462953D03*
X1305079Y1463741D03*
X1313740Y1468071D03*
X1305079Y1489331D03*
X1313740Y1493662D03*
X1305079Y1494449D03*
X1313740Y1498780D03*
X1305079Y1576339D03*
X1313740Y1580670D03*
X1305079Y1581457D03*
X1313740Y1585788D03*
X1305079Y1591693D03*
X1313740Y1596024D03*
X1305079Y1596811D03*
X1313740Y1601142D03*
X1322402Y1458622D03*
X1331063Y1462953D03*
X1322402Y1463741D03*
X1331063Y1468071D03*
X1322402Y1489331D03*
X1331063Y1493662D03*
X1322402Y1494449D03*
X1331063Y1498780D03*
X1322402Y1576339D03*
X1331063Y1580670D03*
X1322402Y1581457D03*
X1331063Y1585788D03*
X1322402Y1591693D03*
X1331063Y1596024D03*
X1322402Y1596811D03*
X1331063Y1601142D03*
X1339725Y1458622D03*
X1348386Y1462953D03*
X1339725Y1463741D03*
X1348386Y1468071D03*
X1339725Y1489331D03*
X1348386Y1493662D03*
X1339725Y1494449D03*
X1348386Y1498780D03*
X1339725Y1576339D03*
X1348386Y1580670D03*
X1339725Y1581457D03*
X1348386Y1585788D03*
X1339725Y1591693D03*
X1348386Y1596024D03*
X1339725Y1596811D03*
X1348386Y1601142D03*
X1357047Y1458622D03*
X1365709Y1462953D03*
X1357047Y1463741D03*
X1365709Y1468071D03*
X1357047Y1489331D03*
X1365709Y1493662D03*
X1357047Y1494449D03*
X1365709Y1498780D03*
X1357047Y1576339D03*
X1365709Y1580670D03*
X1357047Y1581457D03*
X1365709Y1585788D03*
X1357047Y1591693D03*
X1365709Y1596024D03*
X1357047Y1596811D03*
X1365709Y1601142D03*
X1478307Y1473977D03*
Y1479095D03*
Y1504685D03*
Y1509804D03*
Y1560985D03*
Y1566103D03*
Y1591693D03*
Y1596811D03*
X1495630Y1473977D03*
Y1479095D03*
X1486968Y1478308D03*
Y1483426D03*
X1495630Y1504685D03*
Y1509804D03*
X1486968Y1509016D03*
Y1514134D03*
X1495630Y1560985D03*
Y1566103D03*
X1486968Y1565315D03*
Y1570434D03*
X1495630Y1591693D03*
X1486968Y1596024D03*
X1495630Y1596811D03*
X1486968Y1601142D03*
X1512953Y1473977D03*
Y1479095D03*
X1504291Y1478308D03*
Y1483426D03*
X1512953Y1504685D03*
Y1509804D03*
X1504291Y1509016D03*
Y1514134D03*
X1512953Y1560985D03*
Y1566103D03*
X1504291Y1565315D03*
Y1570434D03*
X1512953Y1591693D03*
X1504291Y1596024D03*
X1512953Y1596811D03*
X1504291Y1601142D03*
X1530275Y1473977D03*
Y1479095D03*
X1521614Y1478308D03*
Y1483426D03*
X1530275Y1504685D03*
Y1509804D03*
X1521614Y1509016D03*
Y1514134D03*
X1530275Y1560985D03*
Y1566103D03*
X1521614Y1565315D03*
Y1570434D03*
X1530275Y1591693D03*
X1521614Y1596024D03*
X1530275Y1596811D03*
X1521614Y1601142D03*
X1538937Y1478308D03*
Y1483426D03*
Y1509016D03*
Y1514134D03*
Y1565315D03*
Y1570434D03*
Y1596024D03*
Y1601142D03*
X1651535Y1458622D03*
X1660196Y1462953D03*
X1651535Y1463741D03*
X1660196Y1468071D03*
X1651535Y1489331D03*
X1660196Y1493662D03*
X1651535Y1494449D03*
X1660196Y1498780D03*
X1651535Y1560985D03*
X1660196Y1565315D03*
X1651535Y1566103D03*
X1660196Y1570434D03*
X1651535Y1591693D03*
X1660196Y1596024D03*
X1651535Y1596811D03*
X1660196Y1601142D03*
X1668858Y1458622D03*
Y1463741D03*
Y1489331D03*
Y1494449D03*
Y1560985D03*
Y1566103D03*
Y1591693D03*
Y1596811D03*
X1686181Y1458622D03*
Y1463741D03*
X1677519Y1462953D03*
Y1468071D03*
X1686181Y1489331D03*
Y1494449D03*
X1677519Y1493662D03*
Y1498780D03*
X1686181Y1560985D03*
Y1566103D03*
X1677519Y1565315D03*
Y1570434D03*
X1686181Y1591693D03*
X1677519Y1596024D03*
X1686181Y1596811D03*
X1677519Y1601142D03*
X1703503Y1458622D03*
Y1463741D03*
X1694842Y1462953D03*
Y1468071D03*
X1703503Y1489331D03*
Y1494449D03*
X1694842Y1493662D03*
Y1498780D03*
X1703503Y1560985D03*
Y1566103D03*
X1694842Y1565315D03*
Y1570434D03*
X1703503Y1591693D03*
X1694842Y1596024D03*
X1703503Y1596811D03*
X1694842Y1601142D03*
X1712165Y1462953D03*
Y1468071D03*
Y1493662D03*
Y1498780D03*
Y1565315D03*
Y1570434D03*
Y1596024D03*
Y1601142D03*
G54D38*
X173829Y455492D03*
Y583957D03*
X202844Y455492D03*
Y583957D03*
X630915Y455492D03*
Y583957D03*
X659930Y455492D03*
Y583957D03*
X1088002Y455492D03*
Y583957D03*
X1117017Y455492D03*
Y583957D03*
X1545089Y455492D03*
Y583957D03*
X1574104Y455492D03*
Y583957D03*
G54D61*
X1795453Y812874D03*
Y834922D03*
G54D48*
X849441Y1367717D03*
G54D50*
X895384Y228740D03*
Y276772D03*
X923336Y226772D03*
Y278740D03*
G54D55*
X1030635Y764546D03*
G54D62*
X1803917Y823898D03*
G54D59*
X1747253Y1715189D03*
Y1744208D03*
X1747246Y1773377D03*
G54D60*
X1747253Y1802909D03*
G54D63*
X1817323Y1567323D03*
G54D13*
X19685Y-83298D03*
Y1801195D03*
X1821260Y-83298D03*
Y1801195D03*
G54D30*
X116731Y1066535D03*
Y1263386D03*
X352952Y1066535D03*
Y1263386D03*
X573818Y1066535D03*
Y1263386D03*
X810038Y1066535D03*
Y1263386D03*
X1030905Y1066535D03*
Y1263386D03*
X1267125Y1066535D03*
Y1263386D03*
X1487991Y1066535D03*
Y1263386D03*
X1724212Y1066535D03*
Y1263386D03*
G54D17*
X26789Y1373669D03*
X184851Y334492D03*
X235433Y1580079D03*
Y1626339D03*
X581890Y1580079D03*
Y1626339D03*
X1259055Y1580079D03*
Y1626339D03*
X1605512Y1580079D03*
Y1626339D03*
X1796847Y1517889D03*
X1809883Y120792D03*
G54D47*
X770472Y1490945D03*
X820079Y388583D03*
X1020866D03*
X1070472Y1490945D03*
G54D32*
X109882Y1453504D03*
Y1468859D03*
Y1484213D03*
Y1499567D03*
Y1514922D03*
Y1555867D03*
Y1571221D03*
Y1586575D03*
Y1601930D03*
Y1617284D03*
X127205Y1453504D03*
X118543Y1457835D03*
X127205Y1468859D03*
X118543Y1473189D03*
X127205Y1484213D03*
X118543Y1488544D03*
X127205Y1499567D03*
Y1514922D03*
X118543Y1503898D03*
Y1519252D03*
X127205Y1555867D03*
X118543Y1560197D03*
X127205Y1571221D03*
X118543Y1575552D03*
X127205Y1586575D03*
X118543Y1590906D03*
X127205Y1601930D03*
X118543Y1606260D03*
X127205Y1617284D03*
X118543Y1621615D03*
X144528Y1453504D03*
X135866Y1457835D03*
X144528Y1468859D03*
X135866Y1473189D03*
X144528Y1484213D03*
X135866Y1488544D03*
X144528Y1499567D03*
Y1514922D03*
X135866Y1503898D03*
Y1519252D03*
X144528Y1555867D03*
X135866Y1560197D03*
X144528Y1571221D03*
X135866Y1575552D03*
X144528Y1586575D03*
X135866Y1590906D03*
X144528Y1601930D03*
X135866Y1606260D03*
X144528Y1617284D03*
X135866Y1621615D03*
X161850Y1453504D03*
X153189Y1457835D03*
X161850Y1468859D03*
X153189Y1473189D03*
X161850Y1484213D03*
X153189Y1488544D03*
X161850Y1499567D03*
Y1514922D03*
X153189Y1503898D03*
Y1519252D03*
X161850Y1555867D03*
X153189Y1560197D03*
X161850Y1571221D03*
X153189Y1575552D03*
X161850Y1586575D03*
X153189Y1590906D03*
X161850Y1601930D03*
X153189Y1606260D03*
X161850Y1617284D03*
X153189Y1621615D03*
X179173Y1453504D03*
X170512Y1457835D03*
X179173Y1468859D03*
X170512Y1473189D03*
X179173Y1484213D03*
X170512Y1488544D03*
X179173Y1499567D03*
Y1514922D03*
X170512Y1503898D03*
Y1519252D03*
X179173Y1555867D03*
X170512Y1560197D03*
X179173Y1571221D03*
X170512Y1575552D03*
X179173Y1586575D03*
X170512Y1590906D03*
X179173Y1601930D03*
X170512Y1606260D03*
X179173Y1617284D03*
X170512Y1621615D03*
X187835Y1457835D03*
Y1473189D03*
Y1488544D03*
Y1503898D03*
Y1519252D03*
Y1560197D03*
Y1575552D03*
Y1590906D03*
Y1606260D03*
Y1621615D03*
X283110Y1453504D03*
X291771Y1457835D03*
X283110Y1468859D03*
X291771Y1473189D03*
X283110Y1484213D03*
X291771Y1488544D03*
X283110Y1499567D03*
X291771Y1503898D03*
X283110Y1514922D03*
X291771Y1519252D03*
X283110Y1555867D03*
X291771Y1560197D03*
X283110Y1571221D03*
X291771Y1575552D03*
X283110Y1586575D03*
X291771Y1590906D03*
X283110Y1601930D03*
X291771Y1606260D03*
X283110Y1617284D03*
X291771Y1621615D03*
X300433Y1453504D03*
X309094Y1457835D03*
X300433Y1468859D03*
X309094Y1473189D03*
X300433Y1484213D03*
X309094Y1488544D03*
X300433Y1499567D03*
X309094Y1503898D03*
X300433Y1514922D03*
X309094Y1519252D03*
X300433Y1555867D03*
X309094Y1560197D03*
X300433Y1571221D03*
X309094Y1575552D03*
X300433Y1586575D03*
X309094Y1590906D03*
X300433Y1601930D03*
X309094Y1606260D03*
X300433Y1617284D03*
X309094Y1621615D03*
X317756Y1453504D03*
X326417Y1457835D03*
X317756Y1468859D03*
X326417Y1473189D03*
X317756Y1484213D03*
X326417Y1488544D03*
X317756Y1499567D03*
X326417Y1503898D03*
X317756Y1514922D03*
X326417Y1519252D03*
X317756Y1555867D03*
X326417Y1560197D03*
X317756Y1571221D03*
X326417Y1575552D03*
X317756Y1586575D03*
X326417Y1590906D03*
X317756Y1601930D03*
X326417Y1606260D03*
X317756Y1617284D03*
X326417Y1621615D03*
X335078Y1453504D03*
X343740Y1457835D03*
X335078Y1468859D03*
X343740Y1473189D03*
X335078Y1484213D03*
X343740Y1488544D03*
X335078Y1499567D03*
X343740Y1503898D03*
X335078Y1514922D03*
X343740Y1519252D03*
X335078Y1555867D03*
X343740Y1560197D03*
X335078Y1571221D03*
X343740Y1575552D03*
X335078Y1586575D03*
X343740Y1590906D03*
X335078Y1601930D03*
X343740Y1606260D03*
X335078Y1617284D03*
X343740Y1621615D03*
X352401Y1453504D03*
X361063Y1457835D03*
X352401Y1468859D03*
X361063Y1473189D03*
X352401Y1484213D03*
X361063Y1488544D03*
X352401Y1499567D03*
X361063Y1503898D03*
X352401Y1514922D03*
X361063Y1519252D03*
X352401Y1555867D03*
X361063Y1560197D03*
X352401Y1571221D03*
X361063Y1575552D03*
X352401Y1586575D03*
X361063Y1590906D03*
X352401Y1601930D03*
X361063Y1606260D03*
X352401Y1617284D03*
X361063Y1621615D03*
X456339Y1453504D03*
Y1468859D03*
Y1484213D03*
Y1499567D03*
Y1514922D03*
Y1555867D03*
Y1571221D03*
Y1586575D03*
Y1601930D03*
Y1617284D03*
X473662Y1453504D03*
X465000Y1457835D03*
X473662Y1468859D03*
X465000Y1473189D03*
X473662Y1484213D03*
X465000Y1488544D03*
X473662Y1499567D03*
Y1514922D03*
X465000Y1503898D03*
Y1519252D03*
X473662Y1555867D03*
X465000Y1560197D03*
X473662Y1571221D03*
X465000Y1575552D03*
X473662Y1586575D03*
X465000Y1590906D03*
X473662Y1601930D03*
X465000Y1606260D03*
X473662Y1617284D03*
X465000Y1621615D03*
X490985Y1453504D03*
X482323Y1457835D03*
X490985Y1468859D03*
X482323Y1473189D03*
X490985Y1484213D03*
X482323Y1488544D03*
X490985Y1499567D03*
Y1514922D03*
X482323Y1503898D03*
Y1519252D03*
X490985Y1555867D03*
X482323Y1560197D03*
X490985Y1571221D03*
X482323Y1575552D03*
X490985Y1586575D03*
X482323Y1590906D03*
X490985Y1601930D03*
X482323Y1606260D03*
X490985Y1617284D03*
X482323Y1621615D03*
X508307Y1453504D03*
X499646Y1457835D03*
X508307Y1468859D03*
X499646Y1473189D03*
X508307Y1484213D03*
X499646Y1488544D03*
X508307Y1499567D03*
Y1514922D03*
X499646Y1503898D03*
Y1519252D03*
X508307Y1555867D03*
X499646Y1560197D03*
X508307Y1571221D03*
X499646Y1575552D03*
X508307Y1586575D03*
X499646Y1590906D03*
X508307Y1601930D03*
X499646Y1606260D03*
X508307Y1617284D03*
X499646Y1621615D03*
X516969Y1457835D03*
Y1473189D03*
Y1488544D03*
Y1503898D03*
Y1519252D03*
Y1560197D03*
Y1575552D03*
Y1590906D03*
Y1606260D03*
Y1621615D03*
X525630Y1453504D03*
X534292Y1457835D03*
X525630Y1468859D03*
X534292Y1473189D03*
X525630Y1484213D03*
X534292Y1488544D03*
X525630Y1499567D03*
X534292Y1503898D03*
X525630Y1514922D03*
X534292Y1519252D03*
X525630Y1555867D03*
X534292Y1560197D03*
X525630Y1571221D03*
X534292Y1575552D03*
X525630Y1586575D03*
X534292Y1590906D03*
X525630Y1601930D03*
X534292Y1606260D03*
X525630Y1617284D03*
X534292Y1621615D03*
X629567Y1453504D03*
X638228Y1457835D03*
X629567Y1468859D03*
X638228Y1473189D03*
X629567Y1484213D03*
X638228Y1488544D03*
X629567Y1499567D03*
X638228Y1503898D03*
X629567Y1514922D03*
X638228Y1519252D03*
X629567Y1555867D03*
X638228Y1560197D03*
X629567Y1571221D03*
X638228Y1575552D03*
X629567Y1586575D03*
X638228Y1590906D03*
X629567Y1601930D03*
X638228Y1606260D03*
X629567Y1617284D03*
X638228Y1621615D03*
X646890Y1453504D03*
Y1468859D03*
Y1484213D03*
Y1499567D03*
Y1514922D03*
Y1555867D03*
Y1571221D03*
Y1586575D03*
Y1601930D03*
Y1617284D03*
X664213Y1453504D03*
X655551Y1457835D03*
X664213Y1468859D03*
X655551Y1473189D03*
X664213Y1484213D03*
X655551Y1488544D03*
X664213Y1499567D03*
Y1514922D03*
X655551Y1503898D03*
Y1519252D03*
X664213Y1555867D03*
X655551Y1560197D03*
X664213Y1571221D03*
X655551Y1575552D03*
X664213Y1586575D03*
X655551Y1590906D03*
X664213Y1601930D03*
X655551Y1606260D03*
X664213Y1617284D03*
X655551Y1621615D03*
X681535Y1453504D03*
X672874Y1457835D03*
X681535Y1468859D03*
X672874Y1473189D03*
X681535Y1484213D03*
X672874Y1488544D03*
X681535Y1499567D03*
Y1514922D03*
X672874Y1503898D03*
Y1519252D03*
X681535Y1555867D03*
X672874Y1560197D03*
X681535Y1571221D03*
X672874Y1575552D03*
X681535Y1586575D03*
X672874Y1590906D03*
X681535Y1601930D03*
X672874Y1606260D03*
X681535Y1617284D03*
X672874Y1621615D03*
X698858Y1453504D03*
X690197Y1457835D03*
X698858Y1468859D03*
X690197Y1473189D03*
X698858Y1484213D03*
X690197Y1488544D03*
X698858Y1499567D03*
Y1514922D03*
X690197Y1503898D03*
Y1519252D03*
X698858Y1555867D03*
X690197Y1560197D03*
X698858Y1571221D03*
X690197Y1575552D03*
X698858Y1586575D03*
X690197Y1590906D03*
X698858Y1601930D03*
X690197Y1606260D03*
X698858Y1617284D03*
X690197Y1621615D03*
X707520Y1457835D03*
Y1473189D03*
Y1488544D03*
Y1503898D03*
Y1519252D03*
Y1560197D03*
Y1575552D03*
Y1590906D03*
Y1606260D03*
Y1621615D03*
X1131850Y1453504D03*
X1140511Y1457835D03*
X1131850Y1468859D03*
X1140511Y1473189D03*
X1131850Y1484213D03*
X1140511Y1488544D03*
X1131850Y1499567D03*
X1140511Y1503898D03*
X1131850Y1514922D03*
X1140511Y1519252D03*
X1131850Y1555867D03*
X1140511Y1560197D03*
X1131850Y1571221D03*
X1140511Y1575552D03*
X1131850Y1586575D03*
X1140511Y1590906D03*
X1131850Y1601930D03*
X1140511Y1606260D03*
X1131850Y1617284D03*
X1140511Y1621615D03*
X1149173Y1453504D03*
X1157834Y1457835D03*
X1149173Y1468859D03*
X1157834Y1473189D03*
X1149173Y1484213D03*
X1157834Y1488544D03*
X1149173Y1499567D03*
X1157834Y1503898D03*
X1149173Y1514922D03*
X1157834Y1519252D03*
X1149173Y1555867D03*
X1157834Y1560197D03*
X1149173Y1571221D03*
X1157834Y1575552D03*
X1149173Y1586575D03*
X1157834Y1590906D03*
X1149173Y1601930D03*
X1157834Y1606260D03*
X1149173Y1617284D03*
X1157834Y1621615D03*
X1166496Y1453504D03*
Y1468859D03*
Y1484213D03*
Y1499567D03*
Y1514922D03*
Y1555867D03*
Y1571221D03*
Y1586575D03*
Y1601930D03*
Y1617284D03*
X1183818Y1453504D03*
X1175157Y1457835D03*
X1183818Y1468859D03*
X1175157Y1473189D03*
X1183818Y1484213D03*
X1175157Y1488544D03*
X1183818Y1499567D03*
Y1514922D03*
X1175157Y1503898D03*
Y1519252D03*
X1183818Y1555867D03*
X1175157Y1560197D03*
X1183818Y1571221D03*
X1175157Y1575552D03*
X1183818Y1586575D03*
X1175157Y1590906D03*
X1183818Y1601930D03*
X1175157Y1606260D03*
X1183818Y1617284D03*
X1175157Y1621615D03*
X1201141Y1453504D03*
X1192480Y1457835D03*
X1201141Y1468859D03*
X1192480Y1473189D03*
X1201141Y1484213D03*
X1192480Y1488544D03*
X1201141Y1499567D03*
Y1514922D03*
X1192480Y1503898D03*
Y1519252D03*
X1201141Y1555867D03*
X1192480Y1560197D03*
X1201141Y1571221D03*
X1192480Y1575552D03*
X1201141Y1586575D03*
X1192480Y1590906D03*
X1201141Y1601930D03*
X1192480Y1606260D03*
X1201141Y1617284D03*
X1192480Y1621615D03*
X1209803Y1457835D03*
Y1473189D03*
Y1488544D03*
Y1503898D03*
Y1519252D03*
Y1560197D03*
Y1575552D03*
Y1590906D03*
Y1606260D03*
Y1621615D03*
X1305079Y1453504D03*
X1313740Y1457835D03*
X1305079Y1468859D03*
X1313740Y1473189D03*
X1305079Y1484213D03*
X1313740Y1488544D03*
X1305079Y1499567D03*
X1313740Y1503898D03*
X1305079Y1514922D03*
X1313740Y1519252D03*
X1305079Y1555867D03*
X1313740Y1560197D03*
X1305079Y1571221D03*
X1313740Y1575552D03*
X1305079Y1586575D03*
X1313740Y1590906D03*
X1305079Y1601930D03*
X1313740Y1606260D03*
X1305079Y1617284D03*
X1313740Y1621615D03*
X1322402Y1453504D03*
X1331063Y1457835D03*
X1322402Y1468859D03*
X1331063Y1473189D03*
X1322402Y1484213D03*
X1331063Y1488544D03*
X1322402Y1499567D03*
X1331063Y1503898D03*
X1322402Y1514922D03*
X1331063Y1519252D03*
X1322402Y1555867D03*
X1331063Y1560197D03*
X1322402Y1571221D03*
X1331063Y1575552D03*
X1322402Y1586575D03*
X1331063Y1590906D03*
X1322402Y1601930D03*
X1331063Y1606260D03*
X1322402Y1617284D03*
X1331063Y1621615D03*
X1339725Y1453504D03*
X1348386Y1457835D03*
X1339725Y1468859D03*
X1348386Y1473189D03*
X1339725Y1484213D03*
X1348386Y1488544D03*
X1339725Y1499567D03*
X1348386Y1503898D03*
X1339725Y1514922D03*
X1348386Y1519252D03*
X1339725Y1555867D03*
X1348386Y1560197D03*
X1339725Y1571221D03*
X1348386Y1575552D03*
X1339725Y1586575D03*
X1348386Y1590906D03*
X1339725Y1601930D03*
X1348386Y1606260D03*
X1339725Y1617284D03*
X1348386Y1621615D03*
X1357047Y1453504D03*
X1365709Y1457835D03*
X1357047Y1468859D03*
X1365709Y1473189D03*
X1357047Y1484213D03*
X1365709Y1488544D03*
X1357047Y1499567D03*
X1365709Y1503898D03*
X1357047Y1514922D03*
X1365709Y1519252D03*
X1357047Y1555867D03*
X1365709Y1560197D03*
X1357047Y1571221D03*
X1365709Y1575552D03*
X1357047Y1586575D03*
X1365709Y1590906D03*
X1357047Y1601930D03*
X1365709Y1606260D03*
X1357047Y1617284D03*
X1365709Y1621615D03*
X1374370Y1453504D03*
X1383032Y1457835D03*
X1374370Y1468859D03*
X1383032Y1473189D03*
X1374370Y1484213D03*
X1383032Y1488544D03*
X1374370Y1499567D03*
X1383032Y1503898D03*
X1374370Y1514922D03*
X1383032Y1519252D03*
X1374370Y1555867D03*
X1383032Y1560197D03*
X1374370Y1571221D03*
X1383032Y1575552D03*
X1374370Y1586575D03*
X1383032Y1590906D03*
X1374370Y1601930D03*
X1383032Y1606260D03*
X1374370Y1617284D03*
X1383032Y1621615D03*
X1478307Y1453504D03*
Y1468859D03*
Y1484213D03*
Y1499567D03*
Y1514922D03*
Y1555867D03*
Y1571221D03*
Y1586575D03*
Y1601930D03*
Y1617284D03*
X1495630Y1453504D03*
X1486968Y1457835D03*
X1495630Y1468859D03*
X1486968Y1473189D03*
X1495630Y1484213D03*
X1486968Y1488544D03*
X1495630Y1499567D03*
Y1514922D03*
X1486968Y1503898D03*
Y1519252D03*
X1495630Y1555867D03*
X1486968Y1560197D03*
X1495630Y1571221D03*
X1486968Y1575552D03*
X1495630Y1586575D03*
X1486968Y1590906D03*
X1495630Y1601930D03*
X1486968Y1606260D03*
X1495630Y1617284D03*
X1486968Y1621615D03*
X1512953Y1453504D03*
X1504291Y1457835D03*
X1512953Y1468859D03*
X1504291Y1473189D03*
X1512953Y1484213D03*
X1504291Y1488544D03*
X1512953Y1499567D03*
Y1514922D03*
X1504291Y1503898D03*
Y1519252D03*
X1512953Y1555867D03*
X1504291Y1560197D03*
X1512953Y1571221D03*
X1504291Y1575552D03*
X1512953Y1586575D03*
X1504291Y1590906D03*
X1512953Y1601930D03*
X1504291Y1606260D03*
X1512953Y1617284D03*
X1504291Y1621615D03*
X1530275Y1453504D03*
X1521614Y1457835D03*
X1530275Y1468859D03*
X1521614Y1473189D03*
X1530275Y1484213D03*
X1521614Y1488544D03*
X1530275Y1499567D03*
Y1514922D03*
X1521614Y1503898D03*
Y1519252D03*
X1530275Y1555867D03*
X1521614Y1560197D03*
X1530275Y1571221D03*
X1521614Y1575552D03*
X1530275Y1586575D03*
X1521614Y1590906D03*
X1530275Y1601930D03*
X1521614Y1606260D03*
X1530275Y1617284D03*
X1521614Y1621615D03*
X1547598Y1453504D03*
X1538937Y1457835D03*
X1547598Y1468859D03*
X1538937Y1473189D03*
X1547598Y1484213D03*
X1538937Y1488544D03*
X1547598Y1499567D03*
Y1514922D03*
X1538937Y1503898D03*
Y1519252D03*
X1547598Y1555867D03*
X1538937Y1560197D03*
X1547598Y1571221D03*
X1538937Y1575552D03*
X1547598Y1586575D03*
X1538937Y1590906D03*
X1547598Y1601930D03*
X1538937Y1606260D03*
X1547598Y1617284D03*
X1538937Y1621615D03*
X1556260Y1457835D03*
Y1473189D03*
Y1488544D03*
Y1503898D03*
Y1519252D03*
Y1560197D03*
Y1575552D03*
Y1590906D03*
Y1606260D03*
Y1621615D03*
X1651535Y1453504D03*
X1660196Y1457835D03*
X1651535Y1468859D03*
X1660196Y1473189D03*
X1651535Y1484213D03*
X1660196Y1488544D03*
X1651535Y1499567D03*
X1660196Y1503898D03*
X1651535Y1514922D03*
X1660196Y1519252D03*
X1651535Y1555867D03*
X1660196Y1560197D03*
X1651535Y1571221D03*
X1660196Y1575552D03*
X1651535Y1586575D03*
X1660196Y1590906D03*
X1651535Y1601930D03*
X1660196Y1606260D03*
X1651535Y1617284D03*
X1660196Y1621615D03*
X1668858Y1453504D03*
X1677519Y1457835D03*
X1668858Y1468859D03*
X1677519Y1473189D03*
X1668858Y1484213D03*
X1677519Y1488544D03*
X1668858Y1499567D03*
X1677519Y1503898D03*
X1668858Y1514922D03*
X1677519Y1519252D03*
X1668858Y1555867D03*
X1677519Y1560197D03*
X1668858Y1571221D03*
X1677519Y1575552D03*
X1668858Y1586575D03*
X1677519Y1590906D03*
X1668858Y1601930D03*
X1677519Y1606260D03*
X1668858Y1617284D03*
X1677519Y1621615D03*
X1686181Y1453504D03*
Y1468859D03*
Y1484213D03*
Y1499567D03*
Y1514922D03*
Y1555867D03*
Y1571221D03*
Y1586575D03*
Y1601930D03*
Y1617284D03*
X1703503Y1453504D03*
X1694842Y1457835D03*
X1703503Y1468859D03*
X1694842Y1473189D03*
X1703503Y1484213D03*
X1694842Y1488544D03*
X1703503Y1499567D03*
Y1514922D03*
X1694842Y1503898D03*
Y1519252D03*
X1703503Y1555867D03*
X1694842Y1560197D03*
X1703503Y1571221D03*
X1694842Y1575552D03*
X1703503Y1586575D03*
X1694842Y1590906D03*
X1703503Y1601930D03*
X1694842Y1606260D03*
X1703503Y1617284D03*
X1694842Y1621615D03*
X1720826Y1453504D03*
X1712165Y1457835D03*
X1720826Y1468859D03*
X1712165Y1473189D03*
X1720826Y1484213D03*
X1712165Y1488544D03*
X1720826Y1499567D03*
Y1514922D03*
X1712165Y1503898D03*
Y1519252D03*
X1720826Y1555867D03*
X1712165Y1560197D03*
X1720826Y1571221D03*
X1712165Y1575552D03*
X1720826Y1586575D03*
X1712165Y1590906D03*
X1720826Y1601930D03*
X1712165Y1606260D03*
X1720826Y1617284D03*
X1712165Y1621615D03*
X1729488Y1457835D03*
Y1473189D03*
Y1488544D03*
Y1503898D03*
Y1519252D03*
Y1560197D03*
Y1575552D03*
Y1590906D03*
Y1606260D03*
Y1621615D03*
G54D40*
X235433Y1606142D03*
X581890D03*
X1259055D03*
X1605512D03*
G54D16*
X15139Y198883D03*
Y201683D03*
X18564Y238589D03*
X6690Y1496782D03*
X34520Y213539D03*
X36201Y238714D03*
X21530Y236121D03*
X27966Y238689D03*
X27625Y663094D03*
X25818Y682139D03*
X28818D03*
X32079Y1517641D03*
X65189Y228961D03*
Y231461D03*
Y223661D03*
Y226461D03*
X54733Y231226D03*
Y228726D03*
Y223726D03*
Y226226D03*
X67622Y572842D03*
X64408Y572975D03*
X73110Y101701D03*
X78501Y110445D03*
Y115401D03*
Y129574D03*
Y124618D03*
X73158Y229286D03*
X76851Y222212D03*
Y224712D03*
X73158Y231786D03*
X75777Y585507D03*
X71184D03*
X71730Y579475D03*
X71228Y590145D03*
X75822Y590190D03*
X75684Y605443D03*
X83684D03*
X78129Y656900D03*
X72314Y680207D03*
Y683407D03*
X82714Y674707D03*
X71928Y873683D03*
X88903Y117557D03*
Y122513D03*
Y131731D03*
Y136687D03*
X94390Y293645D03*
Y290845D03*
Y288345D03*
X91890Y293645D03*
Y290845D03*
Y288345D03*
X93456Y649838D03*
X89432Y668293D03*
X92134D03*
X85614Y674707D03*
X87714Y684607D03*
X117501Y198883D03*
Y201683D03*
X111275Y1008262D03*
Y1011762D03*
X130328Y238689D03*
X123892Y236121D03*
X120926Y238589D03*
X136882Y213539D03*
X138563Y238714D03*
X143186Y402291D03*
Y397335D03*
X140786Y416465D03*
Y411509D03*
Y425682D03*
Y430638D03*
Y439855D03*
Y444811D03*
Y468609D03*
Y473565D03*
Y487738D03*
Y482782D03*
Y512743D03*
Y517699D03*
Y531872D03*
Y526916D03*
X157095Y228726D03*
Y231226D03*
X167551Y223661D03*
X157095Y226226D03*
Y223726D03*
X151188Y390223D03*
Y395179D03*
Y404396D03*
Y409352D03*
Y423525D03*
Y418569D03*
Y432743D03*
Y437699D03*
Y489895D03*
Y480677D03*
Y475721D03*
Y494851D03*
Y519855D03*
Y538984D03*
Y534028D03*
Y524811D03*
X175472Y101701D03*
X175520Y229286D03*
X179213Y224712D03*
Y222212D03*
X167551Y231461D03*
Y228961D03*
Y226461D03*
X175520Y231786D03*
X194189Y103621D03*
X196752Y293645D03*
Y290845D03*
Y288345D03*
X194252Y293645D03*
Y290845D03*
Y288345D03*
X203740Y567914D03*
Y565414D03*
Y570414D03*
Y575414D03*
Y572914D03*
X219863Y198883D03*
Y201683D03*
X226254Y236121D03*
X223288Y238589D03*
X239244Y213539D03*
X232690Y238689D03*
X240925Y238714D03*
X259457Y228726D03*
Y231226D03*
Y226226D03*
Y223726D03*
X251802Y824128D03*
X277834Y101701D03*
X269913Y228961D03*
Y226461D03*
Y223661D03*
X277882Y229286D03*
X269913Y231461D03*
X277882Y231786D03*
X286129Y36971D03*
X296551Y103621D03*
X281575Y224712D03*
Y222212D03*
X296614Y293645D03*
Y290845D03*
Y288345D03*
X309106Y37543D03*
X299114Y290845D03*
Y288345D03*
Y293645D03*
X302966Y324139D03*
X310013Y316731D03*
X301158Y380307D03*
X301308Y395346D03*
X301393Y400039D03*
X322225Y198883D03*
Y201683D03*
X325650Y238589D03*
X328616Y236121D03*
X321549Y445315D03*
Y448115D03*
X323489Y471484D03*
Y466528D03*
Y480701D03*
Y485657D03*
Y515617D03*
Y510661D03*
Y529791D03*
Y524835D03*
Y565657D03*
Y560701D03*
Y574874D03*
Y579830D03*
Y589047D03*
Y594003D03*
Y603221D03*
Y608177D03*
X330905Y11806D03*
Y23806D03*
Y31806D03*
X341606Y213539D03*
X335052Y238689D03*
X343287Y238714D03*
X345050Y458334D03*
X333891Y473640D03*
Y487813D03*
Y478596D03*
Y492769D03*
Y522730D03*
Y517774D03*
Y531947D03*
Y536903D03*
Y572769D03*
Y567813D03*
Y586943D03*
Y581987D03*
Y596160D03*
Y601116D03*
Y610333D03*
Y615289D03*
X347450Y447486D03*
X353670Y488618D03*
Y491118D03*
Y493618D03*
Y496118D03*
X372275Y226461D03*
X361819Y231226D03*
Y228726D03*
Y223726D03*
Y226226D03*
X372275Y228961D03*
Y231461D03*
Y223661D03*
X364954Y450091D03*
X367564Y452740D03*
X365332Y490070D03*
Y487570D03*
X361887Y493758D03*
Y496258D03*
X377020Y782535D03*
X368491Y815092D03*
X368273Y928100D03*
X380196Y101701D03*
X380244Y229286D03*
X383937Y222212D03*
Y224712D03*
X380244Y231786D03*
X393837Y466409D03*
X393823Y487382D03*
X398913Y103621D03*
X398976Y293645D03*
X401476D03*
Y288345D03*
Y290845D03*
X398976Y288345D03*
Y290845D03*
X406843Y399161D03*
Y401661D03*
Y396661D03*
X405603Y668060D03*
X408103D03*
X403103D03*
X400603D03*
Y678060D03*
X405603D03*
X408103D03*
X403103D03*
X406967Y878764D03*
X406415Y874840D03*
X399285Y1081599D03*
X398915Y1097278D03*
X396415D03*
X401711Y1419771D03*
X406667D03*
X400911Y1537902D03*
X407048D03*
X400911Y1544424D03*
X407048Y1549936D03*
X400911D03*
X420050Y33425D03*
X418876Y401661D03*
Y396661D03*
Y399161D03*
X411754Y474513D03*
X424731Y508152D03*
Y513452D03*
Y515952D03*
X414275Y508217D03*
Y510717D03*
Y515717D03*
Y513217D03*
X424731Y510952D03*
X410603Y668060D03*
Y678060D03*
X425759Y869921D03*
Y872721D03*
Y875521D03*
Y867121D03*
Y878321D03*
X411214Y892109D03*
X413012Y1537902D03*
Y1544098D03*
X426196Y1534087D03*
X413012Y1549936D03*
X421616Y1549885D03*
X442704Y506427D03*
X427693Y506520D03*
X438353Y508685D03*
X427693Y509020D03*
X432700Y516277D03*
X429210Y784833D03*
X428759Y869921D03*
Y867121D03*
Y872721D03*
Y875521D03*
Y878321D03*
X432332Y892049D03*
Y897649D03*
Y894849D03*
Y900449D03*
X453544Y461961D03*
X451144Y472809D03*
X447836Y711199D03*
X451889Y1301067D03*
X456832Y1299121D03*
X451889Y1306023D03*
X472226Y198883D03*
Y201683D03*
X473658Y467215D03*
X471048Y464566D03*
X469495Y1011303D03*
Y1023303D03*
Y1017303D03*
X491607Y213539D03*
X478617Y236121D03*
X475651Y238589D03*
X485053Y238689D03*
X481495Y1011303D03*
X475495D03*
X481495Y1023303D03*
Y1017303D03*
X475495Y1023303D03*
X484800Y1302000D03*
X493288Y238714D03*
X522276Y223661D03*
Y226461D03*
Y228961D03*
Y231461D03*
X511820Y231226D03*
Y228726D03*
Y223726D03*
Y226226D03*
X521494Y572975D03*
X524475Y952290D03*
X509471Y981608D03*
X517374Y1287222D03*
X514363Y1287370D03*
X520548Y1287181D03*
X530197Y101701D03*
X530245Y229286D03*
X533938Y222212D03*
Y224712D03*
X530245Y231786D03*
X524708Y572842D03*
X532863Y585507D03*
X528270D03*
X528816Y579475D03*
X532908Y590190D03*
X528314Y590145D03*
X532770Y605443D03*
X528868Y873683D03*
X548914Y103621D03*
X551477Y288345D03*
Y290845D03*
X548977Y288345D03*
Y290845D03*
Y293645D03*
X551477D03*
X540770Y605443D03*
X574588Y201683D03*
X568362Y1008262D03*
Y1011762D03*
X574588Y198883D03*
X587415Y238689D03*
X580979Y236121D03*
X578013Y238589D03*
X577249Y965445D03*
X593969Y213539D03*
X595650Y238714D03*
X600272Y397335D03*
Y402291D03*
X597872Y425682D03*
Y416465D03*
Y411509D03*
Y439855D03*
Y430638D03*
Y444811D03*
Y468609D03*
Y473565D03*
Y487738D03*
Y482782D03*
Y517699D03*
Y531872D03*
Y526916D03*
X606142Y965665D03*
X614182Y223726D03*
Y226226D03*
Y231226D03*
Y228726D03*
X608274Y390223D03*
Y395179D03*
Y404396D03*
Y409352D03*
Y418569D03*
Y423525D03*
Y432743D03*
Y437699D03*
Y489895D03*
Y480677D03*
Y475721D03*
Y494851D03*
Y519855D03*
Y538984D03*
Y534028D03*
Y524811D03*
X632559Y101701D03*
X624638Y231461D03*
X636300Y222212D03*
Y224712D03*
X632607Y229286D03*
X624638Y223661D03*
Y226461D03*
Y228961D03*
X632607Y231786D03*
X651276Y103621D03*
X651339Y290845D03*
Y293645D03*
X653839D03*
Y288345D03*
Y290845D03*
X651339Y288345D03*
X660826Y570414D03*
Y567914D03*
Y565414D03*
Y575414D03*
Y572914D03*
X676950Y201683D03*
X680375Y238589D03*
X683341Y236121D03*
X696331Y213539D03*
X698012Y238714D03*
X689777Y238689D03*
X716544Y228726D03*
Y231226D03*
Y226226D03*
Y223726D03*
X704446Y760611D03*
X713425Y786029D03*
X734921Y101701D03*
X727000Y228961D03*
Y226461D03*
Y223661D03*
X734969Y229286D03*
X727000Y231461D03*
X734969Y231786D03*
X721218Y742131D03*
X720271Y782481D03*
X738662Y224712D03*
Y222212D03*
X744069Y746617D03*
X735576Y861780D03*
X753638Y103621D03*
X760407Y324494D03*
X767099Y316731D03*
X767310Y1599164D03*
X756358Y1616917D03*
X779312Y198883D03*
Y201683D03*
X782737Y238589D03*
X780575Y471484D03*
Y466528D03*
Y480701D03*
Y485657D03*
Y510661D03*
Y515617D03*
Y524835D03*
Y529791D03*
Y560701D03*
Y565657D03*
Y579830D03*
Y574874D03*
Y589047D03*
Y594003D03*
Y603221D03*
Y608177D03*
X798693Y213539D03*
X792139Y238689D03*
X785703Y236121D03*
X790977Y473640D03*
Y487813D03*
Y478596D03*
Y492769D03*
Y517774D03*
Y522730D03*
Y531947D03*
Y536903D03*
Y567813D03*
Y572769D03*
Y581987D03*
Y586943D03*
Y601116D03*
Y596160D03*
Y615289D03*
Y610333D03*
X800374Y238714D03*
X804536Y441486D03*
X802136Y452334D03*
X810756Y491118D03*
Y488618D03*
Y483618D03*
Y486118D03*
X815492Y732917D03*
X829362Y231461D03*
Y228961D03*
Y226461D03*
Y223661D03*
X818906Y228726D03*
Y231226D03*
Y226226D03*
Y223726D03*
X829381Y348036D03*
X824650Y446740D03*
X822040Y444091D03*
X826262Y462326D03*
Y459326D03*
X818973Y491258D03*
Y488758D03*
X822418Y485070D03*
Y482570D03*
X823790Y713375D03*
X823843Y732109D03*
X819890Y736924D03*
X828423Y964731D03*
X837283Y101701D03*
X837331Y229286D03*
X841024Y224712D03*
Y222212D03*
X837331Y231786D03*
X839573Y325327D03*
X856000Y103621D03*
X858563Y293645D03*
Y290845D03*
X856063Y293645D03*
Y290845D03*
X858563Y288345D03*
X856063D03*
X854622Y359004D03*
X873885Y340892D03*
X873733Y357844D03*
X871382Y373971D03*
X875907Y486256D03*
X870137Y669461D03*
X875916Y808965D03*
X886026Y346584D03*
X896592Y362369D03*
Y366369D03*
Y370369D03*
X882907Y480350D03*
X892023Y570176D03*
X890959Y579788D03*
X890956Y588325D03*
X894015Y588253D03*
X895933Y618143D03*
X910076Y304843D03*
X905120D03*
X913206Y336489D03*
X910040Y353532D03*
X902169Y413002D03*
Y418002D03*
Y415502D03*
X913853Y561487D03*
X904393Y570176D03*
X908517D03*
X898815D03*
X898232Y588320D03*
X902635Y588305D03*
X906999Y588274D03*
X905313Y709259D03*
X905050Y720268D03*
X913716Y800815D03*
X899916D03*
X911053Y800510D03*
X901428Y1136426D03*
X904897Y1145169D03*
X902397D03*
X929978Y186854D03*
Y184054D03*
X917906Y321670D03*
X922629Y336609D03*
X922198Y342051D03*
X917858Y331453D03*
X927309Y357267D03*
X921389D03*
X915395D03*
Y363212D03*
X927309Y363239D03*
Y369210D03*
X921468D03*
X915395D03*
X927072Y386992D03*
X919072D03*
X923072D03*
X914202Y418002D03*
Y413002D03*
Y415502D03*
X916590Y800636D03*
X921790Y810965D03*
X926044Y1545370D03*
Y1542370D03*
X938125Y230891D03*
X942805Y223860D03*
X936369Y221292D03*
X940158Y245707D03*
X946064Y252998D03*
X941845Y278968D03*
X939606Y310521D03*
X939653Y317474D03*
X940924Y328959D03*
X936608Y326058D03*
X945120Y326441D03*
X930398Y342050D03*
X936453Y345336D03*
X945599Y345383D03*
X940972Y338238D03*
X943663Y355674D03*
X944900Y363700D03*
X938499Y362202D03*
X940600Y370600D03*
X939314Y707847D03*
X931244Y720471D03*
X936026Y730600D03*
X941916Y808965D03*
X949359Y198710D03*
X951040Y223885D03*
X956348Y356371D03*
X952170Y356131D03*
X958823Y362802D03*
X954888Y369513D03*
X948400Y370045D03*
X956035Y1545333D03*
X959035D03*
X953035D03*
X950035D03*
X959035Y1542333D03*
X956035D03*
X953035D03*
X950035D03*
X968906Y223726D03*
Y228726D03*
Y231226D03*
X979362Y223661D03*
X968906Y226226D03*
X973338Y345018D03*
X978581Y572975D03*
X971144Y908972D03*
X965405Y1136426D03*
X987283Y101701D03*
X987331Y229286D03*
X991024Y224712D03*
Y222212D03*
X979362Y231461D03*
Y228961D03*
Y226461D03*
X987331Y231786D03*
X992045Y366559D03*
X984045D03*
X988045D03*
X981795Y572842D03*
X985903Y579475D03*
X985357Y585507D03*
X989950D03*
X985401Y590145D03*
X989995Y590190D03*
X989857Y605443D03*
X983712Y722064D03*
X1006000Y103621D03*
X1008563Y293645D03*
X1006063D03*
Y290845D03*
Y288345D03*
X1008563Y290845D03*
Y288345D03*
X997857Y605443D03*
X1010606Y1547824D03*
X1010659Y1568771D03*
Y1565771D03*
X1010653Y1571669D03*
X1021451Y322879D03*
X1026032Y322906D03*
X1018238Y678647D03*
X1018155Y684132D03*
X1025116Y698332D03*
X1024932Y717856D03*
X1016320Y828481D03*
X1026340Y917761D03*
X1025448Y1008262D03*
Y1011762D03*
X1013606Y1547824D03*
X1016606D03*
X1019606D03*
X1013659Y1568771D03*
X1016659D03*
X1019659D03*
X1013659Y1565771D03*
X1016659D03*
X1019659D03*
X1013653Y1571669D03*
X1016653D03*
X1019653D03*
X1031674Y198883D03*
Y201683D03*
X1038065Y236121D03*
X1035099Y238589D03*
X1030184Y288709D03*
X1038068Y298789D03*
X1033112D03*
X1030753Y732213D03*
X1051055Y213539D03*
X1044501Y238689D03*
X1052736Y238714D03*
X1048695Y280161D03*
X1057359Y402291D03*
Y397335D03*
X1054959Y411509D03*
Y425682D03*
Y416465D03*
Y430638D03*
Y439855D03*
Y444811D03*
Y468609D03*
Y473565D03*
Y487738D03*
Y482782D03*
Y517699D03*
Y512743D03*
Y531872D03*
Y526916D03*
X1071268Y226226D03*
Y223726D03*
Y228726D03*
Y231226D03*
X1065361Y390223D03*
Y395179D03*
Y404396D03*
Y409352D03*
Y423525D03*
Y418569D03*
Y432743D03*
Y437699D03*
Y489895D03*
Y480677D03*
Y475721D03*
Y494851D03*
Y519855D03*
Y524811D03*
Y538984D03*
Y534028D03*
X1089645Y101701D03*
X1081724Y226461D03*
Y223661D03*
X1089693Y229286D03*
X1081724Y231461D03*
Y228961D03*
X1089693Y231786D03*
X1079863Y345660D03*
X1090747Y1617415D03*
X1108362Y103621D03*
X1093386Y224712D03*
Y222212D03*
X1108425Y293645D03*
Y290845D03*
Y288345D03*
X1096264Y1562285D03*
X1093713Y1585583D03*
X1110925Y293645D03*
Y290845D03*
Y288345D03*
X1117913Y565414D03*
Y567914D03*
Y570414D03*
Y572914D03*
Y575414D03*
X1122718Y598857D03*
X1121191Y612555D03*
X1120512Y617332D03*
X1121022Y607750D03*
X1134036Y198883D03*
Y201683D03*
X1137461Y238589D03*
X1140427Y236121D03*
X1138166Y534759D03*
X1153417Y213539D03*
X1146863Y238689D03*
X1155098Y238714D03*
X1149437Y728541D03*
X1152316Y746625D03*
X1173630Y226226D03*
Y223726D03*
Y228726D03*
Y231226D03*
X1161274Y550462D03*
X1170603Y715281D03*
X1163751Y719498D03*
X1168577Y733812D03*
X1169266Y800799D03*
X1184086Y231461D03*
Y228961D03*
Y226461D03*
Y223661D03*
X1176577Y885974D03*
X1188431Y936568D03*
X1192007Y101701D03*
X1192055Y229286D03*
X1195748Y224712D03*
Y222212D03*
X1192055Y231786D03*
X1192990Y914873D03*
X1195118Y936296D03*
X1210724Y103621D03*
X1213287Y293645D03*
Y290845D03*
Y288345D03*
X1210787Y293645D03*
Y290845D03*
Y288345D03*
X1217139Y324139D03*
X1222909Y-83456D03*
Y-78500D03*
Y-68500D03*
Y-73456D03*
X1228265Y-44406D03*
Y-39450D03*
Y-29450D03*
Y-34406D03*
X1236398Y198883D03*
Y201683D03*
X1224186Y316731D03*
X1237662Y466528D03*
Y471484D03*
Y480701D03*
Y485657D03*
Y515617D03*
Y510661D03*
Y524835D03*
Y529791D03*
Y565657D03*
Y560701D03*
Y589047D03*
Y574874D03*
Y579830D03*
Y603221D03*
Y594003D03*
Y608177D03*
X1239823Y238589D03*
X1242789Y236121D03*
X1248064Y473640D03*
Y487813D03*
Y478596D03*
Y492769D03*
Y517774D03*
Y522730D03*
Y531947D03*
Y536903D03*
X1255779Y213539D03*
X1257460Y238714D03*
X1264481Y300223D03*
X1261623Y447486D03*
X1259223Y458334D03*
X1267843Y488618D03*
Y491118D03*
Y493618D03*
X1275992Y223726D03*
Y226226D03*
Y231226D03*
Y228726D03*
X1286448Y223661D03*
Y226461D03*
Y228961D03*
Y231461D03*
X1279127Y450091D03*
X1281737Y452740D03*
X1279505Y487570D03*
Y490070D03*
X1276060Y496258D03*
Y493758D03*
X1294369Y101701D03*
X1294417Y229286D03*
X1298110Y222212D03*
Y224712D03*
X1294417Y231786D03*
X1313086Y103621D03*
X1313149Y288345D03*
Y290845D03*
Y293645D03*
X1315649Y288345D03*
Y290845D03*
Y293645D03*
X1308010Y466409D03*
X1307996Y487382D03*
X1313459Y1081599D03*
X1310589Y1097278D03*
X1313089D03*
X1334223Y33425D03*
X1333049Y399268D03*
Y401768D03*
Y396768D03*
X1321016Y399161D03*
Y401661D03*
Y396661D03*
X1325927Y474513D03*
X1386399Y201683D03*
X1383669Y1011303D03*
Y1017303D03*
Y1023303D03*
X1386399Y198883D03*
X1399226Y238689D03*
X1392790Y236121D03*
X1389824Y238589D03*
X1395669Y1011303D03*
X1389669D03*
X1395669Y1017303D03*
Y1023303D03*
X1389669D03*
X1405780Y213539D03*
X1407461Y238714D03*
X1425993Y231226D03*
Y228726D03*
Y226226D03*
Y223726D03*
X1444370Y101701D03*
X1436449Y228961D03*
X1444418Y229286D03*
X1436449Y226461D03*
Y223661D03*
X1448111Y222212D03*
Y224712D03*
X1436449Y231461D03*
X1444418Y231786D03*
X1438882Y572842D03*
X1447037Y585507D03*
X1442444D03*
X1442990Y579475D03*
X1435668Y572975D03*
X1442488Y590145D03*
X1447082Y590190D03*
X1446944Y605443D03*
X1443041Y873683D03*
X1463087Y103621D03*
X1465650Y293645D03*
Y288345D03*
Y290845D03*
X1463150Y288345D03*
Y290845D03*
Y293645D03*
X1454944Y605443D03*
X1479409Y-83456D03*
Y-78500D03*
Y-68500D03*
Y-73456D03*
X1476822Y40780D03*
X1498621Y15043D03*
Y35043D03*
Y27043D03*
X1488761Y198883D03*
Y201683D03*
X1492186Y238589D03*
X1495152Y236121D03*
X1483813Y368516D03*
X1482535Y1008262D03*
Y1002453D03*
Y1011762D03*
X1514765Y-44536D03*
Y-39580D03*
Y-29580D03*
Y-34536D03*
X1508142Y213539D03*
X1509823Y238714D03*
X1501588Y238689D03*
X1514446Y402291D03*
Y397335D03*
X1512046Y411509D03*
Y425682D03*
Y416465D03*
Y439855D03*
Y430638D03*
Y444811D03*
Y468609D03*
Y473565D03*
Y487738D03*
Y482782D03*
Y517699D03*
Y512743D03*
Y531872D03*
Y526916D03*
X1528355Y228726D03*
Y223726D03*
Y226226D03*
Y231226D03*
X1515779Y351594D03*
X1522448Y390223D03*
Y395179D03*
Y404396D03*
Y409352D03*
Y423525D03*
Y418569D03*
Y437699D03*
Y432743D03*
Y489895D03*
Y480677D03*
Y475721D03*
Y494851D03*
Y519855D03*
Y538984D03*
Y534028D03*
Y524811D03*
X1546732Y101701D03*
X1538811Y226461D03*
Y228961D03*
Y231461D03*
X1546780Y229286D03*
X1538811Y223661D03*
X1546780Y231786D03*
X1550473Y222212D03*
Y224712D03*
X1565449Y103621D03*
X1565512Y288345D03*
X1568012Y293645D03*
Y290845D03*
Y288345D03*
X1565512Y293645D03*
Y290845D03*
X1575000Y565414D03*
Y567914D03*
Y570414D03*
Y572914D03*
Y575414D03*
X1579753Y599100D03*
X1578679Y613047D03*
X1578114Y607563D03*
X1591123Y198883D03*
Y201683D03*
X1594548Y238589D03*
X1610504Y213539D03*
X1597514Y236121D03*
X1612185Y238714D03*
X1603950Y238689D03*
X1641173Y231461D03*
X1630717Y223726D03*
Y226226D03*
Y231226D03*
Y228726D03*
X1641173Y223661D03*
Y226461D03*
Y228961D03*
X1649094Y101701D03*
X1649142Y229286D03*
X1652835Y222212D03*
Y224712D03*
X1649142Y231786D03*
X1667811Y103621D03*
X1670374Y290845D03*
Y288345D03*
X1667874Y290845D03*
Y288345D03*
X1670374Y293645D03*
X1667874D03*
X1674226Y324139D03*
X1693485Y198883D03*
Y201683D03*
X1681273Y316731D03*
X1699876Y236121D03*
X1696910Y238589D03*
X1706312Y238689D03*
X1694749Y466528D03*
Y471484D03*
X1705151Y473640D03*
Y487813D03*
Y478596D03*
X1694749Y480701D03*
Y485657D03*
X1705151Y492769D03*
Y517774D03*
Y522730D03*
X1694749Y510661D03*
Y515617D03*
X1705151Y536903D03*
Y531947D03*
X1694749Y524835D03*
Y529791D03*
X1705151Y572769D03*
Y567813D03*
X1694749Y565657D03*
Y560701D03*
Y579830D03*
X1705151Y586943D03*
Y581987D03*
X1694749Y589047D03*
Y574874D03*
Y603221D03*
X1705151Y601116D03*
Y596160D03*
X1694749Y594003D03*
X1705151Y615289D03*
X1694749Y608177D03*
X1705151Y610333D03*
X1712866Y213539D03*
X1714547Y238714D03*
X1718710Y447486D03*
X1716310Y458334D03*
X1724930Y491118D03*
Y488618D03*
Y493618D03*
Y496118D03*
X1733909Y-83456D03*
Y-78500D03*
Y-68500D03*
Y-73456D03*
X1733079Y223726D03*
Y226226D03*
Y231226D03*
Y228726D03*
X1743535Y223661D03*
X1738824Y452740D03*
X1736214Y450091D03*
X1736592Y487570D03*
Y490070D03*
X1733147Y493758D03*
Y496258D03*
X1751456Y101701D03*
X1743535Y226461D03*
X1755197Y224712D03*
X1743535Y228961D03*
Y231461D03*
X1751504Y229286D03*
X1755197Y222212D03*
X1751504Y231786D03*
X1770173Y103621D03*
X1772736Y293645D03*
X1770236D03*
Y290845D03*
Y288345D03*
X1772736Y290845D03*
Y288345D03*
X1765097Y466409D03*
X1765083Y487382D03*
X1772768Y818696D03*
X1790136Y399161D03*
Y401661D03*
Y396661D03*
X1778103Y399161D03*
Y401661D03*
Y396661D03*
X1783014Y474513D03*
X1778801Y836469D03*
X1786256Y927626D03*
X1784306Y924601D03*
X1786256Y930626D03*
X1799265Y-44666D03*
Y-39710D03*
Y-29710D03*
Y-34666D03*
X1791302Y829031D03*
X1816385Y1136912D03*
X1813885D03*
Y1144912D03*
X1816385D03*
G54D21*
X51043Y60709D03*
Y150197D03*
X153405Y60709D03*
Y150197D03*
X255767Y60709D03*
Y150197D03*
X279360Y368760D03*
Y421555D03*
Y501752D03*
Y550020D03*
Y636752D03*
X358129Y60709D03*
Y150197D03*
X508130Y60709D03*
Y150197D03*
X610492Y60709D03*
Y150197D03*
X712854Y60709D03*
Y150197D03*
X736446Y368760D03*
Y421555D03*
Y501752D03*
Y550020D03*
Y636752D03*
X815216Y60709D03*
Y150197D03*
X965216Y60709D03*
Y150197D03*
X1067578Y60709D03*
Y150197D03*
X1169940Y60709D03*
Y150197D03*
X1193533Y368760D03*
Y421555D03*
Y501752D03*
Y550020D03*
Y636752D03*
X1272302Y60709D03*
Y150197D03*
X1422303Y60709D03*
Y150197D03*
X1524665Y60709D03*
Y150197D03*
X1627027Y60709D03*
Y150197D03*
X1650620Y368760D03*
Y421555D03*
Y501752D03*
Y550020D03*
Y636752D03*
X1729389Y60709D03*
Y150197D03*
G54D49*
X843012Y1592787D03*
Y1602787D03*
Y1612787D03*
Y1622787D03*
X853012Y1592787D03*
Y1602787D03*
Y1612787D03*
Y1622787D03*
X878012Y1592787D03*
Y1602787D03*
Y1612787D03*
Y1622787D03*
X888012Y1592787D03*
Y1602787D03*
Y1612787D03*
Y1622787D03*
X913012Y1592787D03*
Y1602787D03*
Y1612787D03*
Y1622787D03*
X923012Y1592787D03*
Y1602787D03*
Y1612787D03*
Y1622787D03*
X948012Y1592787D03*
Y1602787D03*
Y1612787D03*
Y1622787D03*
X958012Y1592787D03*
Y1602787D03*
Y1612787D03*
Y1622787D03*
X983012Y1592787D03*
X993012D03*
X983012Y1602787D03*
Y1612787D03*
X993012Y1602787D03*
Y1612787D03*
X983012Y1622787D03*
X993012D03*
X1018012Y1592787D03*
X1028012D03*
X1018012Y1602787D03*
Y1612787D03*
X1028012Y1602787D03*
Y1612787D03*
X1018012Y1622787D03*
X1028012D03*
G54D12*
X3035Y1578036D03*
X3017Y1639466D03*
X14751Y62381D03*
X12601Y92110D03*
X9364Y107501D03*
X16728Y107910D03*
X12652Y116894D03*
X13615Y153263D03*
X10966Y155873D03*
Y152873D03*
X12709Y175777D03*
X9745Y245784D03*
X19075Y278429D03*
X7036Y268371D03*
X14252Y1121333D03*
X11552D03*
X16752D03*
X8952D03*
X14152Y1111633D03*
X11452D03*
X8852D03*
X16652D03*
X14252Y1130333D03*
X16752D03*
X14306Y1138705D03*
X16806D03*
X20079Y1429347D03*
X12327Y1519202D03*
X11995Y1535134D03*
X6567Y1554215D03*
X14375Y1553121D03*
X18409Y1554202D03*
X12000Y1644980D03*
X33288Y109410D03*
Y116497D03*
X30788D03*
X25988D03*
X22439Y106495D03*
X30788Y123584D03*
X33288Y123583D03*
X25988Y123584D03*
X33288Y130670D03*
X30788D03*
X25988D03*
X30788Y137757D03*
X25988D03*
X29201Y151651D03*
X26201D03*
X20709Y175777D03*
X28740Y247292D03*
X21449Y253198D03*
X28740Y267292D03*
X21386Y273198D03*
X23479Y295619D03*
X32452Y581222D03*
X29652D03*
X35252D03*
Y591215D03*
X29652D03*
X32452D03*
X34254Y611091D03*
X29451Y633560D03*
X30369Y663048D03*
X27854Y671553D03*
X30414Y671508D03*
X26596Y874520D03*
X26844Y920354D03*
X24132Y958151D03*
X25371Y980696D03*
X34314Y1215403D03*
X22284Y1464612D03*
X32079Y1525641D03*
X35237Y1532096D03*
X35850Y1556096D03*
X32000Y1644980D03*
X46450Y82984D03*
Y77784D03*
Y75184D03*
Y80384D03*
X48364Y92473D03*
X46450Y85584D03*
X37988Y109410D03*
Y102323D03*
Y116496D03*
Y130670D03*
Y123583D03*
X52437Y137756D03*
X37988D03*
X45984Y163264D03*
X37284Y285272D03*
X42690Y451466D03*
X48596Y458466D03*
X39643Y555194D03*
X36843D03*
X39643Y563194D03*
X36843D03*
X39643Y571194D03*
X36843D03*
X49265Y886660D03*
X52922Y900295D03*
X47916Y947622D03*
X50366Y1086981D03*
Y1082388D03*
X38200Y1089721D03*
X44365Y1086404D03*
X38216Y1093757D03*
X49500Y1199066D03*
X51197Y1218206D03*
X39452Y1250932D03*
X48195Y1511279D03*
X48079Y1525641D03*
Y1529641D03*
Y1521641D03*
X52048Y1556062D03*
X52000Y1644980D03*
X56098Y109410D03*
Y116496D03*
X55964Y103037D03*
X56098Y123583D03*
Y130670D03*
X68896Y226141D03*
X58279Y293796D03*
X66293Y285690D03*
X68793D03*
X66293Y288190D03*
X68793D03*
X60779Y293796D03*
X65759Y437508D03*
X61759D03*
X57759D03*
X54936Y449352D03*
X59522Y448874D03*
X68619Y447269D03*
X68497Y450201D03*
X64550Y504699D03*
X62050D03*
X59550D03*
X68236Y519458D03*
X61752Y516979D03*
X64252D03*
X59252D03*
X55318Y629362D03*
X53129Y627948D03*
X55307Y688473D03*
X66342Y880067D03*
X67316Y865869D03*
X64175Y897500D03*
X67461Y912983D03*
X63303Y912835D03*
X57178Y981386D03*
X69263Y1053152D03*
X55049Y1082343D03*
X55004Y1086937D03*
X58981Y1105100D03*
X56381D03*
X61581D03*
X64281D03*
X61681Y1114800D03*
X56481D03*
X59081D03*
X64381D03*
X57218Y1123867D03*
X55397Y1133688D03*
X57897D03*
X58250Y1220896D03*
X65940Y1209382D03*
X58250Y1227796D03*
Y1230296D03*
Y1237196D03*
Y1234696D03*
Y1223396D03*
X57185Y1480808D03*
X57144Y1491047D03*
X56114Y1556061D03*
X68743Y1583498D03*
X73381Y94017D03*
X69381D03*
X71422Y151540D03*
X75072Y191941D03*
X81572Y184619D03*
X74939Y188727D03*
X83552Y206760D03*
X71696Y226141D03*
X76766Y256535D03*
X84766D03*
X71593Y285690D03*
Y288190D03*
X75819Y290755D03*
X79819D03*
X83819D03*
X71826Y480705D03*
X75736Y519458D03*
X73236D03*
X70736D03*
X81740Y636250D03*
X69670Y633205D03*
Y636005D03*
X81740Y633450D03*
X69670Y638805D03*
X81740Y639050D03*
X74414Y681907D03*
X76991Y946134D03*
X84679Y1018368D03*
X70059Y1071656D03*
X69373Y1063389D03*
X70059Y1079656D03*
X80290Y1345691D03*
Y1350683D03*
X75334Y1345691D03*
Y1350683D03*
X80290Y1357603D03*
Y1362595D03*
X75334Y1357603D03*
Y1362595D03*
X80290Y1381801D03*
Y1369889D03*
Y1374881D03*
X75334Y1381801D03*
Y1374881D03*
Y1369889D03*
X80290Y1386793D03*
X75334D03*
X87000Y1597855D03*
X76005Y1580680D03*
X82433Y1580590D03*
X72000Y1644980D03*
X88080Y103603D03*
X87002Y146461D03*
X85904Y152367D03*
X87604Y180572D03*
X92287Y180527D03*
X96010Y192421D03*
X92242Y185121D03*
X87604Y185165D03*
X85796Y279208D03*
X89900Y281307D03*
X90257Y445506D03*
X88875Y840940D03*
X91581Y877859D03*
Y874859D03*
X87853Y899220D03*
X91128Y1006487D03*
X99836Y997860D03*
X95836D03*
X100594Y1035088D03*
X97247Y1030568D03*
X103124Y1165091D03*
X87574Y1345691D03*
Y1350683D03*
X99814D03*
Y1345691D03*
X92530D03*
Y1350683D03*
X87574Y1362595D03*
Y1357603D03*
X99814Y1362595D03*
Y1357603D03*
X92530Y1362595D03*
Y1357603D03*
X87574Y1374881D03*
Y1369795D03*
Y1381801D03*
X99814D03*
Y1374881D03*
Y1369889D03*
X92530Y1374881D03*
Y1369795D03*
Y1381801D03*
X87574Y1399079D03*
Y1393993D03*
Y1386793D03*
X99814Y1399079D03*
Y1394087D03*
Y1386793D03*
X92530Y1393993D03*
Y1399079D03*
Y1386793D03*
X87574Y1410991D03*
Y1405999D03*
X99814Y1410991D03*
Y1405999D03*
X92530Y1410991D03*
Y1405999D03*
X92000Y1644980D03*
X107364Y113394D03*
Y110394D03*
X110013Y110784D03*
X110152Y130898D03*
X117607Y133298D03*
X111754Y134579D03*
X107540Y172665D03*
Y180665D03*
X107572Y200864D03*
Y212864D03*
Y216864D03*
Y221864D03*
X109329Y252371D03*
X112474Y716315D03*
X114397Y727974D03*
X113601Y881266D03*
X107641Y865224D03*
X103836Y997860D03*
X111836D03*
X114770Y1009354D03*
X107836Y997860D03*
X115836D03*
X108933Y1102091D03*
X112433D03*
X103124D03*
X112433Y1114691D03*
X103124D03*
X108933D03*
Y1127291D03*
X112433D03*
X103124D03*
X112433Y1139891D03*
X103124Y1152491D03*
X108933D03*
X112433D03*
X108933Y1165091D03*
X112433D03*
X103184Y1177691D03*
X108933D03*
X112433D03*
X109415Y1202103D03*
X112795Y1223749D03*
X104770Y1350683D03*
Y1345691D03*
X112054D03*
Y1350683D03*
X117010Y1345691D03*
Y1350683D03*
X104770Y1362595D03*
Y1357603D03*
X112054Y1362595D03*
Y1357603D03*
X117010Y1362595D03*
Y1357603D03*
Y1369889D03*
Y1374881D03*
Y1381801D03*
X104770D03*
Y1374881D03*
Y1369889D03*
X112054D03*
Y1374881D03*
Y1381801D03*
X104770Y1399079D03*
Y1394087D03*
Y1386793D03*
X112054Y1399079D03*
Y1394087D03*
Y1386793D03*
X117010Y1394087D03*
Y1399079D03*
Y1386793D03*
X104770Y1410991D03*
Y1405999D03*
X112054Y1410991D03*
Y1405999D03*
X117010Y1410991D03*
Y1405999D03*
X107669Y1456451D03*
Y1465913D03*
X116330Y1465513D03*
X107669Y1461182D03*
X116330Y1460782D03*
X107669Y1481267D03*
X116330Y1480867D03*
X107669Y1476536D03*
X116330Y1476136D03*
Y1470244D03*
X107669Y1471805D03*
X116330Y1491490D03*
Y1485598D03*
X107669Y1487159D03*
Y1496621D03*
X116330Y1496221D03*
X107669Y1491890D03*
X116330Y1506845D03*
Y1500952D03*
X107669Y1502514D03*
X116330Y1511576D03*
X107669Y1511976D03*
Y1507245D03*
X116330Y1516307D03*
X107669Y1563544D03*
X116330Y1563144D03*
X107669Y1558813D03*
Y1568275D03*
X116330Y1567875D03*
X107669Y1578898D03*
X116330Y1578498D03*
Y1572606D03*
X107669Y1574167D03*
Y1583629D03*
X116330Y1583229D03*
X107669Y1594253D03*
X116330Y1593853D03*
Y1587960D03*
X107669Y1589522D03*
Y1609607D03*
X116330Y1609207D03*
X107669Y1598984D03*
X116330Y1598584D03*
Y1603315D03*
X107669Y1604876D03*
X116330Y1613938D03*
Y1618669D03*
X107669Y1614338D03*
X112000Y1644980D03*
X128350Y116497D03*
X133150D03*
X124606Y106495D03*
X125599Y109172D03*
X122599D03*
X133150Y123584D03*
X128350D03*
X133150Y130670D03*
X128350D03*
Y137757D03*
X133150D03*
X126246Y141228D03*
X124340Y146012D03*
X129134Y150847D03*
X131102Y247292D03*
X123811Y253198D03*
X125125Y362403D03*
X118122Y747565D03*
X122887Y884000D03*
X127067Y891495D03*
X124079Y1009354D03*
X119836Y997860D03*
X131836D03*
X127836D03*
X123836D03*
X120579Y1009354D03*
Y1021954D03*
X124079D03*
X133870Y1105091D03*
Y1117691D03*
Y1130291D03*
Y1142891D03*
Y1155491D03*
Y1168091D03*
X121211Y1215195D03*
X126937Y1209607D03*
X124294Y1350683D03*
Y1345691D03*
X129250Y1350683D03*
Y1345691D03*
X124294Y1362595D03*
Y1357603D03*
X129250D03*
Y1362595D03*
X124294Y1374881D03*
Y1369889D03*
Y1381801D03*
X129250Y1374881D03*
Y1369889D03*
Y1381801D03*
X124294Y1394087D03*
Y1399079D03*
Y1386793D03*
X129250Y1394087D03*
Y1399079D03*
Y1386793D03*
X124294Y1405999D03*
Y1410991D03*
X129250Y1405999D03*
Y1410991D03*
X124992Y1465913D03*
Y1456451D03*
Y1461182D03*
X133653Y1465513D03*
Y1460782D03*
X124992Y1471805D03*
Y1476536D03*
Y1481267D03*
X133653Y1476136D03*
Y1470244D03*
Y1480867D03*
Y1496221D03*
X124992Y1487159D03*
Y1491890D03*
Y1496621D03*
X133653Y1491490D03*
Y1485598D03*
Y1506845D03*
Y1500952D03*
Y1511576D03*
X124992Y1511976D03*
Y1507245D03*
Y1502514D03*
X133653Y1516307D03*
X124992Y1558813D03*
Y1563544D03*
X133653Y1563144D03*
Y1567875D03*
X124992Y1574167D03*
Y1578898D03*
X133653Y1578498D03*
Y1572606D03*
X124992Y1568275D03*
Y1589522D03*
Y1594253D03*
X133653Y1593853D03*
Y1587960D03*
X124992Y1583629D03*
X133653Y1583229D03*
X124992Y1609607D03*
Y1604876D03*
Y1598984D03*
X133653Y1609207D03*
Y1598584D03*
Y1603315D03*
X124992Y1614338D03*
X133653Y1613938D03*
Y1618669D03*
X132000Y1644980D03*
X148812Y80384D03*
Y82984D03*
Y75184D03*
Y77784D03*
Y85584D03*
X135650Y109410D03*
X140350Y116496D03*
Y109410D03*
Y102323D03*
X135650Y116497D03*
Y123583D03*
Y130670D03*
X140350D03*
Y123583D03*
Y137756D03*
X136604Y450750D03*
X140703Y536382D03*
X145670Y597580D03*
X147893Y599588D03*
X147155Y589556D03*
X147094Y592354D03*
X145609Y594668D03*
X147896Y596095D03*
X147925Y615600D03*
X147893Y607588D03*
X139836Y997860D03*
X147836D03*
X143836D03*
X135836D03*
X145516Y1024954D03*
Y1012354D03*
X148534Y1046476D03*
X134457Y1180654D03*
X141490Y1345691D03*
Y1350683D03*
X136534D03*
Y1345691D03*
X148774Y1350683D03*
Y1345691D03*
X141490Y1357603D03*
Y1362595D03*
X136534D03*
Y1357603D03*
X148774D03*
Y1362595D03*
X141490Y1369889D03*
Y1374881D03*
Y1381801D03*
X136534Y1369889D03*
Y1381801D03*
Y1374881D03*
X148774Y1369889D03*
Y1381801D03*
Y1374881D03*
X141490Y1386793D03*
Y1394087D03*
Y1399079D03*
X136534D03*
Y1394087D03*
Y1386793D03*
X148774Y1394087D03*
Y1399079D03*
Y1386793D03*
X141490Y1405999D03*
Y1410991D03*
X136534D03*
Y1405999D03*
X148774D03*
Y1410991D03*
X142315Y1456451D03*
Y1461182D03*
Y1465913D03*
Y1471805D03*
Y1476536D03*
Y1481267D03*
Y1487159D03*
Y1491890D03*
Y1496621D03*
Y1507245D03*
Y1502514D03*
Y1511976D03*
Y1558813D03*
Y1563544D03*
Y1574167D03*
Y1578898D03*
Y1568275D03*
Y1589522D03*
Y1594253D03*
Y1583629D03*
Y1609607D03*
Y1604876D03*
Y1598984D03*
Y1614338D03*
X151366Y92849D03*
X158460Y116496D03*
X158326Y103037D03*
X158460Y109410D03*
Y130670D03*
Y123583D03*
X155051Y137756D03*
X163141Y293796D03*
X160641D03*
X166528Y312392D03*
X157375Y555234D03*
X157090Y562003D03*
X152386Y634946D03*
X151836Y997860D03*
X159836D03*
X164028Y1041468D03*
X155513Y1065148D03*
X161014Y1345691D03*
Y1350683D03*
X153730Y1345691D03*
Y1350683D03*
X165970Y1345691D03*
Y1350683D03*
X161014Y1362595D03*
Y1357603D03*
X153730Y1362595D03*
Y1357603D03*
X165970Y1362595D03*
Y1357603D03*
X161014Y1381801D03*
Y1369889D03*
Y1374881D03*
X153730Y1369889D03*
Y1381801D03*
Y1374881D03*
X165970D03*
Y1381801D03*
Y1369889D03*
X161014Y1394087D03*
Y1386793D03*
X153730Y1394087D03*
Y1386793D03*
X165970Y1394087D03*
Y1386793D03*
X161014Y1399079D03*
X153730D03*
X165970D03*
X161014Y1410991D03*
Y1405999D03*
X153730D03*
Y1410991D03*
X165970D03*
Y1405999D03*
X159637Y1461182D03*
X150976Y1465513D03*
Y1460782D03*
X159637Y1465913D03*
Y1456451D03*
X150976Y1476136D03*
Y1470244D03*
Y1480867D03*
X159637Y1471805D03*
Y1476536D03*
Y1481267D03*
Y1496621D03*
X150976Y1491490D03*
Y1485598D03*
Y1496221D03*
X159637Y1487159D03*
Y1491890D03*
X150976Y1500952D03*
Y1511576D03*
X159637Y1507245D03*
Y1502514D03*
Y1511976D03*
X150976Y1506845D03*
Y1516307D03*
X159637Y1558813D03*
Y1563544D03*
X150976Y1563144D03*
X159637Y1578898D03*
X150976Y1567875D03*
Y1578498D03*
Y1572606D03*
X159637Y1568275D03*
Y1574167D03*
X150976Y1583229D03*
Y1593853D03*
Y1587960D03*
X159637Y1583629D03*
Y1589522D03*
Y1594253D03*
X150976Y1609207D03*
Y1598584D03*
Y1603315D03*
X159637Y1609607D03*
Y1604876D03*
Y1598984D03*
X150976Y1613938D03*
Y1618669D03*
X159637Y1614338D03*
X152000Y1644980D03*
X179743Y94017D03*
X175743D03*
X171743D03*
X175871Y110445D03*
X180863Y115401D03*
Y110445D03*
X175871Y115401D03*
X180863Y129574D03*
Y124618D03*
X175871Y129574D03*
Y124618D03*
X173784Y151540D03*
X177434Y191941D03*
X177301Y188727D03*
X171258Y226141D03*
X174058D03*
X179128Y256535D03*
X173955Y285690D03*
Y288190D03*
X171155Y285690D03*
X168655Y288190D03*
X171155D03*
X168655Y285690D03*
X182181Y290755D03*
X178181D03*
X177369Y389154D03*
Y396240D03*
Y403327D03*
Y410413D03*
Y417500D03*
Y424587D03*
Y431673D03*
Y438760D03*
Y445847D03*
Y467539D03*
Y474626D03*
Y488799D03*
Y481713D03*
Y495886D03*
Y511673D03*
Y518760D03*
Y525847D03*
Y532933D03*
Y540020D03*
Y547106D03*
X176650Y602197D03*
X177114Y595108D03*
X173254Y1345691D03*
Y1350683D03*
X178210Y1345691D03*
Y1350683D03*
X173254Y1362595D03*
Y1357603D03*
X178210D03*
Y1362595D03*
X173254Y1374881D03*
Y1369889D03*
Y1381801D03*
X178210Y1374881D03*
Y1369889D03*
Y1381801D03*
X173254Y1394087D03*
Y1386793D03*
X178210Y1394087D03*
Y1386793D03*
X173254Y1399079D03*
X178210D03*
X173254Y1405999D03*
Y1410991D03*
X178210Y1405999D03*
Y1410991D03*
X168299Y1465513D03*
Y1460782D03*
X176960Y1465914D03*
Y1456452D03*
Y1461183D03*
X168299Y1476136D03*
Y1470244D03*
Y1480867D03*
X176960Y1476537D03*
Y1471806D03*
Y1481268D03*
X168299Y1491490D03*
Y1485598D03*
Y1496221D03*
X176960Y1491891D03*
Y1487160D03*
Y1496622D03*
Y1507246D03*
Y1502515D03*
X168299Y1506845D03*
Y1500952D03*
Y1511576D03*
X176960Y1511977D03*
X168299Y1516307D03*
Y1563144D03*
X176960Y1563544D03*
Y1558813D03*
Y1568275D03*
X168299Y1578498D03*
Y1572606D03*
Y1567875D03*
Y1583229D03*
X176960Y1583629D03*
X168299Y1593853D03*
Y1587960D03*
X176960Y1594253D03*
Y1589522D03*
X168299Y1609207D03*
Y1598584D03*
Y1603315D03*
X176960Y1609607D03*
Y1598984D03*
Y1604876D03*
X168299Y1613938D03*
Y1618669D03*
X176960Y1614338D03*
X172000Y1644980D03*
X188820Y80140D03*
Y84140D03*
Y76140D03*
X183752Y94017D03*
X186273Y117557D03*
X191265D03*
X186273Y131731D03*
Y122513D03*
X191265D03*
Y131731D03*
X189364Y146461D03*
X186273Y136687D03*
X191265D03*
X188266Y152367D03*
X194649Y180527D03*
X189966Y180572D03*
X198372Y192421D03*
X189966Y185165D03*
X194604Y185121D03*
X183934Y184619D03*
X185914Y206760D03*
X187128Y256535D03*
X188158Y279208D03*
X192262Y281307D03*
X186181Y290755D03*
X191988Y389154D03*
X190518Y396240D03*
X194603Y422864D03*
X195295Y414823D03*
X194673Y429832D03*
X194278Y436447D03*
X196313Y447953D03*
X195480Y467539D03*
X194222Y472772D03*
X194956Y487711D03*
X195069Y479104D03*
X195480Y495886D03*
X190829Y516841D03*
X194080Y510565D03*
X185654Y552872D03*
X185776Y550123D03*
X185099Y562443D03*
X186867Y560675D03*
X187408Y572334D03*
X185640Y574102D03*
X193723Y656942D03*
X185494Y1345597D03*
Y1350683D03*
X190450Y1345597D03*
Y1350683D03*
X197734Y1345691D03*
Y1350683D03*
X185494Y1362595D03*
Y1357603D03*
X197734Y1362595D03*
Y1357603D03*
X190450Y1362595D03*
Y1357603D03*
X185494Y1374881D03*
Y1381801D03*
Y1369889D03*
X197734D03*
Y1381801D03*
Y1374881D03*
X190450Y1369889D03*
Y1374881D03*
Y1381801D03*
X185494Y1393993D03*
Y1386793D03*
X190450Y1393993D03*
Y1386793D03*
X197734Y1394087D03*
Y1386793D03*
X185494Y1399079D03*
X190450D03*
X197734D03*
X185494Y1410991D03*
Y1405999D03*
X190450Y1410991D03*
Y1405999D03*
X197734D03*
Y1410991D03*
X185622Y1465513D03*
Y1460782D03*
Y1480868D03*
Y1476137D03*
Y1470244D03*
Y1485599D03*
X192000Y1644980D03*
X211262Y60922D03*
X206398Y55513D03*
X208463Y96472D03*
X202195Y117261D03*
X209726Y113394D03*
Y110394D03*
X212375Y110784D03*
X211969Y133298D03*
X214116Y134579D03*
X209902Y172665D03*
Y180665D03*
X209934Y200864D03*
Y212864D03*
Y216864D03*
Y221864D03*
X211691Y252371D03*
X215380Y389153D03*
X210580D03*
X215380Y396240D03*
X208080Y403327D03*
X215380Y403326D03*
X210580D03*
X208080Y410413D03*
X210580D03*
X215380D03*
X208080Y396240D03*
X210580D03*
X208080Y417500D03*
X215380Y417499D03*
X210580D03*
X208080Y424586D03*
X210580D03*
X215380D03*
X208080Y431673D03*
Y438760D03*
X210580D03*
X215380D03*
Y431673D03*
X210580D03*
X208080Y445847D03*
X215380Y467539D03*
X210580D03*
X208080Y474626D03*
X210580D03*
X215380D03*
Y488799D03*
X208080D03*
X210580D03*
Y481712D03*
X208080D03*
X215380D03*
X208080Y495886D03*
X215380Y518760D03*
X210580D03*
X208080D03*
X210580Y511673D03*
X215380D03*
X210580Y532933D03*
X208080D03*
Y540020D03*
Y525846D03*
X210580D03*
X215380D03*
Y532933D03*
X212460Y560500D03*
X209429Y625300D03*
X202690Y1345597D03*
Y1350683D03*
Y1362595D03*
Y1357603D03*
Y1369889D03*
Y1381801D03*
Y1374881D03*
Y1394087D03*
Y1386793D03*
Y1399079D03*
Y1405999D03*
Y1410991D03*
X211473Y1446675D03*
X213296Y1438215D03*
X211473Y1451631D03*
Y1462631D03*
Y1457675D03*
X224961Y109172D03*
X226968Y106495D03*
X230712Y116497D03*
X227961Y109172D03*
X230712Y123584D03*
Y130670D03*
X219969Y133298D03*
X228608Y141228D03*
X230712Y137757D03*
X226702Y146012D03*
X231496Y150847D03*
X226173Y253198D03*
X228760Y316122D03*
X223925Y543925D03*
X224500Y555000D03*
X222646Y607542D03*
X217945Y1423924D03*
X217799Y1433684D03*
X216465Y1446675D03*
X222253Y1438483D03*
X216465Y1451631D03*
Y1462631D03*
Y1457675D03*
X229260Y1469587D03*
X218171Y1474460D03*
X224176Y1492816D03*
X223235Y1506770D03*
X222908Y1502028D03*
X226957Y1510442D03*
X216342Y1515642D03*
X217519Y1537172D03*
X242712Y116496D03*
Y109410D03*
Y102323D03*
X238012Y116497D03*
X235512D03*
X238012Y109410D03*
Y123583D03*
Y130670D03*
X235512D03*
X242712D03*
Y123583D03*
X235512Y123584D03*
Y137757D03*
X242712Y137756D03*
X233464Y247292D03*
X236349Y339428D03*
X247333Y599506D03*
X241967Y616063D03*
X243078Y636486D03*
X240249Y628328D03*
X241084Y638243D03*
X246583Y665140D03*
X241850Y678462D03*
X247600Y848500D03*
X240845Y1345691D03*
Y1350683D03*
X245801Y1345691D03*
Y1350683D03*
X240845Y1357603D03*
Y1362595D03*
X245801Y1357603D03*
Y1362595D03*
X240845Y1381801D03*
Y1374881D03*
Y1369889D03*
X245801Y1381801D03*
Y1374881D03*
Y1369889D03*
X240845Y1386793D03*
X245801D03*
X232675Y1466801D03*
X240466Y1503857D03*
X243268Y1501903D03*
X237700Y1531600D03*
X251174Y77784D03*
Y80384D03*
Y82984D03*
Y75184D03*
Y85584D03*
X253728Y92849D03*
X260688Y103037D03*
X260822Y116496D03*
Y109410D03*
Y130670D03*
Y123583D03*
X257413Y137756D03*
X263003Y293796D03*
X257226Y312081D03*
X265011Y403307D03*
X255000Y427017D03*
X254692Y431029D03*
X253758Y435029D03*
X254678Y449873D03*
X261605Y465492D03*
Y472579D03*
X259105D03*
X254305D03*
X261605Y486752D03*
X254305D03*
X259105Y479666D03*
X261605D03*
X254305D03*
X259105Y486752D03*
X254305Y493839D03*
X259105D03*
X261605Y516713D03*
X259105D03*
Y523800D03*
X261605D03*
X254305D03*
Y516713D03*
X261605Y509626D03*
Y530886D03*
X259105D03*
Y537973D03*
X254305Y530886D03*
Y537973D03*
Y566752D03*
X261605Y559665D03*
Y566752D03*
X259105D03*
X261605Y588012D03*
X259105Y588013D03*
X254305Y573839D03*
X261605D03*
X259105D03*
X261605Y580926D03*
X259105D03*
X254305D03*
Y588013D03*
X259105Y602186D03*
X254305D03*
Y595099D03*
X259105D03*
X261605D03*
Y602185D03*
X254305Y609272D03*
X259105D03*
X261605D03*
X259105Y616359D03*
X254305D03*
X248984Y638125D03*
X258867Y680499D03*
X258041Y1350683D03*
Y1345691D03*
X253085Y1350683D03*
Y1345691D03*
X258041Y1362595D03*
X253085D03*
X258041Y1357603D03*
X253085D03*
X258041Y1381801D03*
Y1369795D03*
Y1374881D03*
X253085Y1381801D03*
Y1369795D03*
Y1374881D03*
Y1393993D03*
Y1399079D03*
X258041Y1386793D03*
Y1399079D03*
Y1393993D03*
X253085Y1386793D03*
X258041Y1405999D03*
Y1410991D03*
X253085Y1405999D03*
Y1410991D03*
X248042Y1532900D03*
X274105Y94017D03*
X278105D03*
X278233Y115401D03*
Y110445D03*
Y129574D03*
Y124618D03*
X276146Y151540D03*
X279796Y191941D03*
X279663Y188727D03*
X276420Y226141D03*
X273620D03*
X276317Y288190D03*
X273517Y285690D03*
X271017Y288190D03*
X273517D03*
X271017Y285690D03*
X265503Y293796D03*
X276317Y285690D03*
X274425Y390500D03*
X265011Y410394D03*
X266405Y451319D03*
Y458406D03*
Y465492D03*
X266229Y462264D03*
X266405Y472579D03*
Y479665D03*
Y486752D03*
Y493839D03*
Y523799D03*
Y516713D03*
Y509626D03*
Y530886D03*
Y537973D03*
Y566752D03*
Y559665D03*
Y580926D03*
Y588012D03*
Y573839D03*
Y602185D03*
Y595099D03*
Y609272D03*
Y616358D03*
X269700Y884600D03*
X269900Y914200D03*
X270100Y946500D03*
X277565Y1350683D03*
Y1345691D03*
X265325D03*
Y1350683D03*
X270281Y1345691D03*
Y1350683D03*
X277565Y1362595D03*
X265325D03*
X270281D03*
X277565Y1357603D03*
X265325D03*
X270281D03*
X277565Y1381801D03*
Y1374881D03*
Y1369889D03*
X265325D03*
Y1374881D03*
Y1381801D03*
X270281Y1369889D03*
Y1374881D03*
Y1381801D03*
X277565Y1386793D03*
Y1394087D03*
Y1399079D03*
X265325Y1394087D03*
Y1399079D03*
Y1386793D03*
X270281Y1399079D03*
Y1394087D03*
Y1386793D03*
X265325Y1405999D03*
Y1410991D03*
X270281Y1405999D03*
Y1410991D03*
X277565Y1405999D03*
Y1410991D03*
X272000Y1644980D03*
X291182Y84140D03*
Y80140D03*
Y76140D03*
X282105Y94017D03*
X286114D03*
X288635Y117557D03*
X283225Y115401D03*
Y110445D03*
X293627Y117557D03*
X288635Y131731D03*
Y122513D03*
X283225Y129574D03*
Y124618D03*
X293627Y122513D03*
Y131731D03*
X291726Y146461D03*
X293627Y136687D03*
X288635D03*
X290628Y152367D03*
X292328Y180572D03*
Y185165D03*
X286296Y184619D03*
X288276Y206760D03*
X281490Y256535D03*
X289490D03*
X290520Y279208D03*
X294624Y281307D03*
X284543Y290755D03*
X280543D03*
X288543D03*
X284075Y381500D03*
X284482Y460250D03*
X284516Y465492D03*
X282247Y470136D03*
X284516Y472579D03*
Y479665D03*
Y486752D03*
Y493839D03*
Y516713D03*
Y509626D03*
X283377Y532756D03*
X283456Y525483D03*
X280976Y537973D03*
X284516Y559665D03*
Y566752D03*
X284366Y579978D03*
X284516Y573839D03*
X284580Y608117D03*
X282521Y1345691D03*
X289805Y1350683D03*
Y1345691D03*
X294761Y1350683D03*
Y1345691D03*
X282521Y1350683D03*
X289805Y1362595D03*
X294761D03*
X282521D03*
X289805Y1357603D03*
X294761D03*
X282521D03*
X289805Y1374881D03*
Y1369889D03*
Y1381801D03*
X294761Y1374881D03*
Y1369889D03*
Y1381801D03*
X282521D03*
Y1374881D03*
Y1369889D03*
X289805Y1394087D03*
Y1399079D03*
Y1386793D03*
X294761Y1394087D03*
Y1399079D03*
Y1386793D03*
X282521D03*
Y1399079D03*
Y1394087D03*
X289805Y1405999D03*
Y1410991D03*
X294761Y1405999D03*
Y1410991D03*
X282521Y1405999D03*
Y1410991D03*
X280897Y1465913D03*
X289558Y1465513D03*
X280897Y1461182D03*
X289558Y1460782D03*
X280897Y1456451D03*
X289558Y1480867D03*
X280897Y1476536D03*
X289558Y1476136D03*
Y1470244D03*
X280897Y1471805D03*
Y1481267D03*
Y1491890D03*
X289558Y1491490D03*
Y1485598D03*
X280897Y1487159D03*
Y1496621D03*
X289558Y1496221D03*
X280897Y1507245D03*
X289558Y1506845D03*
Y1500952D03*
X280897Y1502514D03*
X289558Y1511576D03*
X280897Y1511976D03*
X289558Y1516307D03*
X280897Y1563544D03*
X289558Y1563144D03*
X280897Y1558813D03*
Y1574167D03*
Y1568275D03*
X289558Y1567875D03*
X280897Y1578898D03*
X289558Y1578498D03*
Y1572606D03*
Y1593853D03*
Y1587960D03*
X280897Y1589522D03*
Y1583629D03*
X289558Y1583229D03*
X280897Y1594253D03*
Y1609607D03*
X289558Y1609207D03*
X280897Y1598984D03*
X289558Y1598584D03*
Y1603315D03*
X280897Y1604876D03*
Y1614338D03*
X289558Y1613938D03*
Y1618669D03*
X292000Y1644980D03*
X308760Y55513D03*
X310882Y96613D03*
X305953Y91951D03*
X312088Y113394D03*
X304557Y117261D03*
X297011Y180527D03*
X312264Y172665D03*
Y180665D03*
X299759Y190285D03*
X296966Y185121D03*
X312296Y212864D03*
Y200864D03*
Y221864D03*
Y216864D03*
X306812Y342319D03*
X309258Y389912D03*
Y393924D03*
Y385912D03*
Y409924D03*
Y405924D03*
Y401924D03*
X306673Y418838D03*
X298507Y445908D03*
X302457Y445787D03*
X302045Y1345691D03*
Y1350683D03*
X307001D03*
Y1345691D03*
X302045Y1362595D03*
X307001D03*
X302045Y1357603D03*
X307001D03*
X302045Y1374881D03*
Y1381801D03*
Y1369889D03*
X307001Y1374881D03*
Y1369889D03*
Y1381801D03*
X302045Y1386793D03*
Y1394087D03*
Y1399079D03*
X307001Y1386793D03*
Y1399079D03*
Y1394087D03*
X302045Y1405999D03*
Y1410991D03*
X307001Y1405999D03*
Y1410991D03*
X298220Y1465913D03*
Y1456451D03*
Y1461182D03*
X306881Y1465513D03*
Y1460782D03*
Y1470244D03*
Y1480867D03*
X298220Y1471805D03*
Y1476536D03*
Y1481267D03*
X306881Y1476136D03*
X298220Y1487159D03*
Y1491890D03*
Y1496621D03*
X306881Y1491490D03*
Y1485598D03*
Y1496221D03*
X298220Y1507245D03*
Y1502514D03*
X306881Y1506845D03*
Y1500952D03*
Y1511576D03*
X298220Y1511976D03*
X306881Y1516307D03*
X298220Y1558813D03*
Y1563544D03*
X306881Y1563144D03*
X298220Y1568275D03*
X306881Y1567875D03*
X298220Y1574167D03*
Y1578898D03*
X306881Y1578498D03*
Y1572606D03*
X298220Y1583629D03*
X306881Y1583229D03*
X298220Y1589522D03*
Y1594253D03*
X306881Y1593853D03*
Y1587960D03*
Y1598584D03*
Y1603315D03*
X298220Y1609607D03*
Y1604876D03*
Y1598984D03*
X306881Y1609207D03*
X298220Y1614338D03*
X306881Y1613938D03*
Y1618669D03*
X312000Y1644980D03*
X313624Y60922D03*
X327323Y109172D03*
X314737Y110784D03*
X314854Y130898D03*
X322331Y133298D03*
X329064Y146012D03*
X316478Y134579D03*
X328535Y253198D03*
X314053Y252371D03*
X323882Y303839D03*
X315904Y336324D03*
X320483Y353506D03*
X319241Y1350683D03*
Y1345691D03*
X314285D03*
Y1350683D03*
X326525Y1345691D03*
Y1350683D03*
X319241Y1362595D03*
X314285D03*
X326525D03*
X319241Y1357603D03*
X314285D03*
X326525D03*
X319241Y1374881D03*
Y1381801D03*
Y1369889D03*
X314285Y1374881D03*
Y1381801D03*
Y1369889D03*
X326525Y1381801D03*
Y1369889D03*
Y1374881D03*
X319241Y1386793D03*
Y1399079D03*
Y1394087D03*
X314285Y1386793D03*
Y1399079D03*
Y1394087D03*
X326525Y1399079D03*
Y1394087D03*
Y1386793D03*
X319241Y1410991D03*
Y1405999D03*
X314285Y1410991D03*
Y1405999D03*
X326525Y1410991D03*
Y1405999D03*
X315543Y1465913D03*
Y1456451D03*
Y1461182D03*
X324204Y1465513D03*
Y1460782D03*
Y1480867D03*
X315543Y1471805D03*
Y1476536D03*
Y1481267D03*
X324204Y1476136D03*
Y1470244D03*
X315543Y1487159D03*
Y1491890D03*
Y1496621D03*
X324204Y1491490D03*
Y1485598D03*
Y1496221D03*
Y1500952D03*
Y1511576D03*
X315543Y1507245D03*
Y1502514D03*
Y1511976D03*
X324204Y1506845D03*
Y1516307D03*
X315543Y1558813D03*
Y1563544D03*
X324204Y1563144D03*
X315543Y1574167D03*
Y1578898D03*
X324204Y1567875D03*
Y1578498D03*
Y1572606D03*
X315543Y1568275D03*
Y1583629D03*
Y1589522D03*
Y1594253D03*
X324204Y1583229D03*
Y1593853D03*
Y1587960D03*
X315543Y1609607D03*
Y1604876D03*
Y1598984D03*
X324204Y1609207D03*
Y1598584D03*
Y1603315D03*
X315543Y1614338D03*
X324204Y1613938D03*
Y1618669D03*
X329330Y106495D03*
X345074Y116496D03*
X337874Y116497D03*
X340374D03*
X345074Y109410D03*
Y102323D03*
X340374Y109410D03*
X333074Y116497D03*
X330323Y109172D03*
X337874Y130670D03*
X345074D03*
Y123583D03*
X340374D03*
X337874Y123584D03*
X333074D03*
Y130670D03*
X340374D03*
X333074Y137757D03*
X337874D03*
X330970Y141228D03*
X345074Y137756D03*
X333858Y150847D03*
X335826Y247292D03*
X338358Y554861D03*
X337564Y1018294D03*
X337629Y1186071D03*
X336901Y1196407D03*
X338765Y1350683D03*
Y1345691D03*
X331481D03*
Y1350683D03*
X343721Y1345691D03*
Y1350683D03*
X331481Y1362595D03*
X343721D03*
X338765D03*
X331481Y1357603D03*
X343721D03*
X338765D03*
X331481Y1374881D03*
Y1381801D03*
Y1369889D03*
X343721Y1381801D03*
Y1369889D03*
Y1374881D03*
X338765Y1381801D03*
Y1369889D03*
Y1374881D03*
X331481Y1399079D03*
Y1394087D03*
Y1386793D03*
X343721D03*
Y1394087D03*
Y1399079D03*
X338765Y1386793D03*
Y1394087D03*
Y1399079D03*
X331481Y1410991D03*
Y1405999D03*
X343721Y1410991D03*
Y1405999D03*
X338765Y1410991D03*
Y1405999D03*
X341527Y1460782D03*
X332865Y1465913D03*
Y1456451D03*
Y1461182D03*
X341527Y1465513D03*
Y1476136D03*
Y1470244D03*
Y1480867D03*
X332865Y1471805D03*
Y1476536D03*
Y1481267D03*
X341527Y1491490D03*
Y1485598D03*
Y1496221D03*
X332865Y1487159D03*
Y1491890D03*
Y1496621D03*
Y1511976D03*
X341527Y1506845D03*
Y1500952D03*
Y1511576D03*
X332865Y1507245D03*
Y1502514D03*
X341527Y1516307D03*
X332865Y1558813D03*
Y1563544D03*
X341527Y1563144D03*
X332865Y1578898D03*
X341527Y1567875D03*
Y1578498D03*
Y1572606D03*
X332865Y1568275D03*
Y1574167D03*
Y1583629D03*
Y1589522D03*
Y1594253D03*
X341527Y1583229D03*
Y1593853D03*
Y1587960D03*
X332865Y1598984D03*
X341527Y1609207D03*
Y1598584D03*
Y1603315D03*
X332865Y1609607D03*
Y1604876D03*
X341527Y1613938D03*
Y1618669D03*
X332865Y1614338D03*
X332000Y1644980D03*
X353536Y82984D03*
Y80384D03*
Y77784D03*
Y75184D03*
X356090Y92849D03*
X353536Y85584D03*
X359525Y137756D03*
X356423Y301288D03*
X348375Y322284D03*
X348968Y333138D03*
X359278Y491870D03*
X356778D03*
X358096Y867459D03*
X358086Y884616D03*
X357962Y898800D03*
X358024Y912085D03*
X358085Y923327D03*
X355929Y1132042D03*
X351563Y1132410D03*
X349700Y1148000D03*
X357947Y1159455D03*
X352536Y1160168D03*
X357297Y1192709D03*
X360659Y1209789D03*
X355961Y1350683D03*
X351005Y1345597D03*
Y1350683D03*
X355961Y1345597D03*
X351005Y1362595D03*
X355961D03*
X351005Y1357603D03*
X355961D03*
X351005Y1374881D03*
Y1381801D03*
Y1369889D03*
X355961Y1381801D03*
Y1374881D03*
Y1369889D03*
X351005Y1399079D03*
Y1393993D03*
Y1386793D03*
X355961D03*
Y1399079D03*
Y1393993D03*
X351005Y1410991D03*
Y1405999D03*
X355961D03*
Y1410991D03*
X350188Y1491891D03*
Y1487160D03*
Y1496622D03*
Y1507246D03*
Y1502515D03*
Y1511977D03*
X358850Y1511576D03*
Y1506845D03*
Y1516307D03*
X350188Y1563544D03*
Y1558813D03*
Y1568275D03*
Y1578898D03*
Y1574167D03*
Y1583629D03*
Y1594253D03*
Y1589522D03*
Y1604876D03*
Y1609607D03*
Y1598984D03*
Y1614338D03*
X352000Y1644980D03*
X376467Y94017D03*
X363050Y103037D03*
X363184Y116496D03*
Y109410D03*
Y130670D03*
Y123583D03*
X375982Y226141D03*
X378782D03*
X365365Y293796D03*
X367865D03*
X373379Y288190D03*
X375879Y285690D03*
X373379D03*
X375879Y288190D03*
X368057Y354184D03*
X364933Y374232D03*
X373264Y370010D03*
X366443Y472189D03*
X373504Y517954D03*
X375040Y932959D03*
X371424Y937185D03*
X367944Y946082D03*
X368657Y1146937D03*
X366133Y1162817D03*
X368661Y1182649D03*
X368917Y1195419D03*
X365029Y1214158D03*
X362735Y1211864D03*
X369839Y1218940D03*
X363245Y1345691D03*
Y1350683D03*
X368201Y1345691D03*
Y1350683D03*
X363245Y1362595D03*
X368201D03*
X363245Y1357603D03*
X368201D03*
X363245Y1369889D03*
Y1381801D03*
Y1374881D03*
X368201D03*
Y1381801D03*
Y1369889D03*
X363245Y1399079D03*
Y1394087D03*
Y1386793D03*
X368201D03*
Y1394087D03*
Y1399079D03*
X363245Y1405999D03*
Y1410991D03*
X368201D03*
Y1405999D03*
X372000Y1644980D03*
X393544Y76140D03*
Y84140D03*
Y80140D03*
X384467Y94017D03*
X388476D03*
X380467D03*
X390997Y117557D03*
X385587Y115401D03*
X380595D03*
X385587Y110445D03*
X380595D03*
X390997Y131731D03*
Y122513D03*
X385587Y129574D03*
X380595D03*
X385587Y124618D03*
X380595D03*
X390997Y136687D03*
X382158Y191941D03*
X388658Y184619D03*
X382025Y188727D03*
X390638Y206760D03*
X391852Y256535D03*
X383852D03*
X392882Y279208D03*
X378679Y285690D03*
Y288190D03*
X386905Y290755D03*
X382905D03*
X390905D03*
X392387Y337599D03*
Y342555D03*
X392444Y401949D03*
X393893Y413611D03*
X393833Y423944D03*
X393652Y482382D03*
X393746Y478382D03*
X388593Y664232D03*
X386350Y693559D03*
X391478Y690675D03*
X391614Y938651D03*
X381377Y1003008D03*
X381045Y1009444D03*
X391284Y1307238D03*
X394000Y1508100D03*
X382017Y1555700D03*
Y1547700D03*
Y1551700D03*
X392000Y1644980D03*
X408493Y117577D03*
X395989Y117557D03*
Y131731D03*
Y122513D03*
Y136687D03*
X399373Y180527D03*
X394690Y180572D03*
X403096Y192421D03*
X394690Y185165D03*
X399328Y185121D03*
X396986Y281307D03*
X409484Y314921D03*
X398951Y333711D03*
X397374Y344439D03*
X407493Y354142D03*
X394237Y370899D03*
X394944Y398949D03*
X399518Y402642D03*
X402018D03*
X396633Y423944D03*
X396693Y413611D03*
X399193D03*
X401693D03*
X401633Y423944D03*
X399133D03*
X409284Y741316D03*
X401121Y936686D03*
X409121Y939186D03*
X401121D03*
X409121Y936686D03*
X409231Y1123101D03*
X406105Y1139435D03*
X410131Y1129301D03*
X407631D03*
X409231Y1125801D03*
X406105Y1131935D03*
Y1134435D03*
Y1136935D03*
Y1141935D03*
Y1146935D03*
Y1144435D03*
X403263Y1152684D03*
X406319Y1204405D03*
Y1206905D03*
Y1211905D03*
Y1209405D03*
X397695Y1287071D03*
X399716Y1295198D03*
X408523Y1332967D03*
X404657D03*
X408937Y1351568D03*
X403981D03*
X401990Y1446807D03*
X399731Y1442755D03*
X397245Y1511640D03*
X404053Y1513673D03*
X397220Y1521207D03*
X409461Y1569560D03*
X405461D03*
X426147Y151540D03*
X414626Y180665D03*
Y172665D03*
X414658Y212864D03*
Y200864D03*
Y216864D03*
Y221864D03*
X422873Y309966D03*
X419955Y306966D03*
X414999D03*
X411984Y314921D03*
X421231Y338523D03*
Y331255D03*
Y345776D03*
X413432Y346797D03*
X416318Y367903D03*
X424479Y367859D03*
X418754Y468607D03*
X418226Y653288D03*
Y646480D03*
Y648980D03*
Y655788D03*
X425121Y936686D03*
Y939186D03*
X417121Y936686D03*
Y939186D03*
X417677Y1052215D03*
X425175Y1098767D03*
X417171Y1098887D03*
X419987Y1098518D03*
X419731Y1123101D03*
X417231D03*
X422631Y1125801D03*
X425131Y1129301D03*
X422631D03*
X420131D03*
X417631D03*
X415131D03*
X412631D03*
X420131Y1125801D03*
X417631D03*
X425131D03*
X422495Y1152713D03*
Y1155213D03*
X412095Y1152713D03*
Y1155213D03*
X422934Y1200821D03*
Y1198321D03*
X420619Y1204617D03*
Y1207117D03*
Y1209617D03*
Y1212117D03*
X411174Y1282776D03*
X418537Y1300197D03*
X423741Y1300115D03*
X413354Y1300197D03*
X425582Y1291743D03*
X423762Y1305298D03*
X413374D03*
X418558Y1310523D03*
X413395Y1310481D03*
X423721Y1310523D03*
X425283Y1373958D03*
X411147Y1474993D03*
X419818Y1474945D03*
X415241Y1492990D03*
X415095Y1502750D03*
X411353Y1519440D03*
X419467Y1519706D03*
X420279Y1525978D03*
X410626Y1525991D03*
X413461Y1569560D03*
X412000Y1644980D03*
X441727Y146461D03*
X440629Y152367D03*
X435703Y306966D03*
X430747D03*
X427829Y309966D03*
X428459Y331255D03*
X435793D03*
X428500Y345776D03*
X435793Y345738D03*
X430439Y358115D03*
X435702Y367813D03*
X430746D03*
X427782Y464026D03*
X438396Y511493D03*
X435834Y509580D03*
X431804Y536682D03*
Y539182D03*
X441832Y626193D03*
X433206Y1055498D03*
X430706D03*
Y1057998D03*
X433206D03*
Y1060498D03*
Y1062998D03*
X430706D03*
Y1060498D03*
X441359Y1123101D03*
X438233Y1139435D03*
X441359Y1125801D03*
X439759Y1129301D03*
X442259D03*
X429331Y1136935D03*
Y1134435D03*
Y1139435D03*
Y1131935D03*
X435733D03*
Y1134435D03*
Y1136935D03*
Y1139435D03*
X438233Y1131935D03*
Y1134435D03*
Y1136935D03*
X429331Y1141935D03*
X435733D03*
Y1146935D03*
Y1144435D03*
X438233Y1141935D03*
Y1146935D03*
Y1144435D03*
X437231Y1154902D03*
Y1152402D03*
X429331Y1146935D03*
Y1144435D03*
X433249Y1204405D03*
Y1209405D03*
Y1211905D03*
Y1206905D03*
X437991Y1286544D03*
X440896Y1311366D03*
X432485Y1325784D03*
X439624Y1345691D03*
Y1350683D03*
Y1357603D03*
Y1362595D03*
Y1381801D03*
Y1369889D03*
Y1374881D03*
X436002Y1382252D03*
X439624Y1386793D03*
X437675Y1550158D03*
X429784Y1548222D03*
X432000Y1644980D03*
X458454Y328963D03*
Y324007D03*
Y339755D03*
Y344711D03*
X453463Y370694D03*
X448092Y375770D03*
X443094Y491251D03*
X455104Y536582D03*
Y539082D03*
X447279Y633881D03*
X454815Y974622D03*
X448999Y994483D03*
X456210Y1004680D03*
X452319Y1000828D03*
X449731Y1000855D03*
X453710Y1018825D03*
X443091Y1022766D03*
Y1030266D03*
X450063Y1043140D03*
X449767Y1047047D03*
X457303Y1098767D03*
X452115Y1098518D03*
X446863Y1098428D03*
X449359Y1123101D03*
X451859D03*
X457259Y1129301D03*
X449759Y1125801D03*
X452259D03*
X444759Y1129301D03*
X447259D03*
X449759D03*
X452259D03*
X454759Y1125801D03*
X457259D03*
X454759Y1129301D03*
X443223Y1155213D03*
Y1152713D03*
X452623D03*
Y1155213D03*
X447549Y1204617D03*
X449864Y1198321D03*
Y1200821D03*
X447549Y1209617D03*
Y1207117D03*
Y1212117D03*
X454120Y1269498D03*
X456213Y1286776D03*
X451304Y1293045D03*
X456820Y1345691D03*
X451864D03*
Y1350683D03*
X456820D03*
X444580Y1345691D03*
Y1350683D03*
X456820Y1362595D03*
Y1357603D03*
X451864Y1362595D03*
Y1357603D03*
X444580D03*
Y1362595D03*
X456820Y1374881D03*
X451864D03*
X444580Y1369889D03*
X456820Y1369795D03*
X451864D03*
X444580Y1374881D03*
Y1381801D03*
X456820D03*
X451864D03*
X456820Y1399079D03*
X451864Y1393993D03*
Y1399079D03*
X456820Y1393993D03*
Y1386793D03*
X451864D03*
X444580D03*
X456820Y1405999D03*
X451864D03*
Y1410991D03*
X456820D03*
X454125Y1461182D03*
Y1465913D03*
Y1471805D03*
Y1481267D03*
Y1476536D03*
Y1491890D03*
Y1487159D03*
Y1496621D03*
Y1511976D03*
Y1507245D03*
Y1502514D03*
Y1558813D03*
Y1578898D03*
Y1568275D03*
Y1563544D03*
Y1574167D03*
Y1583629D03*
Y1589522D03*
Y1594253D03*
Y1609607D03*
Y1598984D03*
Y1604876D03*
Y1614338D03*
X452000Y1644980D03*
X464738Y110784D03*
X462089Y113394D03*
X472332Y133298D03*
X464332D03*
X466479Y134579D03*
X464054Y252371D03*
X461454Y336837D03*
Y331881D03*
Y347629D03*
Y352585D03*
X466375Y366365D03*
X470389Y389553D03*
X468558Y491669D03*
Y503669D03*
Y507669D03*
Y512669D03*
X462242Y809792D03*
X475032Y843252D03*
X474678Y857919D03*
X463134Y859203D03*
X460455Y867050D03*
X475046Y885952D03*
X467494Y924532D03*
X462427Y1030218D03*
X460277Y1090268D03*
Y1093068D03*
X474818Y1123101D03*
X469192Y1131935D03*
X474818Y1125801D03*
X473218Y1129301D03*
X461459Y1136935D03*
Y1134435D03*
Y1139435D03*
Y1131935D03*
X471692Y1139435D03*
Y1136935D03*
Y1134435D03*
Y1131935D03*
X469192Y1139435D03*
Y1136935D03*
Y1134435D03*
X471692Y1146935D03*
Y1141935D03*
X469192Y1144435D03*
Y1146935D03*
Y1141935D03*
X471692Y1144435D03*
X461459D03*
X462687Y1152684D03*
X468850D03*
X461459Y1141935D03*
Y1146935D03*
X463216Y1254164D03*
Y1250760D03*
Y1244055D03*
X461613Y1286776D03*
X469060Y1345691D03*
Y1350683D03*
X464104Y1345691D03*
Y1350683D03*
X469060Y1357603D03*
Y1362595D03*
X464104D03*
Y1357603D03*
Y1381801D03*
X469060D03*
X464104Y1369889D03*
X469060D03*
X464104Y1374881D03*
X469060D03*
Y1386793D03*
X464104D03*
X469060Y1399079D03*
X464104Y1394087D03*
X469060D03*
X464104Y1399079D03*
Y1405999D03*
X469060D03*
X464104Y1410991D03*
X469060D03*
X471448Y1461182D03*
X462786Y1460782D03*
X471448Y1465913D03*
X462786Y1465513D03*
X471448Y1481267D03*
X462786Y1480867D03*
X471448Y1471805D03*
Y1476536D03*
X462786Y1476136D03*
Y1470244D03*
X471448Y1496621D03*
X462786Y1496221D03*
X471448Y1491890D03*
X462786Y1491490D03*
Y1485598D03*
X471448Y1487159D03*
Y1511976D03*
Y1502514D03*
Y1507245D03*
X462786Y1511576D03*
Y1506845D03*
Y1500952D03*
Y1516307D03*
Y1563144D03*
X471448Y1558813D03*
X462786Y1578498D03*
X471448Y1574167D03*
Y1568275D03*
Y1563544D03*
X462786Y1567875D03*
Y1572606D03*
X471448Y1578898D03*
Y1594253D03*
X462786Y1593853D03*
X471448Y1589522D03*
Y1583629D03*
X462786Y1583229D03*
Y1587960D03*
X471448Y1598984D03*
X462786Y1609207D03*
Y1598584D03*
Y1603315D03*
X471448Y1609607D03*
Y1604876D03*
Y1614338D03*
X462786Y1613938D03*
Y1618669D03*
X472000Y1644980D03*
X480324Y109172D03*
X477324D03*
X479331Y106495D03*
X483075Y116497D03*
X487875D03*
X490375Y109410D03*
Y116497D03*
X483075Y130670D03*
X487875Y123584D03*
Y130670D03*
X490375Y123583D03*
Y130670D03*
X483075Y123584D03*
X479065Y146012D03*
X480971Y141228D03*
X483075Y137757D03*
X487875D03*
X483859Y150847D03*
X485827Y247292D03*
X478536Y253198D03*
X483242Y366481D03*
X483584Y375840D03*
X483736Y371266D03*
X483541Y380306D03*
X481724Y391589D03*
Y387089D03*
X488438Y425464D03*
X482532Y418464D03*
X482484Y444517D03*
X486738Y581222D03*
X489538D03*
Y591215D03*
X486738D03*
X491340Y611091D03*
X485005Y659771D03*
X491324Y667293D03*
X485303Y681841D03*
X486246Y804497D03*
X485824Y819787D03*
X481593Y826387D03*
X491453Y834546D03*
X491527Y843206D03*
X488469Y857013D03*
X481943Y924633D03*
X488388Y938903D03*
X483636Y952152D03*
X490143Y989521D03*
X476148Y1057998D03*
Y1055498D03*
X478648D03*
Y1057998D03*
X476148Y1060498D03*
Y1062998D03*
X478648D03*
Y1060498D03*
X490762Y1098767D03*
X485574Y1098518D03*
X480322Y1098428D03*
X485318Y1123101D03*
X482818D03*
X490718Y1129301D03*
X483218Y1125801D03*
X485718D03*
X475718Y1129301D03*
X478218D03*
X480718D03*
X483218D03*
X485718D03*
X488218Y1125801D03*
X490718D03*
X488218Y1129301D03*
X477682Y1152713D03*
Y1155213D03*
X488082D03*
Y1152713D03*
X479521Y1204405D03*
Y1206905D03*
Y1211905D03*
Y1209405D03*
X488584Y1345691D03*
Y1350683D03*
X481300Y1345691D03*
X476344D03*
X481300Y1350683D03*
X476344D03*
X488584Y1357603D03*
Y1362595D03*
X481300D03*
Y1357603D03*
X476344Y1362595D03*
Y1357603D03*
X488584Y1381801D03*
X481300D03*
X488584Y1374881D03*
Y1369889D03*
X481300D03*
Y1374881D03*
X476344Y1381801D03*
Y1369889D03*
Y1374881D03*
X488584Y1386793D03*
X481300D03*
Y1399079D03*
X476344Y1394087D03*
Y1399079D03*
X488584Y1394087D03*
X481300D03*
X488584Y1399079D03*
X476344Y1386793D03*
Y1410991D03*
X481300Y1405999D03*
X476344D03*
X488584D03*
Y1410991D03*
X481300D03*
X480109Y1460782D03*
Y1465513D03*
X488771Y1465913D03*
Y1461182D03*
X480109Y1476136D03*
Y1470244D03*
X488771Y1471805D03*
Y1476536D03*
Y1481267D03*
X480109Y1480867D03*
Y1496221D03*
X488771Y1487159D03*
Y1491890D03*
X480109Y1491490D03*
Y1485598D03*
X488771Y1496621D03*
Y1511976D03*
X480109Y1511576D03*
Y1506845D03*
Y1500952D03*
X488771Y1502514D03*
Y1507245D03*
X480109Y1516307D03*
X488771Y1558813D03*
X480109Y1563144D03*
X488771Y1578898D03*
X480109Y1578498D03*
X488771Y1574167D03*
Y1568275D03*
Y1563544D03*
X480109Y1567875D03*
Y1572606D03*
X488771Y1589522D03*
Y1583629D03*
X480109Y1583229D03*
Y1587960D03*
X488771Y1594253D03*
X480109Y1593853D03*
X488771Y1609607D03*
Y1604876D03*
Y1598984D03*
X480109Y1609207D03*
Y1598584D03*
Y1603315D03*
X488771Y1614338D03*
X480109Y1613938D03*
Y1618669D03*
X503537Y77784D03*
Y75184D03*
Y80384D03*
Y82984D03*
X506091Y92849D03*
X503537Y85584D03*
X495075Y116496D03*
Y102323D03*
Y109410D03*
Y130670D03*
Y123583D03*
Y137756D03*
X497424Y354559D03*
X492317Y376252D03*
X503682Y455466D03*
X497776Y448466D03*
X493929Y555194D03*
X496729D03*
X493929Y563194D03*
X496729D03*
X493929Y571194D03*
X496729D03*
X492338Y581222D03*
Y591215D03*
X494632Y654622D03*
X501618Y698355D03*
X499012Y699819D03*
X503311Y715652D03*
X500705Y705524D03*
X507546Y738539D03*
X505673Y767961D03*
X500717D03*
X504341Y812040D03*
X491655Y829173D03*
X506246Y824689D03*
X492799Y846488D03*
X503741Y846830D03*
X497467Y833027D03*
X499640Y861538D03*
X499595Y963963D03*
X493050Y976078D03*
X506566Y1000766D03*
Y1004766D03*
Y1016266D03*
Y1030766D03*
X505981Y1052487D03*
X506946Y1123101D03*
Y1125801D03*
X505346Y1129301D03*
X507846D03*
X503820Y1139435D03*
Y1136935D03*
Y1134435D03*
Y1131935D03*
X501320Y1139435D03*
Y1136935D03*
Y1134435D03*
Y1131935D03*
X494918Y1136935D03*
Y1134435D03*
Y1139435D03*
Y1131935D03*
X503820Y1144435D03*
Y1146935D03*
Y1141935D03*
X501320Y1144435D03*
Y1146935D03*
Y1141935D03*
X494918Y1146935D03*
Y1144435D03*
Y1141935D03*
X502562Y1152713D03*
Y1155213D03*
X506451Y1204405D03*
X493821Y1204617D03*
X496136Y1200821D03*
Y1198321D03*
X506451Y1206905D03*
Y1211905D03*
Y1209405D03*
X493821Y1207117D03*
Y1209617D03*
Y1212117D03*
X500824Y1350683D03*
Y1345691D03*
X505780Y1350683D03*
Y1345691D03*
X493540D03*
Y1350683D03*
X505780Y1362595D03*
Y1357603D03*
X500824Y1362595D03*
Y1357603D03*
X493540Y1362595D03*
Y1357603D03*
Y1381801D03*
Y1374881D03*
Y1369889D03*
X505780Y1381801D03*
Y1374881D03*
Y1369889D03*
X500824D03*
Y1381801D03*
Y1374881D03*
Y1394087D03*
X505780Y1399079D03*
X500824D03*
X505780Y1394087D03*
X493540Y1386793D03*
Y1394087D03*
Y1399079D03*
X505780Y1386793D03*
X500824D03*
X505780Y1410991D03*
X500824D03*
X505780Y1405999D03*
X500824D03*
X493540D03*
Y1410991D03*
X497432Y1465513D03*
X506093Y1465913D03*
X497432Y1460782D03*
X506093Y1461182D03*
X497432Y1480867D03*
X506093Y1481267D03*
X497432Y1476136D03*
Y1470244D03*
X506093Y1471805D03*
Y1476536D03*
X497432Y1496221D03*
Y1491490D03*
Y1485598D03*
X506093Y1487159D03*
Y1491890D03*
Y1496621D03*
Y1511976D03*
X497432Y1506845D03*
Y1500952D03*
X506093Y1502514D03*
Y1507245D03*
X497432Y1511576D03*
Y1516307D03*
Y1563144D03*
X506093Y1558813D03*
X497432Y1578498D03*
X506093Y1578898D03*
X497432Y1567875D03*
Y1572606D03*
X506093Y1574167D03*
Y1568275D03*
Y1563544D03*
X497432Y1587960D03*
X506093Y1589522D03*
Y1583629D03*
X497432Y1593853D03*
X506093Y1594253D03*
X497432Y1583229D03*
X506093Y1604876D03*
Y1598984D03*
X497432Y1609207D03*
X506093Y1609607D03*
X497432Y1598584D03*
Y1603315D03*
Y1613938D03*
Y1618669D03*
X506093Y1614338D03*
X492000Y1644980D03*
X513051Y103037D03*
X513185Y116496D03*
Y109410D03*
Y130670D03*
Y123583D03*
X509251Y137756D03*
X517866Y293796D03*
X515366D03*
X523380Y285690D03*
Y288190D03*
X511342Y311124D03*
X520845Y434508D03*
X516845D03*
X512845D03*
X514608Y445874D03*
X510022Y446352D03*
X523705Y444269D03*
X523583Y447201D03*
X521636Y504699D03*
X516636D03*
X519136D03*
X516338Y516979D03*
X521338D03*
X518838D03*
X512404Y629362D03*
X510215Y627948D03*
X511990Y686365D03*
X518001Y694940D03*
X522410Y694881D03*
X518067Y699378D03*
X518530Y703584D03*
X522628Y703884D03*
X508237Y723585D03*
X512502Y738539D03*
X516953Y738575D03*
X521909D03*
X520159Y758832D03*
X509063Y782867D03*
X517194Y773232D03*
X522316Y793574D03*
X509316Y793224D03*
X508130Y787488D03*
X521178Y814001D03*
X521565Y820931D03*
X520720Y846133D03*
X517832Y834558D03*
X508049Y877789D03*
X523272Y880067D03*
X509428Y888390D03*
X521115Y897500D03*
X511025Y911443D03*
X509673Y900295D03*
X516256Y939157D03*
X514886Y952189D03*
X519792Y1031271D03*
X517702Y1098518D03*
X512450Y1098428D03*
X522890Y1098767D03*
X514946Y1123101D03*
X517446D03*
X522846Y1129301D03*
X515346Y1125801D03*
X517846D03*
X510346Y1129301D03*
X512846D03*
X515346D03*
X517846D03*
X520346Y1125801D03*
X522846D03*
X520346Y1129301D03*
X518210Y1155213D03*
Y1152713D03*
X508810D03*
Y1155213D03*
X520751Y1204617D03*
X523066Y1200821D03*
Y1198321D03*
X520751Y1207117D03*
Y1209617D03*
Y1212117D03*
X513064Y1345691D03*
X518020Y1350683D03*
X513064D03*
X518020Y1345691D03*
Y1357603D03*
X513064Y1362595D03*
Y1357603D03*
X518020Y1362595D03*
X513064Y1369889D03*
Y1381801D03*
Y1374881D03*
X518020Y1369889D03*
Y1381801D03*
Y1374881D03*
Y1394087D03*
Y1399079D03*
X513064Y1394087D03*
Y1399079D03*
Y1386793D03*
X518020D03*
Y1405999D03*
Y1410991D03*
X513064D03*
Y1405999D03*
X514755Y1460782D03*
Y1465513D03*
Y1480867D03*
Y1476136D03*
Y1470244D03*
Y1491490D03*
Y1485598D03*
Y1496221D03*
Y1511576D03*
Y1506845D03*
Y1500952D03*
Y1516307D03*
Y1563144D03*
Y1567875D03*
Y1572606D03*
Y1578498D03*
Y1593853D03*
Y1583229D03*
Y1587960D03*
Y1603315D03*
Y1609207D03*
Y1598584D03*
Y1613938D03*
Y1618669D03*
X512000Y1644980D03*
X526468Y94017D03*
X534468D03*
X538477D03*
X530468D03*
X530596Y115401D03*
X535588Y110445D03*
Y115401D03*
X530596Y110445D03*
Y124618D03*
Y129574D03*
X535588Y124618D03*
Y129574D03*
X528509Y151540D03*
X538659Y184619D03*
X532159Y191941D03*
X532026Y188727D03*
X528783Y226141D03*
X525983D03*
X533853Y256535D03*
X525880Y285690D03*
X528680D03*
X525880Y288190D03*
X528680D03*
X532906Y290755D03*
X536906D03*
X540906D03*
X524206Y354119D03*
X533027Y351836D03*
X530215Y364422D03*
X535142Y397552D03*
X532936Y519544D03*
X527936D03*
X525436D03*
X530436D03*
X538826Y633450D03*
X526756Y636005D03*
Y633205D03*
X538826Y636250D03*
Y639050D03*
X526756Y638805D03*
X524653Y643595D03*
X534940Y684489D03*
X539111Y681459D03*
X526956Y694959D03*
X526951Y699443D03*
X535387Y712617D03*
X526933Y703820D03*
X532628Y720776D03*
X526276Y721339D03*
X539763Y734097D03*
X534807D03*
X531763Y739097D03*
X526807D03*
X532450Y767474D03*
X532278Y762736D03*
X531501Y792331D03*
X531260Y794934D03*
X531666Y815724D03*
X531313Y822693D03*
X527733Y847026D03*
X527346Y911458D03*
X528674Y964851D03*
X527046Y1131935D03*
Y1139435D03*
Y1134435D03*
Y1136935D03*
X528274Y1152684D03*
X527046Y1146935D03*
Y1144435D03*
Y1141935D03*
X525304Y1345691D03*
X530260D03*
X537544Y1350683D03*
X525304D03*
X530260D03*
X537544Y1345691D03*
Y1357603D03*
X525304Y1362595D03*
X530260D03*
X525304Y1357603D03*
X530260D03*
X537544Y1362595D03*
Y1374881D03*
X525304Y1369889D03*
Y1381801D03*
Y1374881D03*
X530260Y1369889D03*
Y1381801D03*
Y1374881D03*
X537544Y1369889D03*
Y1381801D03*
Y1399079D03*
Y1394087D03*
X530260D03*
Y1399079D03*
X525304Y1394087D03*
Y1399079D03*
X537544Y1386793D03*
X525304D03*
X530260D03*
X537544Y1410991D03*
Y1405999D03*
X530260D03*
X525304D03*
X530260Y1410991D03*
X525304D03*
X532000Y1644980D03*
X543545Y84140D03*
Y80140D03*
Y76140D03*
X540998Y117557D03*
X545990D03*
Y122513D03*
Y131731D03*
X540998Y122513D03*
Y131731D03*
X544089Y146461D03*
X545990Y136687D03*
X540998D03*
X542991Y152367D03*
X549374Y180527D03*
X544691Y180572D03*
X553097Y192421D03*
X549329Y185121D03*
X544691Y185165D03*
X540639Y206760D03*
X541853Y256535D03*
X542883Y279208D03*
X546987Y281307D03*
X541644Y389047D03*
X553731Y388487D03*
X541706Y381723D03*
X552905Y430829D03*
X550274Y658676D03*
X556574Y684031D03*
Y700031D03*
Y688987D03*
Y716031D03*
Y704987D03*
Y720987D03*
X552384Y762892D03*
X552188Y766577D03*
X553871Y811298D03*
X545741Y804149D03*
X548464Y823156D03*
X540807Y816556D03*
X541129Y828335D03*
Y838865D03*
X545981Y846389D03*
X549241Y841388D03*
X545237Y850319D03*
X548521Y877859D03*
Y874859D03*
X545144Y909025D03*
X544793Y899220D03*
X548215Y1006560D03*
X552923Y997860D03*
X541766Y1018368D03*
X557681Y1035088D03*
X554740Y1345597D03*
X542500Y1345691D03*
X549784Y1345597D03*
X542500Y1350683D03*
X549784D03*
X554740D03*
Y1362595D03*
Y1357603D03*
X542500Y1362595D03*
X549784D03*
X542500Y1357603D03*
X549784D03*
X554740Y1381801D03*
Y1374881D03*
X542500D03*
X549784Y1369889D03*
Y1381801D03*
Y1374881D03*
X542500Y1369889D03*
Y1381801D03*
X554740Y1369889D03*
Y1399079D03*
Y1393993D03*
X542500Y1399079D03*
X549784Y1393993D03*
Y1399079D03*
X542500Y1394087D03*
X554740Y1386793D03*
X549784D03*
X542500D03*
X554740Y1410991D03*
Y1405999D03*
X542500Y1410991D03*
X549784D03*
X542500Y1405999D03*
X549784D03*
X552000Y1644980D03*
X566287Y60922D03*
X561123Y55513D03*
X563224Y96813D03*
X558316Y91951D03*
X556920Y117261D03*
X567100Y110784D03*
X564451Y113394D03*
X567290Y130898D03*
X568841Y134579D03*
X564627Y180665D03*
Y172665D03*
X569969Y195176D03*
X564659Y212864D03*
Y200864D03*
X569829Y203393D03*
X564659Y221864D03*
Y216864D03*
X566416Y252371D03*
X570634Y375453D03*
X559074Y696987D03*
Y692031D03*
Y712987D03*
Y708031D03*
X561886Y728138D03*
X559625Y739609D03*
X557813Y747814D03*
X570578Y749800D03*
X570695Y767052D03*
X564276Y776701D03*
X558241Y796389D03*
X569186Y787332D03*
X561401Y811242D03*
X567316Y806224D03*
X561061Y803606D03*
X563099Y829943D03*
X567316Y827724D03*
X559741Y822149D03*
X572171Y842346D03*
X559196Y846296D03*
X569577Y886913D03*
X560814Y901022D03*
X564923Y997860D03*
X560923D03*
X568923D03*
X556923D03*
X571857Y1009354D03*
X565451Y1035102D03*
X569520Y1102091D03*
X560211D03*
X566020D03*
X569520Y1114691D03*
X566020D03*
X560211D03*
X569520Y1139891D03*
X566020D03*
X560211D03*
X566020Y1127291D03*
X560211D03*
X569520D03*
X566020Y1152491D03*
X560211D03*
X569520D03*
X566020Y1165091D03*
X560211D03*
X569520D03*
X560211Y1177691D03*
X566020D03*
X569520D03*
X566502Y1202103D03*
X569882Y1223749D03*
X562024Y1350683D03*
Y1345691D03*
X566980D03*
Y1350683D03*
X562024Y1357603D03*
X566980D03*
Y1362595D03*
X562024D03*
Y1369889D03*
Y1381801D03*
Y1374881D03*
X566980Y1369889D03*
Y1381801D03*
Y1374881D03*
Y1399079D03*
Y1394087D03*
X562024Y1399079D03*
Y1394087D03*
X566980Y1386793D03*
X562024D03*
X566980Y1410991D03*
X562024D03*
X566980Y1405999D03*
X562024D03*
X565600Y1530800D03*
X569349Y1541947D03*
X560635Y1543531D03*
X566800Y1541800D03*
X582686Y109172D03*
X579686D03*
X581693Y106495D03*
X585437Y116497D03*
X574694Y133298D03*
X585437Y123584D03*
Y130670D03*
X581427Y146012D03*
X583333Y141228D03*
X585437Y137757D03*
X586221Y150847D03*
X588189Y247292D03*
X580898Y253198D03*
X581487Y336676D03*
X573805Y728301D03*
X574620Y772724D03*
X584624Y781850D03*
X581001Y814123D03*
X579758Y817753D03*
X579827Y884000D03*
X579251Y903364D03*
X582706Y908959D03*
X580923Y997860D03*
X576923D03*
X588923D03*
X577666Y1009354D03*
X581166D03*
X572923Y997860D03*
X584923D03*
X581166Y1021954D03*
X577666D03*
X578298Y1215195D03*
X584024Y1209607D03*
X587689Y1505724D03*
X583661Y1529142D03*
X573784Y1530646D03*
X575332Y1523740D03*
X583800Y1518000D03*
X583740Y1520640D03*
X587858Y1517942D03*
X577645Y1540982D03*
X580700Y1544100D03*
X592737Y109410D03*
X590237Y116497D03*
X592737D03*
X597437Y102323D03*
Y109410D03*
Y116496D03*
Y123583D03*
Y130670D03*
X592737Y123583D03*
X590237Y123584D03*
Y130670D03*
X592737D03*
X597437Y137756D03*
X590237Y137757D03*
X590178Y309760D03*
X593690Y450750D03*
X597872Y512743D03*
X592880D03*
X597789Y536382D03*
X602756Y597580D03*
X604979Y599588D03*
X604241Y589556D03*
X604180Y592354D03*
X602695Y594668D03*
X604982Y596095D03*
X605011Y615600D03*
X604979Y607588D03*
X592238Y880612D03*
X597129Y913386D03*
X602385Y940920D03*
X596923Y997860D03*
X592923D03*
X604923D03*
X600923D03*
X602603Y1012354D03*
Y1024954D03*
X604405Y1034870D03*
X591898Y1035011D03*
X590957Y1105091D03*
Y1117691D03*
Y1130291D03*
Y1155491D03*
Y1142891D03*
Y1168091D03*
Y1180691D03*
X592978Y1514812D03*
X591858Y1523542D03*
X598800Y1546400D03*
X605899Y80384D03*
Y82984D03*
Y77784D03*
Y75184D03*
X608453Y92849D03*
X605899Y85584D03*
X615413Y103037D03*
X615547Y116496D03*
Y109410D03*
Y130670D03*
Y123583D03*
X612138Y137756D03*
X617728Y293796D03*
X620228D03*
X614461Y555234D03*
X614176Y562003D03*
X609472Y634946D03*
X612489Y941024D03*
X616923Y997860D03*
X608923D03*
X620151Y1040363D03*
X619086Y1056453D03*
X620715Y1046785D03*
X612000Y1644980D03*
X636830Y94017D03*
X628830D03*
X632830D03*
X632958Y110445D03*
Y115401D03*
Y124618D03*
Y129574D03*
X630871Y151540D03*
X634521Y191941D03*
X634388Y188727D03*
X631145Y226141D03*
X628345D03*
X636215Y256535D03*
X631042Y288190D03*
Y285690D03*
X625742Y288190D03*
X628242Y285690D03*
X625742D03*
X628242Y288190D03*
X635268Y290755D03*
X634455Y389154D03*
Y396240D03*
Y403327D03*
Y410413D03*
Y417500D03*
Y424587D03*
Y431673D03*
Y438760D03*
Y445847D03*
Y467539D03*
Y474626D03*
Y488799D03*
Y481713D03*
Y495886D03*
Y511673D03*
Y518760D03*
Y525847D03*
Y532933D03*
Y540020D03*
Y547106D03*
X633736Y602197D03*
X634200Y595108D03*
X622270Y864781D03*
X630466Y1394087D03*
X625510Y1399079D03*
Y1394087D03*
X630466Y1399079D03*
X625510Y1405999D03*
X630466D03*
X625510Y1410991D03*
X630466D03*
X636015Y1460782D03*
X627354Y1461182D03*
X636015Y1465513D03*
X627354Y1465913D03*
Y1456451D03*
X636015Y1476136D03*
X627354Y1476536D03*
X636015Y1480867D03*
X627354Y1481267D03*
Y1471805D03*
X636015Y1470244D03*
X627354Y1487159D03*
X636015Y1485598D03*
Y1491490D03*
X627354Y1491890D03*
X636015Y1496221D03*
X627354Y1496621D03*
Y1507245D03*
Y1511976D03*
X636015Y1511576D03*
X627354Y1502514D03*
X636015Y1500952D03*
Y1506845D03*
Y1516307D03*
X627354Y1558813D03*
X636015Y1563144D03*
X627354Y1563544D03*
X636015Y1567875D03*
X627354Y1568275D03*
Y1574167D03*
X636015Y1572606D03*
Y1578498D03*
X627354Y1578898D03*
X636015Y1593853D03*
X627354Y1594253D03*
X636015Y1583229D03*
X627354Y1583629D03*
Y1589522D03*
X636015Y1587960D03*
X627354Y1604876D03*
X636015Y1603315D03*
Y1598584D03*
X627354Y1598984D03*
X636015Y1609207D03*
X627354Y1609607D03*
X636015Y1618669D03*
Y1613938D03*
X627354Y1614338D03*
X632000Y1644980D03*
X645907Y76140D03*
Y84140D03*
Y80140D03*
X640839Y94017D03*
X643360Y117557D03*
X637950Y110445D03*
Y115401D03*
X648352Y117557D03*
X643360Y122513D03*
Y131731D03*
X637950Y124618D03*
Y129574D03*
X648352Y122513D03*
Y131731D03*
X646451Y146461D03*
X643360Y136687D03*
X648352D03*
X645353Y152367D03*
X647053Y180572D03*
X651736Y180527D03*
X651691Y185121D03*
X647053Y185165D03*
X641021Y184619D03*
X643001Y206760D03*
X644215Y256535D03*
X645245Y279208D03*
X649349Y281307D03*
X639268Y290755D03*
X643268D03*
X649074Y389154D03*
X647604Y396240D03*
X652381Y414823D03*
X651689Y422864D03*
X651759Y429832D03*
X651364Y436447D03*
X653399Y447953D03*
X652566Y467539D03*
X651308Y472772D03*
X652042Y487711D03*
X652155Y479104D03*
X652566Y495886D03*
X647915Y516841D03*
X651166Y510565D03*
X642862Y550123D03*
X642740Y552872D03*
X644494Y572334D03*
X642185Y562443D03*
X643953Y560675D03*
X642726Y574102D03*
X647361Y653161D03*
X648352Y645467D03*
X650958Y677843D03*
X649990Y1350683D03*
Y1345691D03*
Y1357603D03*
Y1362595D03*
Y1381801D03*
X642706Y1374881D03*
Y1381801D03*
Y1369889D03*
X649990Y1374881D03*
Y1369889D03*
X637750Y1374881D03*
Y1381801D03*
Y1369889D03*
X649990Y1399079D03*
Y1394087D03*
X642706Y1386793D03*
X649990D03*
X637750Y1399079D03*
X642706Y1394087D03*
X637750D03*
X642706Y1399079D03*
X637750Y1386793D03*
X649990Y1405999D03*
Y1410991D03*
X637750D03*
X642706D03*
Y1405999D03*
X637750D03*
X653338Y1465513D03*
X644677Y1461182D03*
Y1456451D03*
Y1465913D03*
X653338Y1460782D03*
X644677Y1476536D03*
Y1471805D03*
X653338Y1480867D03*
Y1470244D03*
Y1476136D03*
X644677Y1481267D03*
X653338Y1491490D03*
X644677Y1496621D03*
Y1491890D03*
Y1487159D03*
X653338Y1496221D03*
Y1485598D03*
X644677Y1511976D03*
X653338Y1511576D03*
Y1500952D03*
Y1506845D03*
X644677Y1502514D03*
Y1507245D03*
X653338Y1516307D03*
X644677Y1558813D03*
X653338Y1563144D03*
X644677Y1563544D03*
X653338Y1572606D03*
Y1578498D03*
X644677Y1578898D03*
Y1574167D03*
X653338Y1567875D03*
X644677Y1568275D03*
X653338Y1587960D03*
Y1593853D03*
X644677Y1594253D03*
Y1589522D03*
X653338Y1583229D03*
X644677Y1583629D03*
X653338Y1609207D03*
X644677Y1598984D03*
Y1604876D03*
Y1609607D03*
X653338Y1603315D03*
Y1598584D03*
Y1613938D03*
X644677Y1614338D03*
X653338Y1618669D03*
X652000Y1644980D03*
X668649Y60922D03*
X666209Y57297D03*
X665423Y96853D03*
X660678Y91951D03*
X659282Y117261D03*
X666813Y113394D03*
X669462Y110784D03*
X669056Y133298D03*
X666989Y172665D03*
Y180665D03*
X655459Y192421D03*
X667021Y200864D03*
Y212864D03*
Y221864D03*
Y216864D03*
X668778Y252371D03*
X667666Y389153D03*
X665166Y396240D03*
X667666D03*
X665166Y403327D03*
X667666Y403326D03*
X665166Y410413D03*
X667666D03*
Y417499D03*
X665166Y424586D03*
X667666D03*
X665166Y417500D03*
Y431673D03*
Y438760D03*
X667666D03*
Y431673D03*
X665166Y445847D03*
X667666Y467539D03*
X665166Y474626D03*
X667666D03*
X665166Y488799D03*
X667666D03*
Y481712D03*
X665166D03*
Y495886D03*
X667666Y518760D03*
X665166D03*
X667666Y511673D03*
Y532933D03*
X665166D03*
Y540020D03*
Y525846D03*
X667666D03*
X669546Y560500D03*
X655752Y668885D03*
X661776Y662981D03*
X656157Y691851D03*
X661768Y705043D03*
X654946Y1350683D03*
X662230D03*
X667186D03*
Y1345691D03*
X654946D03*
X662230D03*
X654946Y1357603D03*
Y1362595D03*
X662230Y1357603D03*
Y1362595D03*
X667186Y1357603D03*
Y1362595D03*
X662230Y1369889D03*
X667186Y1374881D03*
Y1381801D03*
Y1369889D03*
X662230Y1374881D03*
Y1381801D03*
X654946D03*
Y1369889D03*
Y1374881D03*
X667186Y1399079D03*
Y1393993D03*
X662230D03*
Y1399079D03*
X655046D03*
Y1394087D03*
X667186Y1386793D03*
X662230D03*
X654946D03*
X667186Y1410991D03*
Y1405999D03*
X662230D03*
Y1410991D03*
X655046Y1405999D03*
Y1410991D03*
X662000Y1456451D03*
Y1465913D03*
Y1461182D03*
Y1481267D03*
Y1476536D03*
Y1471805D03*
Y1496621D03*
Y1491890D03*
Y1487159D03*
Y1511976D03*
Y1502514D03*
Y1507245D03*
Y1563544D03*
Y1558813D03*
Y1568275D03*
Y1578898D03*
Y1574167D03*
Y1594253D03*
Y1589522D03*
Y1583629D03*
Y1598984D03*
Y1604876D03*
Y1609607D03*
Y1614338D03*
X682048Y109172D03*
X685048D03*
X684055Y106495D03*
X677056Y133298D03*
X671203Y134579D03*
X683789Y146012D03*
X685695Y141228D03*
X677331Y195176D03*
X676950Y198883D03*
X683260Y253198D03*
X686012Y339795D03*
X672466Y389153D03*
Y410413D03*
Y396240D03*
Y403326D03*
Y424586D03*
Y417499D03*
Y438760D03*
Y431673D03*
Y467539D03*
Y474626D03*
Y488799D03*
Y481712D03*
Y518760D03*
Y511673D03*
Y525846D03*
Y532933D03*
X681586Y555000D03*
X681011Y543925D03*
X679426Y1350683D03*
X674470Y1345691D03*
X679426D03*
X674470Y1350683D03*
Y1357603D03*
Y1362595D03*
X679426Y1357603D03*
Y1362595D03*
Y1374881D03*
X674470D03*
Y1381801D03*
X679426D03*
Y1369889D03*
X674470D03*
X679426Y1399079D03*
X674470Y1394087D03*
X679426D03*
X674470Y1399079D03*
Y1386793D03*
X679426D03*
X674470Y1405999D03*
X679426D03*
X674470Y1410991D03*
X679426D03*
X679322Y1461182D03*
Y1456451D03*
Y1465913D03*
X670661Y1460782D03*
Y1465513D03*
Y1470244D03*
Y1476136D03*
X679322Y1481267D03*
Y1476536D03*
Y1471805D03*
X670661Y1480867D03*
X679322Y1487159D03*
X670661Y1496221D03*
Y1485598D03*
Y1491490D03*
X679322Y1496621D03*
Y1491890D03*
X670661Y1500952D03*
Y1506845D03*
X679322Y1511976D03*
Y1502514D03*
Y1507245D03*
X670661Y1511576D03*
Y1516307D03*
X679322Y1558813D03*
X670661Y1563144D03*
X679322Y1563544D03*
Y1578898D03*
Y1574167D03*
Y1568275D03*
X670661Y1572606D03*
Y1578498D03*
Y1567875D03*
X679322Y1583629D03*
X670661Y1587960D03*
Y1593853D03*
Y1583229D03*
X679322Y1594253D03*
Y1589522D03*
Y1604876D03*
Y1609607D03*
X670661Y1603315D03*
Y1598584D03*
Y1609207D03*
X679322Y1598984D03*
Y1614338D03*
X670661Y1618669D03*
Y1613938D03*
X672000Y1644980D03*
X695099Y109410D03*
X687799Y116497D03*
X692599D03*
X695099D03*
X699799Y116496D03*
Y109410D03*
Y102323D03*
X687799Y123584D03*
X695099Y123583D03*
X692599Y123584D03*
X687799Y130670D03*
X692599D03*
X695099D03*
X699799Y123583D03*
Y130670D03*
X687799Y137757D03*
X692599D03*
X699799Y137756D03*
X688583Y150847D03*
X690551Y247292D03*
X700164Y636842D03*
X698936Y678462D03*
X702691Y766471D03*
Y753471D03*
X702677Y771159D03*
Y784659D03*
X698950Y1350683D03*
Y1345597D03*
X686710Y1350683D03*
X691666D03*
X686710Y1345691D03*
X691666D03*
X698950Y1362595D03*
Y1357603D03*
X686710D03*
Y1362595D03*
X691666Y1357603D03*
Y1362595D03*
X698950Y1374881D03*
Y1381801D03*
Y1369889D03*
X691666D03*
Y1374881D03*
Y1381801D03*
X686710Y1374881D03*
Y1369889D03*
Y1381801D03*
X698950Y1399079D03*
Y1394087D03*
X686710D03*
Y1399079D03*
X691666Y1394087D03*
Y1399079D03*
X698950Y1386793D03*
X691666D03*
X686710D03*
X698950Y1405999D03*
Y1410991D03*
X686710D03*
X691666D03*
X686710Y1405999D03*
X691666D03*
X696645Y1461183D03*
Y1456452D03*
Y1465914D03*
X687984Y1460782D03*
Y1465513D03*
Y1470244D03*
Y1476136D03*
X696645Y1481268D03*
Y1471806D03*
Y1476537D03*
X687984Y1480867D03*
X696645Y1491891D03*
X687984Y1496221D03*
Y1485598D03*
Y1491490D03*
X696645Y1496622D03*
Y1487160D03*
Y1511977D03*
Y1502515D03*
Y1507246D03*
X687984Y1511576D03*
Y1500952D03*
Y1506845D03*
Y1516307D03*
X696645Y1558813D03*
Y1563544D03*
X687984Y1563144D03*
X696645Y1574167D03*
Y1578898D03*
X687984Y1572606D03*
Y1578498D03*
X696645Y1568275D03*
X687984Y1567875D03*
Y1583229D03*
X696645Y1589522D03*
Y1594253D03*
X687984Y1587960D03*
Y1593853D03*
X696645Y1583629D03*
Y1598984D03*
Y1609607D03*
X687984Y1603315D03*
Y1598584D03*
Y1609207D03*
X696645Y1604876D03*
X687984Y1613938D03*
X696645Y1614338D03*
X687984Y1618669D03*
X692000Y1644980D03*
X718488Y-27642D03*
X718503Y-25127D03*
X708261Y82984D03*
Y80384D03*
Y77784D03*
Y75184D03*
X710815Y92849D03*
X708261Y85584D03*
X717775Y103037D03*
X717909Y116496D03*
Y109410D03*
Y130670D03*
Y123583D03*
X714500Y137756D03*
X713162Y434493D03*
X711764Y449873D03*
X718691Y465492D03*
Y472579D03*
X716191D03*
X711391D03*
X716191Y479666D03*
X718691D03*
X711391D03*
Y486752D03*
X716191D03*
X718691D03*
X711391Y493839D03*
X716191D03*
Y516713D03*
Y523800D03*
X718691D03*
X711391D03*
Y516713D03*
X718691D03*
Y509626D03*
Y530886D03*
X716191D03*
Y537973D03*
X711391Y530886D03*
Y537973D03*
Y566752D03*
X718691Y559665D03*
Y566752D03*
X716191D03*
X711391Y573839D03*
X718691D03*
X716191D03*
X711391Y588013D03*
X718691Y588012D03*
X716191Y588013D03*
X718691Y580926D03*
X716191D03*
X711391D03*
X716191Y602186D03*
X711391D03*
X718691Y602185D03*
Y595099D03*
X711391D03*
X716191D03*
X711391Y609272D03*
X716191D03*
X718691D03*
X716191Y616359D03*
X711391D03*
X706070Y638125D03*
X716656Y646429D03*
X703669Y665140D03*
X716350Y699477D03*
X703604Y699653D03*
X716146Y1350683D03*
X711190D03*
X716146Y1345691D03*
X711190D03*
X703906Y1350683D03*
Y1345597D03*
X716146Y1357603D03*
X711190D03*
Y1362595D03*
X716146D03*
X703906Y1357603D03*
Y1362595D03*
X716146Y1374881D03*
Y1381801D03*
Y1369889D03*
X711190D03*
Y1374881D03*
Y1381801D03*
X703906D03*
Y1369889D03*
Y1374881D03*
X716146Y1399079D03*
X711190D03*
X716146Y1393993D03*
X711190D03*
X703906Y1394087D03*
Y1399079D03*
X716146Y1386793D03*
X711190D03*
X703906D03*
X716146Y1405999D03*
X711190D03*
X716146Y1410991D03*
X711190D03*
X703906Y1405999D03*
Y1410991D03*
X712000Y1644980D03*
X721741Y-27628D03*
X721756Y-25113D03*
X724781Y-26433D03*
X735192Y94017D03*
X731192D03*
X733233Y151540D03*
X736750Y188727D03*
X730707Y226141D03*
X733507D03*
X733404Y285690D03*
X720090Y293796D03*
X722590D03*
X728104Y288190D03*
X730604Y285690D03*
X728104D03*
X730604Y288190D03*
X733404D03*
X731511Y390500D03*
X734606Y379562D03*
X722097Y410394D03*
Y403307D03*
X723491Y458406D03*
Y451319D03*
Y465492D03*
X723315Y462264D03*
X723491Y472579D03*
Y479665D03*
Y486752D03*
Y493839D03*
Y523799D03*
Y516713D03*
Y509626D03*
Y530886D03*
Y537973D03*
Y566752D03*
Y559665D03*
Y573839D03*
Y588012D03*
Y580926D03*
Y595099D03*
Y602185D03*
Y609272D03*
Y616358D03*
X734819Y646429D03*
X725318Y890354D03*
X720373Y940310D03*
X724547Y958287D03*
X723430Y1350683D03*
X728386Y1345691D03*
X723430D03*
X728386Y1350683D03*
Y1357603D03*
Y1362595D03*
X723430Y1357603D03*
Y1362595D03*
X728386Y1381801D03*
Y1374881D03*
Y1369889D03*
X723430D03*
Y1381801D03*
Y1374881D03*
X728386Y1386793D03*
X723430D03*
X728386Y1398985D03*
Y1393993D03*
X723430Y1398985D03*
Y1393993D03*
X728386Y1410897D03*
Y1405905D03*
X723430Y1410897D03*
Y1405905D03*
X732000Y1644980D03*
X748269Y84140D03*
Y76140D03*
Y80140D03*
X743201Y94017D03*
X739192D03*
X750714Y117557D03*
X745722D03*
X740312Y115401D03*
Y110445D03*
X735320D03*
Y115401D03*
X745722Y131731D03*
Y122513D03*
X740312Y129574D03*
Y124618D03*
X735320D03*
Y129574D03*
X750714Y131731D03*
Y122513D03*
Y136687D03*
X745722D03*
X748813Y146461D03*
X747715Y152367D03*
X749415Y180572D03*
Y185165D03*
X743383Y184619D03*
X736883Y191941D03*
X745363Y206760D03*
X738577Y256535D03*
X746577D03*
X747607Y279208D03*
X751711Y281307D03*
X741630Y290755D03*
X737630D03*
X745630D03*
X741161Y381500D03*
X741602Y465492D03*
X741568Y460250D03*
X739333Y470136D03*
X741602Y472579D03*
X741072Y478958D03*
X741602Y486752D03*
Y493839D03*
Y509626D03*
Y516713D03*
X738062Y537973D03*
X740542Y525483D03*
X740463Y532756D03*
X741602Y559665D03*
Y566752D03*
X741452Y579978D03*
X741602Y573839D03*
X741666Y608117D03*
X741000Y771100D03*
X738707Y987952D03*
X745673Y1007009D03*
X747910Y1345691D03*
Y1350683D03*
X735670D03*
X740626D03*
X735670Y1345691D03*
X740626D03*
X747910Y1357603D03*
Y1362595D03*
X735670Y1357603D03*
Y1362595D03*
X740626Y1357603D03*
Y1362595D03*
X747910Y1374881D03*
Y1381801D03*
Y1369889D03*
X740626Y1381801D03*
Y1369889D03*
Y1374881D03*
X735670Y1381801D03*
Y1369889D03*
Y1374881D03*
X747910Y1386793D03*
X735670Y1393993D03*
X740626D03*
Y1398985D03*
X735670D03*
X740626Y1386793D03*
X735670D03*
Y1405905D03*
Y1410897D03*
X740626Y1405905D03*
Y1410897D03*
X742655Y1445733D03*
X747590Y1627871D03*
X765847Y55513D03*
X762065Y117040D03*
X754098Y180527D03*
X757821Y192421D03*
X754053Y185121D03*
X756201Y288345D03*
Y290845D03*
X753701Y288345D03*
Y290845D03*
Y293645D03*
X756201D03*
X763898Y342319D03*
X766344Y393924D03*
Y389912D03*
Y385912D03*
X758038Y381143D03*
X766344Y409924D03*
Y405924D03*
Y401924D03*
X752341Y407148D03*
X756800Y403824D03*
X758381Y395391D03*
X759543Y445787D03*
X755593Y445908D03*
X765106Y1350683D03*
Y1345597D03*
X760150D03*
Y1350683D03*
X752866Y1345691D03*
Y1350683D03*
X765106Y1362595D03*
Y1357603D03*
X760150D03*
Y1362595D03*
X752866Y1357603D03*
Y1362595D03*
X765106Y1374881D03*
Y1381801D03*
Y1369889D03*
X760150Y1374881D03*
Y1381801D03*
Y1369889D03*
X752866Y1374881D03*
Y1381801D03*
Y1369889D03*
X765106Y1386793D03*
X760150D03*
X752866D03*
X766433Y1583713D03*
X752150Y1627871D03*
X762776Y1629415D03*
X752000Y1644980D03*
X771011Y60922D03*
X767929Y96890D03*
X771824Y110784D03*
X769175Y113394D03*
X779418Y133298D03*
X771960Y130898D03*
X773565Y134579D03*
X769351Y172665D03*
Y180665D03*
X769383Y200864D03*
Y212864D03*
Y221864D03*
Y216864D03*
X771140Y252371D03*
X780968Y303839D03*
X772990Y336324D03*
X777569Y353506D03*
X772390Y1350683D03*
X777346D03*
Y1345691D03*
X772390D03*
Y1357603D03*
Y1362595D03*
X777346Y1357603D03*
Y1362595D03*
X777114Y1442270D03*
X778045Y1622545D03*
X782289Y1620109D03*
X773822Y1627418D03*
X772000Y1644980D03*
X784410Y109172D03*
X787410D03*
X794961Y116497D03*
X797461D03*
X790161D03*
X786417Y106495D03*
X797461Y109410D03*
Y123583D03*
X794961Y123584D03*
X790161D03*
X794961Y130670D03*
X797461D03*
X790161D03*
X794961Y137757D03*
X790161D03*
X788057Y141228D03*
X786151Y146012D03*
X793221Y140296D03*
X790945Y150847D03*
X792913Y247292D03*
X785622Y253198D03*
X788522Y290304D03*
X799937Y347340D03*
X791686Y1025440D03*
X794716Y1186071D03*
X792183Y1334030D03*
Y1331230D03*
X789383Y1334030D03*
Y1331230D03*
X794506Y1411307D03*
X793723Y1468071D03*
X793564Y1642682D03*
X810623Y77784D03*
Y82984D03*
Y80384D03*
Y75184D03*
X813177Y92849D03*
X810623Y85584D03*
X802161Y116496D03*
Y109410D03*
Y102323D03*
Y130670D03*
Y123583D03*
Y137756D03*
X816364Y486870D03*
X813864D03*
X813566Y744187D03*
X812661Y810032D03*
X812980Y824166D03*
X816016Y838036D03*
X813182Y852800D03*
X814731Y889365D03*
X812811Y908162D03*
X809682Y1133284D03*
X806787Y1148000D03*
X815034Y1159455D03*
X809623Y1160168D03*
X809393Y1187252D03*
X807487Y1193019D03*
X815487D03*
X811487D03*
X817446Y1210089D03*
X800627Y1392748D03*
X800703Y1426779D03*
X811457Y1639797D03*
X820137Y103037D03*
X820271Y116496D03*
Y109410D03*
Y130670D03*
Y123583D03*
X816637Y137756D03*
X824952Y293796D03*
X822452D03*
X830466Y285690D03*
Y288190D03*
X825792Y305225D03*
X823529Y467189D03*
X830318Y674164D03*
X829784Y713939D03*
X832284Y731216D03*
X830484Y746701D03*
X819993Y754109D03*
X817500Y760000D03*
X820547Y780314D03*
X826925Y769000D03*
X820500Y777500D03*
X826925Y787000D03*
X820500Y792000D03*
X818500Y814000D03*
X820432Y800529D03*
X826925Y805000D03*
Y823000D03*
X826165Y863000D03*
X819134Y863607D03*
X829000Y852000D03*
X825686Y869496D03*
X826797Y883756D03*
X825508Y913869D03*
X822462Y915095D03*
X818347Y939610D03*
X828193Y949324D03*
X832432Y977982D03*
X832711Y993268D03*
X828385Y1120599D03*
X817006Y1133027D03*
X822006Y1130208D03*
X825744Y1146937D03*
X823220Y1162817D03*
X823487Y1193019D03*
X819487D03*
X826612Y1219254D03*
X819522Y1212164D03*
X821816Y1214458D03*
X832084Y1461072D03*
X831457Y1639797D03*
X844781Y-65613D03*
X841756Y-64293D03*
X838503Y-64307D03*
X841741Y-66808D03*
X838488Y-66822D03*
X841554Y94017D03*
X837554D03*
X845563D03*
X833554D03*
X837682Y110445D03*
Y115401D03*
X848084Y117557D03*
X842674Y115401D03*
Y110445D03*
Y129574D03*
Y124618D03*
X837682D03*
Y129574D03*
X848084Y131731D03*
Y122513D03*
Y136687D03*
X839112Y188727D03*
X839245Y191941D03*
X845745Y184619D03*
X847725Y206760D03*
X833069Y226141D03*
X835869D03*
X848939Y256535D03*
X840939D03*
X832966Y288190D03*
Y285690D03*
X835766Y288190D03*
Y285690D03*
X843992Y290755D03*
X839992D03*
X847992D03*
X835236Y533174D03*
X845729Y661263D03*
X836503Y667845D03*
X845784Y713939D03*
X848284Y731181D03*
X846484Y746701D03*
X841500Y758161D03*
Y776161D03*
Y794161D03*
Y812161D03*
X838685Y832987D03*
X845654Y895437D03*
X833870Y881860D03*
X839381Y915839D03*
X839122Y939655D03*
X843734Y1008778D03*
X848520Y1016855D03*
X850631Y84140D03*
Y80140D03*
Y76140D03*
X864006Y117261D03*
X853076Y117557D03*
Y131731D03*
Y122513D03*
Y136687D03*
X851777Y180572D03*
X856460Y180527D03*
X860183Y192421D03*
X851777Y185165D03*
X856415Y185121D03*
X849969Y279208D03*
X854073Y281307D03*
X864920Y343168D03*
X854086Y385000D03*
X858586D03*
X850733Y461382D03*
X850832Y473382D03*
X850738Y477382D03*
X850909Y482382D03*
X853900Y627700D03*
X858202Y646330D03*
X851111Y656635D03*
X856145Y677887D03*
X855646Y685230D03*
X858186Y713170D03*
X867227Y722060D03*
X849500Y761000D03*
X864575Y770500D03*
X849500Y779000D03*
X864575Y788500D03*
X849500Y797000D03*
Y815000D03*
X864575Y806500D03*
X865004Y831273D03*
X864464Y828503D03*
X864575Y824500D03*
X851782Y823720D03*
X851161Y855205D03*
X856628Y915242D03*
X864253D03*
X849600Y915266D03*
X855867Y935540D03*
X849088Y951081D03*
X852247Y1009529D03*
X849996Y1091073D03*
X850023Y1095179D03*
X863342Y1120636D03*
X855542D03*
X858142D03*
X860842D03*
X863442Y1130336D03*
X858242D03*
X855642D03*
X860942D03*
Y1139336D03*
X863442D03*
X861119Y1148080D03*
X863619D03*
X851457Y1639797D03*
X873373Y60922D03*
X868209Y55513D03*
X870395Y96738D03*
X865402Y91951D03*
X871713Y172665D03*
Y180665D03*
X871745Y200864D03*
Y212864D03*
Y216864D03*
Y221864D03*
X876246Y302754D03*
X869313Y688486D03*
X872069Y700894D03*
X876286Y686970D03*
X880501Y710611D03*
X873021Y715729D03*
X877616Y749484D03*
X873318Y744597D03*
X873250Y798750D03*
X872700Y816615D03*
X872628Y915242D03*
X880628D03*
X876481Y941126D03*
X868908Y933640D03*
X867199Y949372D03*
X869390Y978003D03*
X878004Y1224406D03*
X883142Y1259935D03*
X875700Y1299700D03*
X871457Y1639797D03*
X886011Y154100D03*
X895780Y237517D03*
Y232634D03*
X886261Y252090D03*
X885741Y261150D03*
X894844Y418983D03*
X889219Y426952D03*
X887770Y415290D03*
X890270D03*
X897344Y418983D03*
X894519Y426952D03*
X889596Y437264D03*
X896388Y437614D03*
X887096Y437264D03*
X892019Y426952D03*
X897019D03*
X882891Y536122D03*
X896449Y550863D03*
X893949Y550363D03*
X882949Y557363D03*
X887949Y608863D03*
X894449Y606363D03*
X884903Y694119D03*
X886836Y729778D03*
X889083Y780371D03*
X888545Y785528D03*
X888514Y797602D03*
X891916Y808965D03*
X882609Y994245D03*
X897056Y1091391D03*
X891055Y1095407D03*
X897056Y1095984D03*
X884906Y1102760D03*
X884890Y1098724D03*
X893190Y1208069D03*
X894887Y1227209D03*
X891003Y1292765D03*
X890738Y1311132D03*
X891457Y1639797D03*
X898813Y146461D03*
X897715Y152367D03*
X898851Y231496D03*
Y238583D03*
Y245669D03*
X910977Y238583D03*
X898851Y259843D03*
X898576Y253056D03*
X910977Y252756D03*
Y257480D03*
X898851Y274016D03*
X910977Y266929D03*
X898851D03*
X912786Y306697D03*
X901848Y307782D03*
Y312738D03*
X909417Y323302D03*
X912085Y332335D03*
X898888Y437614D03*
X906996Y530707D03*
X902459Y530755D03*
X911630Y543998D03*
X910578Y550186D03*
X909362Y555614D03*
X898156Y554812D03*
X909024Y586768D03*
X908730Y619120D03*
X913686D03*
X899898Y619040D03*
X904854D03*
X910036Y702285D03*
X910753Y715864D03*
X912864Y864189D03*
Y870488D03*
Y867338D03*
X899693Y895207D03*
X904833Y915340D03*
X912628Y928101D03*
X911355Y944909D03*
X906710Y962433D03*
X906909Y951494D03*
X909296Y1020224D03*
X909300Y1014639D03*
X901739Y1091346D03*
X897815Y1078042D03*
X901366Y1078069D03*
X901694Y1095940D03*
X911071Y1123803D03*
X905771D03*
X903171D03*
X908371D03*
X910971Y1114103D03*
X908271D03*
X903071D03*
X905671D03*
X911699Y1129488D03*
X909041Y1126328D03*
X911641D03*
X903908Y1132870D03*
X904063Y1135946D03*
X901940Y1236799D03*
Y1229899D03*
Y1232399D03*
Y1246199D03*
Y1243699D03*
Y1239299D03*
X904703Y1297398D03*
X911457Y1639797D03*
X919175Y113394D03*
X921824Y110784D03*
X921418Y133298D03*
X929418D03*
X923565Y134579D03*
X920142Y308501D03*
X926801Y323302D03*
X923902Y332411D03*
X924600Y533706D03*
X920961Y550075D03*
X915949Y563363D03*
X915712Y613792D03*
X915194Y666671D03*
X928043Y677795D03*
X917286Y679625D03*
X924932Y701051D03*
X920628Y928101D03*
X928628D03*
X916628D03*
X924628D03*
X924487Y951244D03*
X918648Y964717D03*
X915490Y969886D03*
X916749Y1080659D03*
Y1088659D03*
X917110Y1101902D03*
X927598Y1120636D03*
X924898D03*
X914661Y1132612D03*
X914299Y1129488D03*
X914241Y1126328D03*
X924919Y1130336D03*
X927619D03*
X924919Y1139336D03*
X927419D03*
X925097Y1147708D03*
X927597D03*
X927146Y1328597D03*
Y1323641D03*
X929094Y1542353D03*
Y1545353D03*
X926041Y1554503D03*
Y1551503D03*
Y1548503D03*
Y1557503D03*
Y1560503D03*
X944961Y116497D03*
X934410Y109172D03*
X936417Y106495D03*
X937410Y109172D03*
X940161Y116497D03*
Y123584D03*
X944961D03*
X940161Y130670D03*
X944961D03*
X940161Y137757D03*
X944961D03*
X936151Y146012D03*
X938057Y141228D03*
X940945Y150847D03*
X932388Y330517D03*
X932622Y336817D03*
X944694Y352192D03*
X931627Y561578D03*
Y565578D03*
X943825Y581222D03*
Y591215D03*
X935281Y677795D03*
X945626Y789761D03*
X932000Y831000D03*
X942634Y886520D03*
X933700Y887508D03*
X944839Y902400D03*
X938188Y900853D03*
X944628Y928101D03*
X932628D03*
X936628D03*
X940497D03*
X941981Y1224406D03*
X947119Y1259935D03*
X933254Y1308273D03*
X940848Y1310181D03*
X930441Y1455039D03*
Y1458039D03*
Y1464039D03*
Y1461039D03*
Y1467039D03*
X938670Y1510528D03*
X941270D03*
Y1505328D03*
X938670D03*
X940170Y1507928D03*
X943870Y1510528D03*
Y1505328D03*
X945370Y1507928D03*
X942770D03*
X935094Y1542353D03*
X932094D03*
X935094Y1545353D03*
X932094D03*
X938094Y1542353D03*
Y1545353D03*
X941094Y1542353D03*
X944094D03*
X941094Y1545353D03*
X944094D03*
X931457Y1639797D03*
X960623Y82984D03*
Y77784D03*
Y80384D03*
Y75184D03*
Y85584D03*
X947461Y116497D03*
X952161Y116496D03*
Y109410D03*
Y102323D03*
X947461Y109410D03*
Y130670D03*
X952161D03*
Y123583D03*
X947461D03*
X952161Y137756D03*
X949443Y208206D03*
X949579Y330517D03*
X949813Y336817D03*
X956863Y451466D03*
X953816Y555194D03*
X951016D03*
X953816Y571194D03*
X951016D03*
X953816Y563194D03*
X951016D03*
X946625Y581222D03*
X949425D03*
Y591215D03*
X946625D03*
X948427Y611091D03*
X957551Y698251D03*
X954023Y725336D03*
X951195Y727165D03*
X952681Y735256D03*
X956323Y748412D03*
X957474Y764426D03*
X955086Y779798D03*
X956051Y793937D03*
X947735Y824921D03*
X948935Y835800D03*
X954700Y842700D03*
X947735Y854935D03*
X953091Y857440D03*
X953217Y861440D03*
X955967Y860376D03*
X946700Y849200D03*
X950251Y874268D03*
X950291Y870240D03*
Y866240D03*
X953145Y874240D03*
X952738Y886624D03*
X953587Y902814D03*
X961479Y927643D03*
X957671Y991564D03*
X946642Y991361D03*
X961033Y1091391D03*
X948883Y1102760D03*
X948867Y1098724D03*
X955032Y1095407D03*
X961033Y1095984D03*
X957167Y1208069D03*
X958864Y1227209D03*
X949970Y1321749D03*
X952070Y1367717D03*
X949070D03*
X956238Y1455139D03*
Y1458139D03*
Y1461139D03*
Y1464139D03*
X952676Y1461039D03*
Y1464039D03*
Y1458039D03*
Y1455039D03*
X956238Y1467139D03*
Y1469902D03*
X952676Y1467039D03*
X946470Y1510528D03*
Y1505328D03*
X947094Y1545353D03*
Y1542353D03*
X951457Y1639797D03*
X963177Y92849D03*
X970137Y103037D03*
X970271Y116496D03*
Y109410D03*
Y130670D03*
Y123583D03*
X966347Y137756D03*
X974952Y293796D03*
X972452D03*
X972147Y323681D03*
X975932Y437508D03*
X971932D03*
X962769Y458466D03*
X973695Y448874D03*
X969109Y449352D03*
X978723Y504699D03*
X976223D03*
X973723D03*
X978425Y516979D03*
X973425D03*
X975925D03*
X967302Y627948D03*
X969491Y629362D03*
X963187Y667620D03*
X973138Y667621D03*
X978059Y747438D03*
X976764Y786563D03*
X964070Y807686D03*
Y813006D03*
X977218Y802178D03*
X964036Y818961D03*
X968319Y826191D03*
X976635Y835018D03*
X976800Y838011D03*
X974282D03*
X976902Y847135D03*
X971808Y851242D03*
X975925Y854783D03*
X978201Y897500D03*
X969806Y993033D03*
X965716Y1091346D03*
X965671Y1095940D03*
X967148Y1123803D03*
X969748D03*
X969648Y1114103D03*
X967048D03*
X972348Y1123803D03*
X975048D03*
X972248Y1114103D03*
X974948D03*
X970485Y1132870D03*
X967885D03*
X968874Y1145169D03*
X966374D03*
X965917Y1236799D03*
Y1229899D03*
Y1232399D03*
Y1246199D03*
Y1243699D03*
Y1239299D03*
X978727Y1284908D03*
X971467Y1509515D03*
X974067D03*
X972567Y1512115D03*
X969967D03*
X976667Y1509515D03*
X977767Y1506915D03*
X975167D03*
X969967D03*
X972567D03*
X975167Y1512115D03*
X977767D03*
X971140Y1514693D03*
X968540D03*
X973740D03*
X976340D03*
X971457Y1639797D03*
X983554Y94017D03*
X987554D03*
X991554D03*
X987682Y115401D03*
X992674D03*
Y110445D03*
X987682D03*
X992674Y124618D03*
X987682D03*
Y129574D03*
X992674D03*
X985595Y151540D03*
X989245Y191941D03*
X989112Y188727D03*
X983069Y226141D03*
X985869D03*
X990939Y256535D03*
X985766Y288190D03*
X982966D03*
X985766Y285690D03*
X982966D03*
X980466Y288190D03*
Y285690D03*
X993992Y290755D03*
X989992D03*
X979932Y437508D03*
X982792Y447269D03*
X982670Y450201D03*
X989936Y519531D03*
X987436D03*
X982436D03*
X984936D03*
X983843Y633205D03*
Y636005D03*
Y638805D03*
X984307Y748432D03*
X985030Y781204D03*
X988329Y781445D03*
X991990Y773974D03*
X984963Y785387D03*
X979313Y814316D03*
X987903Y818645D03*
X993061Y833135D03*
X979203Y837159D03*
X988820Y858903D03*
X980529Y879097D03*
X988231Y878203D03*
X984892Y868720D03*
X987790Y896596D03*
X995133Y888503D03*
X982787Y899757D03*
X988461Y1013841D03*
X980726Y1080659D03*
Y1088659D03*
X981087Y1101902D03*
X988389Y1302558D03*
X980501Y1369685D03*
X983501D03*
X979538Y1464039D03*
Y1461039D03*
Y1458039D03*
Y1455039D03*
Y1467039D03*
Y1469802D03*
X979267Y1509515D03*
X984467D03*
X981867D03*
X985567Y1512115D03*
Y1506915D03*
X980367D03*
X982967D03*
Y1512115D03*
X980367D03*
X989667Y1509515D03*
X992267D03*
X987067D03*
X988167Y1512115D03*
X990767D03*
Y1506915D03*
X988167D03*
X984140Y1514693D03*
X981540D03*
X978940D03*
X986740D03*
X989340D03*
X991457Y1639797D03*
X1005256Y-25113D03*
X1002003Y-25027D03*
X1005241Y-27628D03*
X1001988Y-27542D03*
X1008281Y-26433D03*
X1000631Y84140D03*
Y76140D03*
Y80140D03*
X995563Y94017D03*
X1003076Y117557D03*
X998084D03*
X1003076Y122513D03*
Y131731D03*
X998084Y122513D03*
Y131731D03*
X1001175Y146461D03*
X1003076Y136687D03*
X998084D03*
X1000077Y152367D03*
X1001777Y180572D03*
X1006460Y180527D03*
X1010183Y192421D03*
X1001777Y185165D03*
X1006415Y185121D03*
X995745Y184619D03*
X997725Y206760D03*
X998939Y256535D03*
X999826Y278734D03*
X1004061Y280808D03*
X997992Y290755D03*
X1004544Y318050D03*
X1004933Y314535D03*
X997921Y333654D03*
X995913Y633450D03*
Y636250D03*
Y639050D03*
X1008342Y761735D03*
X1003539Y762632D03*
X1002834Y777394D03*
X1006053Y787745D03*
X999825Y819488D03*
X1002887Y834342D03*
X1000369D03*
X1005607Y874859D03*
Y877859D03*
X1002930Y906785D03*
X1010009Y998100D03*
X1005301Y1006560D03*
X999700Y1018400D03*
X1008312Y1363533D03*
X1008452Y1376752D03*
X1008483Y1372734D03*
X1006211Y1397662D03*
X1009338Y1391597D03*
Y1388597D03*
X1002538Y1463939D03*
Y1460939D03*
Y1457939D03*
Y1454939D03*
Y1466939D03*
Y1469702D03*
X1008549Y1509815D03*
X1007049Y1507215D03*
X1011149Y1509815D03*
X1009649Y1507215D03*
Y1512415D03*
X1007049D03*
X1008222Y1514993D03*
X1005622D03*
X1010822D03*
X1023373Y60922D03*
X1018209Y55513D03*
X1020254Y97068D03*
X1014006Y117261D03*
X1021537Y113394D03*
X1024186Y110784D03*
X1024289Y130898D03*
X1025927Y134579D03*
X1021713Y180665D03*
Y172665D03*
X1026915Y203393D03*
X1021745Y212864D03*
Y200864D03*
Y221864D03*
Y216864D03*
X1023502Y252371D03*
X1013354Y323362D03*
X1013327Y327453D03*
X1013318Y333190D03*
X1022845Y340944D03*
X1013313Y339909D03*
X1015195Y428305D03*
X1015804Y760454D03*
X1026090Y770943D03*
X1019375Y783056D03*
X1018044Y793592D03*
X1015800Y807535D03*
X1014587Y802788D03*
X1025859Y802275D03*
X1020703Y833659D03*
X1021221Y848712D03*
X1025219Y842155D03*
X1025239Y845070D03*
X1022009Y997860D03*
X1018009D03*
X1026009D03*
X1014009D03*
X1014767Y1035088D03*
X1022594Y1035114D03*
X1017297Y1102091D03*
X1026606Y1102591D03*
X1023106Y1102091D03*
X1017297Y1114691D03*
X1023106D03*
X1026606D03*
X1023106Y1127291D03*
X1026606D03*
X1017297Y1139891D03*
X1023106D03*
X1026606D03*
X1017297Y1127291D03*
X1026606Y1152491D03*
X1017297D03*
X1023106D03*
X1017297Y1165091D03*
X1023106D03*
X1026606D03*
X1017297Y1177691D03*
X1023106D03*
X1026606D03*
X1022420Y1203204D03*
X1026968Y1223749D03*
X1025434Y1320606D03*
X1011829Y1347471D03*
Y1342515D03*
X1015286Y1344924D03*
X1021623Y1373216D03*
X1012338Y1388597D03*
Y1391597D03*
X1015338D03*
Y1388597D03*
X1021338D03*
Y1391597D03*
X1018338D03*
Y1388597D03*
X1027338D03*
Y1391597D03*
X1024338D03*
Y1388597D03*
X1025138Y1463839D03*
Y1460839D03*
Y1457839D03*
Y1454839D03*
Y1466839D03*
Y1469602D03*
X1013749Y1509815D03*
X1016349D03*
X1021549D03*
X1018949D03*
X1024149D03*
X1022649Y1507215D03*
X1025249D03*
X1017449D03*
X1020049D03*
X1014849D03*
X1012249D03*
X1026749Y1509815D03*
X1012249Y1512415D03*
X1014849D03*
X1025249D03*
X1022649D03*
X1020049D03*
X1017449D03*
X1013422Y1514993D03*
X1023822D03*
X1021222D03*
X1018622D03*
X1016022D03*
X1026422D03*
X1011457Y1639797D03*
X1036772Y109172D03*
X1039772D03*
X1038779Y106495D03*
X1042523Y116497D03*
X1031780Y133298D03*
X1042523Y130670D03*
Y123584D03*
X1038513Y146012D03*
X1040419Y141228D03*
X1042523Y137757D03*
X1043307Y150847D03*
X1037984Y253198D03*
X1031354Y325901D03*
X1031382Y340947D03*
X1031310Y337888D03*
X1031377Y333671D03*
X1031362Y329268D03*
X1038796Y763272D03*
X1042880Y794924D03*
X1028155Y879413D03*
X1030300Y881400D03*
X1043252Y902501D03*
X1030009Y997860D03*
X1034009D03*
X1038252Y1009354D03*
X1034752D03*
X1028943D03*
X1042009Y997860D03*
X1038009D03*
X1034752Y1021954D03*
X1038252D03*
X1043553Y1035384D03*
X1040600Y1210600D03*
X1035384Y1215195D03*
X1034513Y1333665D03*
X1042586Y1345824D03*
X1030338Y1391597D03*
Y1388597D03*
X1029349Y1509815D03*
X1027849Y1507215D03*
Y1512415D03*
X1031457Y1639797D03*
X1049823Y109410D03*
X1054523Y116496D03*
Y109410D03*
Y102323D03*
X1049823Y116497D03*
X1047323D03*
X1049823Y130670D03*
X1047323D03*
Y123584D03*
X1049823Y123583D03*
X1054523Y130670D03*
Y123583D03*
Y137756D03*
X1047323Y137757D03*
X1045275Y247292D03*
X1050777Y450750D03*
X1054876Y536382D03*
X1059843Y597580D03*
X1059782Y594668D03*
X1062098Y615600D03*
X1044112Y778835D03*
X1045744Y800835D03*
X1048328Y808166D03*
X1057961Y931919D03*
X1046009Y997860D03*
X1054009D03*
X1050009D03*
X1058009D03*
X1059689Y1012354D03*
Y1024954D03*
X1048043Y1105091D03*
Y1117691D03*
Y1130291D03*
Y1155491D03*
Y1142891D03*
Y1168091D03*
Y1180691D03*
X1051249Y1290288D03*
X1052221Y1336984D03*
X1058891Y1345691D03*
Y1350683D03*
X1053935Y1345691D03*
Y1350683D03*
X1058891Y1362595D03*
X1053935D03*
X1058891Y1357603D03*
X1053935D03*
X1058891Y1381801D03*
Y1374881D03*
Y1369889D03*
X1053935Y1381801D03*
Y1374881D03*
Y1369889D03*
X1058891Y1386793D03*
X1053935D03*
X1051457Y1639797D03*
X1071988Y-66722D03*
X1075241Y-66808D03*
X1072003Y-64207D03*
X1075256Y-64293D03*
X1062985Y82984D03*
Y75184D03*
Y77784D03*
Y80384D03*
X1065539Y92849D03*
X1062985Y85584D03*
X1072499Y103037D03*
X1072633Y116496D03*
Y109410D03*
Y130670D03*
Y123583D03*
X1069224Y137756D03*
X1074814Y293796D03*
X1061325Y339509D03*
X1060679Y360151D03*
Y364276D03*
X1071548Y555234D03*
X1071263Y562003D03*
X1062066Y599588D03*
X1061328Y589556D03*
X1061267Y592354D03*
X1062069Y596095D03*
X1062066Y607588D03*
X1066559Y634946D03*
X1066009Y997860D03*
X1062009D03*
X1074009D03*
X1070778Y1012252D03*
X1066933Y1040567D03*
X1071641Y1058029D03*
X1060172Y1050481D03*
X1071348Y1050503D03*
X1066175Y1350683D03*
Y1345691D03*
X1071131Y1350683D03*
Y1345691D03*
X1066175Y1357603D03*
Y1362595D03*
X1071131Y1357603D03*
Y1362595D03*
X1066175Y1381801D03*
Y1369795D03*
Y1374881D03*
X1071131Y1381801D03*
Y1369795D03*
Y1374881D03*
X1066175Y1393993D03*
Y1399079D03*
Y1386793D03*
X1071131Y1399079D03*
Y1393993D03*
Y1386793D03*
X1066175Y1405999D03*
Y1410991D03*
X1071131Y1405999D03*
Y1410991D03*
X1071457Y1639797D03*
X1078281Y-65613D03*
X1089916Y94017D03*
X1085916D03*
X1090044Y110445D03*
Y115401D03*
Y124618D03*
Y129574D03*
X1087957Y151540D03*
X1091607Y191941D03*
X1091474Y188727D03*
X1085431Y226141D03*
X1088231D03*
X1088128Y285690D03*
Y288190D03*
X1085328D03*
X1082828Y285690D03*
X1085328D03*
X1082828Y288190D03*
X1077314Y293796D03*
X1092354Y290755D03*
X1077602Y314060D03*
X1091542Y389154D03*
Y410413D03*
Y396240D03*
Y403327D03*
Y417500D03*
Y424587D03*
Y431673D03*
Y438760D03*
Y445847D03*
Y467539D03*
Y474626D03*
Y488799D03*
Y481713D03*
Y495886D03*
Y511673D03*
Y518760D03*
Y525847D03*
Y532933D03*
Y540020D03*
Y547106D03*
X1090823Y602197D03*
X1091287Y595108D03*
X1079809Y1034386D03*
X1090655Y1350683D03*
Y1345691D03*
X1083371D03*
Y1350683D03*
X1078415Y1345691D03*
Y1350683D03*
X1090655Y1357603D03*
Y1362595D03*
X1083371Y1357603D03*
Y1362595D03*
X1078415D03*
Y1357603D03*
X1090655Y1381801D03*
Y1374881D03*
Y1369889D03*
X1083371D03*
Y1374881D03*
Y1381801D03*
X1078415Y1369889D03*
Y1374881D03*
Y1381801D03*
X1090655Y1394087D03*
Y1399079D03*
Y1386793D03*
X1083371D03*
Y1399079D03*
Y1394087D03*
X1078415Y1386793D03*
Y1394087D03*
Y1399079D03*
X1090655Y1405999D03*
Y1410991D03*
X1083371Y1405999D03*
Y1410991D03*
X1078415Y1405999D03*
Y1410991D03*
X1092000Y1644980D03*
X1102993Y84140D03*
Y76140D03*
Y80140D03*
X1097925Y94017D03*
X1093916D03*
X1100446Y117557D03*
X1095036Y115401D03*
Y110445D03*
X1105438Y117557D03*
X1095036Y129574D03*
Y124618D03*
X1105438Y131731D03*
Y122513D03*
X1100446Y131731D03*
Y122513D03*
X1103537Y146461D03*
X1100446Y136687D03*
X1105438D03*
X1102439Y152367D03*
X1104139Y180572D03*
X1108822Y180527D03*
X1104139Y185165D03*
X1108777Y185121D03*
X1098107Y184619D03*
X1100087Y206760D03*
X1101301Y256535D03*
X1093301D03*
X1102331Y279208D03*
X1106435Y281307D03*
X1096354Y290755D03*
X1100354D03*
X1100703Y340560D03*
X1101999Y353495D03*
X1093994Y374003D03*
X1106161Y389154D03*
X1104691Y396240D03*
X1108776Y422864D03*
X1108846Y429832D03*
X1108451Y436447D03*
X1108395Y472772D03*
X1105002Y516841D03*
X1108253Y510565D03*
X1099949Y550123D03*
X1099827Y552872D03*
X1101581Y572334D03*
X1099272Y562443D03*
X1101040Y560675D03*
X1099813Y574102D03*
X1104448Y653161D03*
X1108045Y677843D03*
X1107851Y1345691D03*
X1102895Y1350683D03*
Y1345691D03*
X1107851Y1350683D03*
X1095611D03*
Y1345691D03*
X1107851Y1357603D03*
X1102895Y1362595D03*
Y1357603D03*
X1107851Y1362595D03*
X1095611Y1357603D03*
Y1362595D03*
X1107851Y1369889D03*
Y1374881D03*
Y1381801D03*
X1102895Y1374881D03*
Y1369889D03*
Y1381801D03*
X1095611D03*
Y1374881D03*
Y1369889D03*
X1107851Y1386793D03*
Y1394087D03*
Y1399079D03*
X1102895Y1386793D03*
Y1394087D03*
Y1399079D03*
X1095611D03*
Y1394087D03*
Y1386793D03*
X1107851Y1405999D03*
Y1410991D03*
X1102895Y1405999D03*
Y1410991D03*
X1095611Y1405999D03*
Y1410991D03*
X1099900Y1535700D03*
X1107620Y1606752D03*
X1123052Y57511D03*
X1122613Y97042D03*
X1116368Y117261D03*
X1123899Y113394D03*
X1124075Y180665D03*
Y172665D03*
X1112545Y192421D03*
X1124107Y200864D03*
Y212864D03*
Y216864D03*
Y221864D03*
X1123500Y329000D03*
Y339000D03*
Y334000D03*
X1124753Y389153D03*
X1122253Y396240D03*
X1124753D03*
X1122253Y403327D03*
X1124753Y403326D03*
X1122253Y410413D03*
X1124753D03*
X1109468Y414823D03*
X1122253Y424586D03*
X1124753D03*
X1122253Y417500D03*
X1124753Y417499D03*
X1122253Y438760D03*
X1124753D03*
Y431673D03*
X1122253D03*
X1110486Y447953D03*
X1122253Y445847D03*
X1109653Y467539D03*
X1124753D03*
X1122253Y474626D03*
X1124753D03*
X1122253Y488799D03*
X1124753D03*
X1109129Y487711D03*
X1109242Y479104D03*
X1124753Y481712D03*
X1122253D03*
Y495886D03*
X1109653D03*
X1124753Y518760D03*
X1122253D03*
X1124753Y511673D03*
Y532933D03*
X1122253D03*
Y540020D03*
Y525846D03*
X1124753D03*
X1118863Y662981D03*
X1112839Y668885D03*
X1113244Y691851D03*
X1118855Y705043D03*
X1115135Y1345691D03*
Y1350683D03*
X1120091Y1345691D03*
Y1350683D03*
X1115135Y1357603D03*
Y1362595D03*
X1120091Y1357603D03*
Y1362595D03*
X1115135Y1374881D03*
Y1381801D03*
Y1369889D03*
X1120091D03*
Y1374881D03*
Y1381801D03*
X1115135Y1394087D03*
Y1399079D03*
Y1386793D03*
X1120091Y1399079D03*
Y1394087D03*
Y1386793D03*
X1115135Y1405999D03*
Y1410991D03*
X1120091Y1405999D03*
Y1410991D03*
X1112000Y1644980D03*
X1125735Y60922D03*
X1139134Y109172D03*
X1141141Y106495D03*
X1126548Y110784D03*
X1134142Y133298D03*
X1126142D03*
X1140875Y146012D03*
X1128289Y134579D03*
X1129277Y203393D03*
X1140346Y253198D03*
X1125864Y252371D03*
X1129553Y389153D03*
Y396240D03*
Y403326D03*
Y410413D03*
Y424586D03*
Y417499D03*
Y431673D03*
Y438760D03*
X1126931Y453564D03*
X1130355Y453483D03*
X1129553Y467539D03*
X1125178Y459792D03*
X1129553Y474626D03*
Y488799D03*
Y481712D03*
Y518760D03*
Y511673D03*
Y532933D03*
Y525846D03*
X1138098Y543925D03*
X1138673Y555000D03*
X1126633Y560500D03*
X1139615Y1350683D03*
Y1345691D03*
X1132331D03*
Y1350683D03*
X1127375D03*
Y1345691D03*
X1139615Y1357603D03*
Y1362595D03*
X1132331D03*
Y1357603D03*
X1127375D03*
Y1362595D03*
X1139615Y1374881D03*
Y1369889D03*
Y1381801D03*
X1132331Y1369889D03*
Y1381801D03*
Y1374881D03*
X1127375Y1369889D03*
Y1381801D03*
Y1374881D03*
X1139615Y1394087D03*
Y1399079D03*
Y1386793D03*
X1132331D03*
Y1394087D03*
Y1399079D03*
X1127375Y1386793D03*
Y1394087D03*
Y1399079D03*
X1139615Y1405999D03*
Y1410991D03*
X1132331Y1405999D03*
Y1410991D03*
X1127375Y1405999D03*
Y1410991D03*
X1129637Y1465913D03*
Y1461182D03*
Y1456451D03*
X1138298Y1465513D03*
Y1460782D03*
X1129637Y1476536D03*
Y1481267D03*
X1138298Y1476136D03*
Y1470244D03*
Y1480867D03*
X1129637Y1471805D03*
Y1496621D03*
X1138298Y1491490D03*
Y1485598D03*
Y1496221D03*
X1129637Y1491890D03*
Y1487159D03*
X1138298Y1500952D03*
Y1511576D03*
X1129637Y1507245D03*
Y1502514D03*
Y1511976D03*
X1138298Y1506845D03*
Y1516307D03*
X1129637Y1563544D03*
Y1558813D03*
X1138298Y1563144D03*
Y1572606D03*
X1129637Y1568275D03*
Y1578898D03*
Y1574167D03*
X1138298Y1567875D03*
Y1578498D03*
X1129637Y1583629D03*
Y1594253D03*
Y1589522D03*
X1138298Y1583229D03*
Y1593853D03*
Y1587960D03*
Y1598584D03*
Y1603315D03*
X1129637Y1609607D03*
Y1598984D03*
Y1604876D03*
X1138298Y1609207D03*
X1129637Y1614338D03*
X1138298Y1613938D03*
Y1618669D03*
X1132000Y1644980D03*
X1142134Y109172D03*
X1156885Y116496D03*
Y102323D03*
Y109410D03*
X1152185D03*
Y116497D03*
X1149685D03*
X1144885D03*
X1152185Y130670D03*
X1149685D03*
Y123584D03*
X1152185Y123583D03*
X1144885Y130670D03*
Y123584D03*
X1156885Y130670D03*
Y123583D03*
X1142781Y141228D03*
X1156885Y137756D03*
X1149685Y137757D03*
X1144885D03*
X1145669Y150847D03*
X1147637Y247292D03*
X1145761Y324148D03*
X1157251Y636842D03*
X1156023Y678462D03*
X1149345Y771517D03*
X1145910Y794217D03*
X1151277Y790996D03*
X1149627Y813323D03*
X1146985Y812642D03*
X1152510Y844642D03*
X1156811Y1350683D03*
Y1345691D03*
X1151855D03*
Y1350683D03*
X1144571D03*
Y1345691D03*
X1156811Y1357603D03*
Y1362595D03*
X1151855D03*
Y1357603D03*
X1144571D03*
Y1362595D03*
X1156811Y1374881D03*
Y1369889D03*
Y1381801D03*
X1151855Y1374881D03*
Y1369889D03*
Y1381801D03*
X1144571Y1369889D03*
Y1381801D03*
Y1374881D03*
X1156811Y1386793D03*
Y1399079D03*
Y1394087D03*
X1151855Y1386793D03*
Y1399079D03*
Y1394087D03*
X1144571D03*
Y1399079D03*
Y1386793D03*
X1156811Y1405999D03*
Y1410991D03*
X1151855Y1405999D03*
Y1410991D03*
X1144571Y1405999D03*
Y1410991D03*
X1146960Y1465913D03*
Y1461182D03*
X1155621Y1465513D03*
Y1460782D03*
X1146960Y1456451D03*
X1155621Y1480867D03*
X1146960Y1471805D03*
Y1476536D03*
Y1481267D03*
X1155621Y1476136D03*
Y1470244D03*
Y1491490D03*
Y1485598D03*
Y1496221D03*
X1146960Y1487159D03*
Y1491890D03*
Y1496621D03*
Y1507245D03*
Y1502514D03*
X1155621Y1506845D03*
Y1500952D03*
Y1511576D03*
X1146960Y1511976D03*
X1155621Y1516307D03*
X1146960Y1563544D03*
X1155621Y1563144D03*
X1146960Y1558813D03*
X1155621Y1572606D03*
X1146960Y1568275D03*
X1155621Y1567875D03*
X1146960Y1574167D03*
Y1578898D03*
X1155621Y1578498D03*
X1146960Y1594253D03*
X1155621Y1593853D03*
Y1587960D03*
X1146960Y1583629D03*
X1155621Y1583229D03*
X1146960Y1589522D03*
Y1609607D03*
Y1604876D03*
Y1598984D03*
X1155621Y1609207D03*
Y1598584D03*
Y1603315D03*
X1146960Y1614338D03*
X1155621Y1613938D03*
Y1618669D03*
X1152000Y1644980D03*
X1165347Y82984D03*
Y75184D03*
Y77784D03*
Y80384D03*
X1167756Y92734D03*
X1165347Y85584D03*
X1171586Y137756D03*
X1168902Y431029D03*
X1167931Y435029D03*
X1169173Y427017D03*
X1168851Y449873D03*
X1171255Y456287D03*
X1173278Y472579D03*
X1168478D03*
X1173278Y479666D03*
X1168478D03*
Y486752D03*
X1173278D03*
X1168478Y493839D03*
X1173278D03*
X1168478Y523800D03*
Y516713D03*
X1173278D03*
Y523800D03*
Y537973D03*
X1168478D03*
X1173278Y530886D03*
X1168478D03*
X1173278Y566752D03*
X1168478D03*
Y580926D03*
X1173278D03*
Y588013D03*
X1168478D03*
X1173278Y573839D03*
X1168478D03*
Y602186D03*
X1173278D03*
Y595099D03*
X1168478D03*
X1173278Y609272D03*
X1168478D03*
Y616359D03*
X1173278D03*
X1163157Y638125D03*
X1160756Y665140D03*
X1157985Y791142D03*
X1161291Y791662D03*
X1173697Y791911D03*
X1160516Y800900D03*
X1169051Y1345597D03*
Y1350683D03*
X1164095D03*
Y1345597D03*
X1169051Y1357603D03*
Y1362595D03*
X1164095Y1357603D03*
Y1362595D03*
X1169051Y1381801D03*
Y1374881D03*
Y1369889D03*
X1164095D03*
Y1381801D03*
Y1374881D03*
X1169051Y1393993D03*
Y1399079D03*
Y1386793D03*
X1164095Y1393993D03*
Y1399079D03*
Y1386793D03*
X1169051Y1410991D03*
Y1405999D03*
X1164095D03*
Y1410991D03*
X1164283Y1465913D03*
Y1456451D03*
Y1461182D03*
X1172944Y1465513D03*
Y1460782D03*
Y1470244D03*
Y1480867D03*
X1164283Y1471805D03*
Y1476536D03*
Y1481267D03*
X1172944Y1476136D03*
X1164283Y1487159D03*
Y1491890D03*
Y1496621D03*
X1172944Y1491490D03*
Y1485598D03*
Y1496221D03*
X1164283Y1507245D03*
Y1502514D03*
X1172944Y1506845D03*
Y1500952D03*
Y1511576D03*
X1164283Y1511976D03*
X1172944Y1516307D03*
X1164283Y1558813D03*
Y1563544D03*
X1172944Y1563144D03*
Y1567875D03*
X1164283Y1574167D03*
Y1578898D03*
X1172944Y1578498D03*
Y1572606D03*
X1164283Y1568275D03*
Y1583629D03*
X1172944Y1583229D03*
X1164283Y1589522D03*
Y1594253D03*
X1172944Y1593853D03*
Y1587960D03*
Y1598584D03*
Y1603315D03*
X1164283Y1609607D03*
Y1604876D03*
Y1598984D03*
X1172944Y1609207D03*
X1164283Y1614338D03*
X1172944Y1613938D03*
Y1618669D03*
X1172000Y1644980D03*
X1188278Y94017D03*
X1174861Y103037D03*
X1174995Y116496D03*
Y109410D03*
Y130670D03*
Y123583D03*
X1187793Y226141D03*
X1190593D03*
X1179676Y293796D03*
X1187690Y288190D03*
X1185190Y285690D03*
X1187690D03*
X1185190Y288190D03*
X1177176Y293796D03*
X1182911Y336516D03*
X1177036Y334148D03*
X1188598Y390500D03*
X1179184Y410394D03*
Y403307D03*
X1180578Y458406D03*
Y451319D03*
X1180402Y462264D03*
X1175778Y465492D03*
X1180578D03*
X1175778Y472579D03*
X1180578D03*
X1175778Y479666D03*
X1180578Y479665D03*
Y486752D03*
X1175778D03*
X1180578Y493839D03*
X1175778Y509626D03*
X1180578Y523799D03*
Y516713D03*
Y509626D03*
X1175778Y516713D03*
Y523800D03*
X1180578Y537973D03*
X1175778Y530886D03*
X1180578D03*
Y559665D03*
Y566752D03*
X1175778D03*
Y559665D03*
Y580926D03*
X1180578D03*
Y588012D03*
X1175778D03*
X1180578Y573839D03*
X1175778D03*
Y602185D03*
X1180578D03*
X1175778Y595099D03*
X1180578D03*
X1175778Y609272D03*
X1180578Y616358D03*
Y609272D03*
X1177745Y771744D03*
X1177566Y778539D03*
X1190062Y844378D03*
X1187703Y849734D03*
X1186742Y855466D03*
X1183431Y868340D03*
X1177775Y894053D03*
X1178480Y915220D03*
X1178000Y936500D03*
X1187200Y963400D03*
X1181291Y1350683D03*
Y1345691D03*
X1176335D03*
Y1350683D03*
X1181291Y1362595D03*
Y1357603D03*
X1176335Y1362595D03*
Y1357603D03*
X1181291Y1369889D03*
Y1381801D03*
Y1374881D03*
X1176335Y1369889D03*
Y1381801D03*
Y1374881D03*
X1181291Y1386793D03*
Y1399079D03*
Y1394087D03*
X1176335Y1386793D03*
Y1399079D03*
Y1394087D03*
X1181291Y1405999D03*
Y1410991D03*
X1176335Y1405999D03*
Y1410991D03*
X1181605Y1465913D03*
Y1456451D03*
Y1461182D03*
Y1471805D03*
Y1476536D03*
Y1481267D03*
Y1487159D03*
Y1491890D03*
Y1496621D03*
Y1507245D03*
Y1502514D03*
Y1511976D03*
Y1558813D03*
Y1563544D03*
Y1568275D03*
Y1574167D03*
Y1578898D03*
Y1583629D03*
Y1589522D03*
Y1594253D03*
Y1598984D03*
Y1609607D03*
Y1604876D03*
Y1614338D03*
X1205355Y84140D03*
Y76140D03*
Y80140D03*
X1196278Y94017D03*
X1200287D03*
X1192278D03*
X1202808Y117557D03*
X1197398Y110445D03*
Y115401D03*
X1192406Y110445D03*
Y115401D03*
X1197398Y129574D03*
Y124618D03*
X1192406D03*
Y129574D03*
X1202808Y122513D03*
Y131731D03*
X1205899Y146461D03*
X1202808Y136687D03*
X1204801Y152367D03*
X1190319Y151540D03*
X1200469Y184619D03*
X1193969Y191941D03*
X1193836Y188727D03*
X1202449Y206760D03*
X1203663Y256535D03*
X1195663D03*
X1204693Y279208D03*
X1194716Y290755D03*
X1202716D03*
X1190490Y285690D03*
Y288190D03*
X1198716Y290755D03*
X1198248Y381500D03*
X1198689Y465492D03*
X1198655Y460250D03*
X1196420Y470136D03*
X1198689Y472579D03*
Y486752D03*
Y479665D03*
Y493839D03*
Y509626D03*
Y516713D03*
X1195149Y537973D03*
X1197629Y525483D03*
X1197550Y532756D03*
X1198689Y559665D03*
Y566752D03*
X1198539Y579978D03*
X1198689Y573839D03*
X1198753Y608117D03*
X1198997Y790610D03*
X1198845Y998504D03*
X1204919Y1021860D03*
X1202268Y1013551D03*
X1190267Y1465513D03*
Y1460782D03*
X1198928Y1465914D03*
Y1456452D03*
Y1461183D03*
Y1481268D03*
X1190267Y1476136D03*
Y1470244D03*
Y1480867D03*
X1198928Y1476537D03*
Y1471806D03*
X1190267Y1485598D03*
Y1496221D03*
X1198928Y1491891D03*
Y1487160D03*
Y1496622D03*
X1190267Y1491490D03*
Y1506845D03*
Y1500952D03*
Y1511576D03*
X1198928Y1507246D03*
Y1502515D03*
Y1511977D03*
X1190267Y1516307D03*
X1198928Y1558813D03*
X1190267Y1563144D03*
X1198928Y1563544D03*
X1190267Y1567875D03*
X1198928Y1568275D03*
X1190267Y1578498D03*
Y1572606D03*
X1198928Y1578898D03*
Y1574167D03*
X1190267Y1583229D03*
X1198928Y1583629D03*
X1190267Y1593853D03*
Y1587960D03*
X1198928Y1594253D03*
Y1589522D03*
X1190267Y1609207D03*
Y1598584D03*
Y1603315D03*
X1198928Y1609607D03*
Y1598984D03*
Y1604876D03*
X1190267Y1613938D03*
Y1618669D03*
X1198928Y1614338D03*
X1192000Y1644980D03*
X1218730Y117261D03*
X1207800Y117557D03*
Y122513D03*
Y131731D03*
Y136687D03*
X1206501Y180572D03*
X1211184Y180527D03*
X1214907Y192421D03*
X1206501Y185165D03*
X1211139Y185121D03*
X1208797Y281307D03*
X1220985Y342319D03*
X1212680Y445908D03*
X1216630Y445787D03*
X1212000Y1644980D03*
X1222933Y55513D03*
X1228097Y60922D03*
X1225041Y97080D03*
X1228910Y110784D03*
X1226261Y113394D03*
X1229195Y130898D03*
X1236504Y133298D03*
X1230651Y134579D03*
X1226437Y180665D03*
Y172665D03*
X1226469Y200864D03*
Y212864D03*
Y216864D03*
Y221864D03*
X1228226Y252371D03*
X1238055Y303839D03*
X1230077Y336324D03*
X1234656Y353506D03*
X1223431Y393924D03*
Y389912D03*
Y385912D03*
Y409924D03*
Y405924D03*
Y401924D03*
X1229548Y1350683D03*
Y1345691D03*
X1234504D03*
Y1350683D03*
X1229548Y1362595D03*
Y1357603D03*
X1234504D03*
Y1362595D03*
X1229548Y1369889D03*
Y1374881D03*
Y1381801D03*
X1234504Y1369889D03*
Y1374881D03*
Y1381801D03*
X1229548Y1386793D03*
X1234504D03*
X1232000Y1644980D03*
X1243503Y106495D03*
X1244496Y109172D03*
X1241496D03*
X1247247Y116497D03*
X1254547Y109410D03*
Y116497D03*
X1252047D03*
X1247247Y123584D03*
Y130670D03*
X1252047Y123584D03*
X1254547Y123583D03*
Y130670D03*
X1252047D03*
X1243237Y146012D03*
X1245143Y141228D03*
X1247247Y137757D03*
X1252047D03*
X1250307Y140296D03*
X1248031Y150847D03*
X1249999Y247292D03*
X1242708Y253198D03*
X1248064Y567813D03*
Y572769D03*
Y581987D03*
Y586943D03*
Y601116D03*
Y596160D03*
Y615289D03*
Y610333D03*
X1246800Y1001600D03*
X1249200Y1014000D03*
X1248721Y1025864D03*
X1251802Y1186071D03*
X1254028Y1350683D03*
Y1345691D03*
X1241788D03*
Y1350683D03*
X1246744Y1345691D03*
Y1350683D03*
X1254028Y1357603D03*
Y1362595D03*
X1241788D03*
Y1357603D03*
X1246744Y1362595D03*
Y1357603D03*
X1254028Y1381801D03*
Y1374881D03*
Y1369889D03*
X1241788Y1374881D03*
Y1369795D03*
Y1381801D03*
X1246744Y1374881D03*
Y1369795D03*
Y1381801D03*
X1254028Y1386793D03*
Y1399079D03*
Y1394087D03*
X1241788Y1399079D03*
Y1393993D03*
Y1386793D03*
X1246744Y1393993D03*
Y1399079D03*
Y1386793D03*
X1254028Y1410991D03*
Y1405999D03*
X1241788Y1410991D03*
Y1405999D03*
X1246744Y1410991D03*
Y1405999D03*
X1245900Y1528000D03*
X1267709Y82984D03*
Y75184D03*
Y77784D03*
Y80384D03*
X1270263Y92849D03*
X1267709Y85584D03*
X1259247Y116496D03*
Y102323D03*
Y109410D03*
Y130670D03*
Y123583D03*
Y137756D03*
X1258925Y324075D03*
X1270951Y491870D03*
X1270515Y908277D03*
X1269876Y1132319D03*
X1263873Y1148000D03*
X1266709Y1160168D03*
X1258736Y1188223D03*
X1268573Y1193019D03*
X1264573D03*
X1266268Y1345691D03*
Y1350683D03*
X1258984D03*
Y1345691D03*
X1266268Y1362595D03*
Y1357603D03*
X1258984Y1362595D03*
Y1357603D03*
X1266268Y1369889D03*
Y1374881D03*
Y1381801D03*
X1258984D03*
Y1369889D03*
Y1374881D03*
X1266268Y1399079D03*
Y1394087D03*
Y1386793D03*
X1258984Y1394087D03*
Y1386793D03*
Y1399079D03*
X1266268Y1410991D03*
Y1405999D03*
X1258984D03*
Y1410991D03*
X1263242Y1523458D03*
X1262985Y1519459D03*
X1260260Y1546500D03*
X1277223Y103037D03*
X1277357Y116496D03*
Y109410D03*
Y130670D03*
Y123583D03*
X1273555Y137756D03*
X1279538Y293796D03*
X1282038D03*
X1283494Y339495D03*
X1287437Y370010D03*
X1280616Y472189D03*
X1273451Y491870D03*
X1279539Y772576D03*
Y776576D03*
X1274417Y861964D03*
X1282317Y880193D03*
X1285493Y892175D03*
X1277039Y916484D03*
X1284021Y940008D03*
X1273865Y1132497D03*
X1282830Y1146937D03*
X1272120Y1159455D03*
X1280306Y1162817D03*
X1276573Y1193019D03*
X1280573D03*
X1272573D03*
X1277108Y1211664D03*
X1279402Y1213958D03*
X1275032Y1209589D03*
X1284198Y1218754D03*
X1283464Y1345691D03*
Y1350683D03*
X1278508Y1345691D03*
Y1350683D03*
X1271224Y1345691D03*
Y1350683D03*
X1283464Y1362595D03*
Y1357603D03*
X1278508D03*
Y1362595D03*
X1271224D03*
Y1357603D03*
X1283464Y1381801D03*
Y1369889D03*
Y1374881D03*
X1278508Y1381801D03*
Y1369889D03*
Y1374881D03*
X1271224Y1369889D03*
Y1374881D03*
Y1381801D03*
X1283464Y1386793D03*
Y1399079D03*
Y1394087D03*
X1278508Y1386793D03*
Y1399079D03*
Y1394087D03*
X1271224D03*
Y1399079D03*
Y1386793D03*
X1283464Y1410991D03*
Y1405999D03*
X1278508Y1410991D03*
Y1405999D03*
X1271224Y1410991D03*
Y1405999D03*
X1291756Y-25143D03*
X1288503Y-25157D03*
X1291741Y-27658D03*
X1288488Y-27672D03*
X1294781Y-26463D03*
X1302649Y94017D03*
X1298640D03*
X1290640D03*
X1294640D03*
X1299760Y110445D03*
Y115401D03*
X1294768Y110445D03*
Y115401D03*
Y129574D03*
X1299760D03*
Y124618D03*
X1294768D03*
X1296331Y191941D03*
X1302831Y184619D03*
X1296198Y188727D03*
X1292955Y226141D03*
X1290155D03*
X1298025Y256535D03*
X1290052Y288190D03*
X1292852D03*
Y285690D03*
X1305078Y290755D03*
X1297078D03*
X1301078D03*
X1287552Y288190D03*
X1290052Y285690D03*
X1287552D03*
X1294425Y321425D03*
X1299959Y351454D03*
X1296783Y511956D03*
X1303520Y748403D03*
X1300516Y832047D03*
X1300504Y835985D03*
X1300204Y859088D03*
X1300097Y851193D03*
X1300091Y854824D03*
X1291955Y901295D03*
X1289547Y928047D03*
X1298090Y940852D03*
X1295453Y940953D03*
X1302988Y1345691D03*
Y1350683D03*
X1290748D03*
Y1345691D03*
X1295704Y1350683D03*
Y1345691D03*
X1302988Y1362595D03*
Y1357603D03*
X1290748Y1362595D03*
Y1357603D03*
X1295704Y1362595D03*
Y1357603D03*
X1302988Y1374881D03*
Y1381801D03*
Y1369889D03*
X1290748D03*
Y1381801D03*
Y1374881D03*
X1295704Y1381801D03*
Y1374881D03*
Y1369889D03*
X1302988Y1386793D03*
Y1399079D03*
Y1394087D03*
X1290748Y1399079D03*
Y1394087D03*
Y1386793D03*
X1295704Y1394087D03*
Y1399079D03*
Y1386793D03*
X1302988Y1410991D03*
Y1405999D03*
X1290748Y1410991D03*
Y1405999D03*
X1295704Y1410991D03*
Y1405999D03*
X1302866Y1461182D03*
Y1456451D03*
Y1465913D03*
Y1476536D03*
Y1471805D03*
Y1481267D03*
Y1491890D03*
Y1487159D03*
Y1496621D03*
Y1507245D03*
Y1502514D03*
Y1511976D03*
Y1558813D03*
Y1563544D03*
Y1578898D03*
Y1574167D03*
Y1568275D03*
Y1594253D03*
Y1589522D03*
Y1583629D03*
Y1609607D03*
Y1598984D03*
Y1604876D03*
Y1614338D03*
X1292000Y1644980D03*
X1307717Y84140D03*
Y76140D03*
Y80140D03*
X1310162Y117557D03*
X1305170D03*
X1310162Y122513D03*
Y131731D03*
X1305170Y122513D03*
Y131731D03*
X1310162Y136687D03*
X1305170D03*
X1313546Y180527D03*
X1308863Y180572D03*
Y185165D03*
X1317269Y192421D03*
X1313501Y185121D03*
X1304811Y206760D03*
X1306025Y256535D03*
X1307055Y279208D03*
X1311159Y281307D03*
X1314569Y318013D03*
X1312069D03*
X1317584Y313058D03*
X1316017Y349889D03*
X1308410Y370899D03*
X1313691Y402642D03*
X1316191D03*
X1309117Y398949D03*
X1306617Y401949D03*
X1308066Y413611D03*
X1310866D03*
X1313366D03*
X1315866D03*
X1315806Y423944D03*
X1313306D03*
X1310806D03*
X1308006D03*
X1307919Y478382D03*
X1307825Y482382D03*
X1305134Y812065D03*
X1313756Y829871D03*
X1308857Y836076D03*
X1316906Y842470D03*
Y867665D03*
Y883413D03*
Y892862D03*
X1316893Y925603D03*
X1318375Y943951D03*
X1303907Y960093D03*
X1307580Y990314D03*
X1304664Y1023462D03*
X1309937Y1037038D03*
X1319326Y1040723D03*
X1317437Y1152684D03*
X1307167Y1245696D03*
X1308276Y1276446D03*
X1315228Y1345691D03*
Y1350683D03*
X1307944D03*
Y1345691D03*
X1315228Y1362595D03*
Y1357603D03*
X1307944D03*
Y1362595D03*
X1315228Y1381801D03*
Y1369889D03*
Y1374881D03*
X1307944D03*
Y1381801D03*
Y1369889D03*
X1315228Y1399079D03*
Y1394087D03*
Y1386793D03*
X1307944D03*
Y1399079D03*
Y1394087D03*
X1315228Y1410991D03*
Y1405999D03*
X1307944Y1410991D03*
Y1405999D03*
X1311527Y1465513D03*
Y1460782D03*
Y1480867D03*
Y1476136D03*
Y1470244D03*
Y1491490D03*
Y1485598D03*
Y1496221D03*
Y1506845D03*
Y1500952D03*
Y1511576D03*
Y1516307D03*
Y1563144D03*
Y1567875D03*
Y1578498D03*
Y1572606D03*
Y1583229D03*
Y1593853D03*
Y1587960D03*
Y1609207D03*
Y1598584D03*
Y1603315D03*
Y1613938D03*
Y1618669D03*
X1312000Y1644980D03*
X1331756Y-64193D03*
X1328503Y-64207D03*
X1331741Y-66708D03*
X1328488Y-66722D03*
X1334781Y-65513D03*
X1321092Y117261D03*
X1328799Y172665D03*
Y180665D03*
X1328831Y212864D03*
Y200864D03*
Y221864D03*
Y216864D03*
X1330414Y310058D03*
X1325458D03*
X1322540Y313058D03*
X1333332D03*
X1331085Y334347D03*
X1323816D03*
Y341615D03*
X1331085Y348868D03*
X1323816D03*
X1332927Y468607D03*
X1326912Y493153D03*
X1325630Y513238D03*
X1335000Y590500D03*
Y586500D03*
Y633000D03*
Y637000D03*
Y677500D03*
Y681500D03*
Y724500D03*
Y728500D03*
X1324217Y780595D03*
X1332654Y836170D03*
X1323205Y861367D03*
X1335803Y851918D03*
Y877114D03*
X1326355Y886562D03*
X1328457Y959986D03*
X1321104Y964398D03*
X1323554Y967623D03*
X1331890Y1051919D03*
X1331359Y1098898D03*
X1334161Y1098518D03*
X1333905Y1123101D03*
X1331405D03*
X1323405D03*
X1320279Y1131935D03*
Y1134435D03*
Y1136935D03*
Y1139435D03*
X1334305Y1129301D03*
X1331805D03*
X1329305D03*
X1326805D03*
X1324305D03*
X1321805D03*
X1334305Y1125801D03*
X1331805D03*
X1323405D03*
X1320279Y1141935D03*
Y1146935D03*
Y1144435D03*
X1326269Y1152713D03*
Y1155213D03*
X1320493Y1204405D03*
X1334793Y1204617D03*
X1320493Y1206905D03*
Y1211905D03*
Y1209405D03*
X1334793Y1207117D03*
Y1209617D03*
Y1212117D03*
X1330070Y1297498D03*
X1335470D03*
X1332424Y1345691D03*
Y1350683D03*
X1327468D03*
Y1345691D03*
X1320184Y1350683D03*
Y1345691D03*
X1332424Y1362595D03*
Y1357603D03*
X1327468D03*
Y1362595D03*
X1320184D03*
Y1357603D03*
X1332424Y1381801D03*
Y1369889D03*
Y1374881D03*
X1327468Y1381801D03*
Y1369889D03*
Y1374881D03*
X1320184Y1381801D03*
Y1374881D03*
Y1369889D03*
X1332424Y1386793D03*
Y1394087D03*
Y1399079D03*
X1327468Y1386793D03*
Y1394087D03*
Y1399079D03*
X1320184D03*
Y1394087D03*
Y1386793D03*
X1332424Y1410991D03*
Y1405999D03*
X1327468Y1410991D03*
Y1405999D03*
X1320184Y1410991D03*
Y1405999D03*
X1328850Y1465513D03*
Y1460782D03*
X1320189Y1465913D03*
Y1456451D03*
Y1461182D03*
X1328850Y1476136D03*
Y1470244D03*
X1320189Y1481267D03*
X1328850Y1480867D03*
X1320189Y1471805D03*
Y1476536D03*
X1328850Y1491490D03*
Y1485598D03*
X1320189Y1496621D03*
X1328850Y1496221D03*
X1320189Y1487159D03*
Y1491890D03*
Y1502514D03*
X1328850Y1506845D03*
Y1500952D03*
Y1511576D03*
X1320189Y1511976D03*
Y1507245D03*
X1328850Y1516307D03*
X1320189Y1558813D03*
Y1563544D03*
X1328850Y1563144D03*
Y1567875D03*
X1320189Y1574167D03*
Y1578898D03*
X1328850Y1578498D03*
Y1572606D03*
X1320189Y1568275D03*
X1328850Y1583229D03*
X1320189Y1589522D03*
Y1594253D03*
X1328850Y1593853D03*
Y1587960D03*
X1320189Y1583629D03*
X1328850Y1603315D03*
X1320189Y1609607D03*
Y1604876D03*
Y1598984D03*
X1328850Y1609207D03*
Y1598584D03*
Y1613938D03*
Y1618669D03*
X1320189Y1614338D03*
X1332000Y1644980D03*
X1340320Y151540D03*
X1338288Y313058D03*
X1338378Y334347D03*
X1338275Y341603D03*
X1338378Y348830D03*
X1345451Y699032D03*
X1347136Y780040D03*
X1351550Y839320D03*
Y855068D03*
X1345252D03*
X1342103D03*
Y861367D03*
X1338953D03*
Y858218D03*
X1338952Y855067D03*
X1338953Y870814D03*
X1342103Y867665D03*
X1338953D03*
X1351550Y873964D03*
X1345252D03*
X1342103D03*
X1338952Y873965D03*
X1345252Y892862D03*
X1341820Y947407D03*
X1347380Y1057998D03*
Y1055498D03*
X1344880D03*
Y1057998D03*
X1347380Y1060498D03*
Y1062998D03*
X1344880D03*
Y1060498D03*
X1339349Y1098767D03*
X1339305Y1129301D03*
X1336805D03*
X1339305Y1125801D03*
X1336805D03*
X1343505Y1136935D03*
Y1134435D03*
Y1139435D03*
Y1131935D03*
X1349907D03*
Y1134435D03*
Y1136935D03*
Y1139435D03*
X1352407Y1131935D03*
Y1134435D03*
Y1136935D03*
Y1139435D03*
X1343505Y1146935D03*
Y1144435D03*
Y1141935D03*
X1349907D03*
Y1146935D03*
Y1144435D03*
X1352407Y1141935D03*
Y1146935D03*
Y1144435D03*
X1336669Y1152713D03*
Y1155213D03*
X1351405Y1154902D03*
Y1152402D03*
X1347423Y1204405D03*
X1337108Y1200821D03*
Y1198321D03*
X1347423Y1209405D03*
Y1211905D03*
Y1206905D03*
X1340870Y1297498D03*
X1346270D03*
X1351670D03*
X1351948Y1350683D03*
Y1345691D03*
X1339708Y1345597D03*
Y1350683D03*
X1344664Y1345597D03*
Y1350683D03*
X1351948Y1357603D03*
Y1362595D03*
X1339708D03*
Y1357603D03*
X1344664Y1362595D03*
Y1357603D03*
X1351948Y1374881D03*
Y1381801D03*
Y1369889D03*
X1339708Y1374881D03*
Y1381801D03*
Y1369889D03*
X1344664D03*
Y1374881D03*
Y1381801D03*
X1351948Y1386793D03*
Y1394087D03*
Y1399079D03*
X1339708D03*
Y1393993D03*
Y1386793D03*
X1344664Y1393993D03*
Y1399079D03*
Y1386793D03*
X1351948Y1410991D03*
Y1405999D03*
X1339708Y1410991D03*
Y1405999D03*
X1344664Y1410991D03*
Y1405999D03*
X1337512Y1461182D03*
X1346173Y1465513D03*
Y1460782D03*
X1337512Y1465913D03*
Y1456451D03*
X1346173Y1476136D03*
Y1470244D03*
X1337512Y1481267D03*
X1346173Y1480867D03*
X1337512Y1471805D03*
Y1476536D03*
X1346173Y1485598D03*
Y1491490D03*
X1337512Y1487159D03*
Y1491890D03*
Y1496621D03*
X1346173Y1496221D03*
X1337512Y1507245D03*
Y1502514D03*
X1346173Y1506845D03*
Y1500952D03*
Y1511576D03*
X1337512Y1511976D03*
X1346173Y1516307D03*
X1337512Y1558813D03*
Y1563544D03*
X1346173Y1563144D03*
X1337512Y1574167D03*
Y1578898D03*
X1346173Y1578498D03*
Y1572606D03*
X1337512Y1568275D03*
X1346173Y1567875D03*
X1337512Y1583629D03*
X1346173Y1583229D03*
X1337512Y1589522D03*
Y1594253D03*
X1346173Y1593853D03*
Y1587960D03*
X1337512Y1609607D03*
Y1604876D03*
Y1598984D03*
X1346173Y1609207D03*
Y1598584D03*
Y1603315D03*
X1337512Y1614338D03*
X1346173Y1613938D03*
Y1618669D03*
X1352000Y1644980D03*
X1355900Y146461D03*
X1354802Y152367D03*
X1355255Y561032D03*
Y607532D03*
Y652032D03*
X1364148Y836170D03*
X1354699Y855068D03*
X1357849Y861367D03*
X1354699D03*
X1357849Y858218D03*
X1357850Y855067D03*
X1360999Y851918D03*
Y877114D03*
X1357850Y873965D03*
X1354699Y873964D03*
X1357849Y870814D03*
Y867665D03*
X1354699D03*
X1363173Y994483D03*
X1363905Y1000855D03*
X1366493Y1000828D03*
X1367884Y1018825D03*
X1357265Y1022766D03*
X1364237Y1043140D03*
X1357265Y1030266D03*
X1363941Y1047047D03*
X1366289Y1098518D03*
X1361037Y1098428D03*
X1355533Y1123101D03*
X1363533D03*
X1366033D03*
X1366433Y1129301D03*
X1355533Y1125801D03*
X1363933D03*
X1366433D03*
X1353933Y1129301D03*
X1356433D03*
X1358933D03*
X1361433D03*
X1363933D03*
X1357397Y1155213D03*
Y1152713D03*
X1366797D03*
Y1155213D03*
X1361723Y1204617D03*
X1364038Y1198321D03*
Y1200821D03*
X1361723Y1212117D03*
Y1209617D03*
Y1207117D03*
X1357070Y1297498D03*
X1356904Y1345691D03*
Y1350683D03*
Y1357603D03*
Y1362595D03*
Y1381801D03*
Y1369889D03*
Y1374881D03*
Y1386793D03*
Y1394087D03*
Y1399079D03*
Y1410991D03*
Y1405999D03*
X1354834Y1465913D03*
Y1456451D03*
Y1461182D03*
X1363496Y1465513D03*
Y1460782D03*
X1354834Y1481267D03*
X1363496Y1476136D03*
Y1470244D03*
Y1480867D03*
X1354834Y1471805D03*
Y1476536D03*
Y1487159D03*
Y1496621D03*
X1363496Y1485598D03*
Y1491490D03*
Y1496221D03*
X1354834Y1491890D03*
Y1502514D03*
Y1511976D03*
X1363496Y1511576D03*
Y1506845D03*
Y1500952D03*
X1354834Y1507245D03*
X1363496Y1516307D03*
X1354834Y1558813D03*
Y1563544D03*
X1363496Y1563144D03*
Y1572606D03*
X1354834Y1568275D03*
Y1574167D03*
Y1578898D03*
X1363496Y1567875D03*
Y1578498D03*
X1354834Y1583629D03*
Y1589522D03*
Y1594253D03*
X1363496Y1583229D03*
Y1593853D03*
Y1587960D03*
X1354834Y1609607D03*
Y1604876D03*
Y1598984D03*
X1363496Y1609207D03*
Y1598584D03*
Y1603315D03*
X1354834Y1614338D03*
X1363496Y1613938D03*
Y1618669D03*
X1376262Y113394D03*
X1378911Y110784D03*
X1378505Y133298D03*
X1380652Y134579D03*
X1378227Y252371D03*
X1383556Y558338D03*
X1383184Y587653D03*
X1383425Y593575D03*
X1383556Y604838D03*
X1381118Y634033D03*
X1383425Y640075D03*
X1381244Y673623D03*
X1383425Y684140D03*
X1381932Y722547D03*
X1383425Y731575D03*
X1383046Y829871D03*
X1379896Y842470D03*
Y858218D03*
X1370447Y867665D03*
Y886562D03*
X1371379Y986717D03*
X1370384Y1004680D03*
X1376601Y1030218D03*
X1374451Y1090568D03*
Y1093068D03*
X1371477Y1098767D03*
X1375633Y1136935D03*
Y1134435D03*
Y1139435D03*
Y1131935D03*
X1383366D03*
Y1134435D03*
Y1136935D03*
Y1139435D03*
X1368933Y1125801D03*
X1371433D03*
X1368933Y1129301D03*
X1371433D03*
X1383024Y1152684D03*
X1376861D03*
X1375633Y1146935D03*
Y1144435D03*
Y1141935D03*
X1383366D03*
Y1146935D03*
Y1144435D03*
X1377390Y1244055D03*
Y1250760D03*
Y1254164D03*
X1372300Y1422900D03*
X1372157Y1461183D03*
Y1456452D03*
Y1465914D03*
Y1471806D03*
Y1476537D03*
Y1481268D03*
Y1487160D03*
Y1491891D03*
Y1496622D03*
Y1502515D03*
Y1507246D03*
Y1511977D03*
Y1558813D03*
Y1563544D03*
Y1568275D03*
Y1574167D03*
Y1578898D03*
Y1583629D03*
Y1589522D03*
Y1594253D03*
Y1604876D03*
Y1598984D03*
Y1609607D03*
Y1614338D03*
X1372000Y1644980D03*
X1391497Y109172D03*
X1394497D03*
X1393504Y106495D03*
X1397248Y116497D03*
X1386505Y133298D03*
X1397248Y130670D03*
Y123584D03*
X1393238Y146012D03*
X1395144Y141228D03*
X1397248Y137757D03*
X1398032Y150847D03*
X1400000Y247292D03*
X1392709Y253198D03*
X1391086Y577192D03*
X1400912Y581222D03*
Y591215D03*
X1391587Y627817D03*
X1388414Y675000D03*
X1388241Y722000D03*
X1396916Y862829D03*
X1395561Y876204D03*
X1396163Y868597D03*
X1398247Y926261D03*
X1390322Y1057998D03*
Y1055498D03*
X1392822D03*
Y1057998D03*
X1390322Y1060498D03*
Y1062998D03*
X1392822D03*
Y1060498D03*
X1399748Y1098518D03*
X1394496Y1098428D03*
X1388992Y1123101D03*
X1396992D03*
X1399492D03*
X1385866Y1131935D03*
Y1134435D03*
Y1136935D03*
Y1139435D03*
X1388992Y1125801D03*
X1397392D03*
X1399892D03*
X1387392Y1129301D03*
X1389892D03*
X1392392D03*
X1394892D03*
X1397392D03*
X1399892D03*
X1391856Y1155213D03*
Y1152713D03*
X1385866Y1141935D03*
Y1146935D03*
Y1144435D03*
X1393695Y1204405D03*
Y1206905D03*
Y1211905D03*
Y1209405D03*
X1385992Y1285466D03*
X1390492D03*
X1392000Y1644980D03*
X1409248Y109410D03*
Y102323D03*
X1404548Y116497D03*
X1402048D03*
X1404548Y109410D03*
X1409248Y116496D03*
X1402048Y130670D03*
Y123584D03*
X1404548Y123583D03*
X1409248Y130670D03*
Y123583D03*
X1404548Y130670D03*
X1409248Y137756D03*
X1402048Y137757D03*
X1408666Y324733D03*
X1411950Y448466D03*
X1408103Y555194D03*
X1410903D03*
X1408103Y563194D03*
X1410903D03*
X1408103Y571194D03*
X1410903D03*
X1406512Y581222D03*
X1403712D03*
Y591215D03*
X1406512D03*
X1405514Y611091D03*
X1405000Y656000D03*
Y699000D03*
X1404689Y910897D03*
X1413575Y915186D03*
X1413322Y958908D03*
X1404317Y989436D03*
X1411038Y985379D03*
X1404936Y1098767D03*
X1415494Y1139435D03*
Y1136935D03*
Y1134435D03*
Y1131935D03*
X1409092Y1136935D03*
Y1134435D03*
Y1139435D03*
Y1131935D03*
X1402392Y1125801D03*
X1404892D03*
X1402392Y1129301D03*
X1404892D03*
X1409092Y1141935D03*
X1416736Y1152713D03*
Y1155213D03*
X1402256D03*
Y1152713D03*
X1415494Y1144435D03*
Y1146935D03*
Y1141935D03*
X1409092Y1146935D03*
Y1144435D03*
X1407995Y1204617D03*
X1410310Y1200821D03*
Y1198321D03*
X1407995Y1207117D03*
Y1209617D03*
Y1212117D03*
X1415903Y1282590D03*
X1404019Y1285290D03*
X1414346Y1303020D03*
X1412000Y1644980D03*
X1417710Y82984D03*
Y75184D03*
Y77784D03*
Y80384D03*
X1420264Y92849D03*
X1417710Y85584D03*
X1427224Y103037D03*
X1427358Y116496D03*
Y109410D03*
Y130670D03*
Y123583D03*
X1423515Y137756D03*
X1429539Y293796D03*
X1432039D03*
X1431019Y434508D03*
X1427019D03*
X1424196Y446352D03*
X1428782Y445874D03*
X1417856Y455466D03*
X1433310Y504699D03*
X1430810D03*
X1433012Y516979D03*
X1430512D03*
X1427233Y628183D03*
X1424389Y627948D03*
X1426000Y709000D03*
Y713000D03*
Y757000D03*
Y753000D03*
X1422813Y910065D03*
X1424126Y900295D03*
X1427553Y939200D03*
X1427473Y965621D03*
X1420740Y1004766D03*
Y1000766D03*
Y1016266D03*
Y1030766D03*
X1420107Y1052514D03*
X1431876Y1098518D03*
X1426624Y1098428D03*
X1421120Y1123101D03*
X1429120D03*
X1431620D03*
X1422020Y1129301D03*
X1424520D03*
X1427020D03*
X1429520D03*
X1432020D03*
X1417994Y1139435D03*
Y1136935D03*
Y1134435D03*
Y1131935D03*
X1421120Y1125801D03*
X1429520D03*
X1432020D03*
X1419520Y1129301D03*
X1432384Y1155213D03*
Y1152713D03*
X1422984D03*
Y1155213D03*
X1417994Y1144435D03*
Y1146935D03*
Y1141935D03*
X1420625Y1204405D03*
Y1206905D03*
Y1209405D03*
X1425652Y1297411D03*
X1433386Y1343309D03*
X1428840Y1407740D03*
X1423065Y1508327D03*
X1432499Y1512175D03*
X1424245Y1543338D03*
X1425558Y1537432D03*
X1425260Y1558072D03*
X1433558Y1555366D03*
X1423701Y1563978D03*
X1432000Y1644980D03*
X1444641Y94017D03*
X1448641D03*
X1440641D03*
X1449761Y115401D03*
Y110445D03*
X1444769D03*
Y115401D03*
X1449761Y124618D03*
X1444769D03*
Y129574D03*
X1449761D03*
X1442682Y151540D03*
X1446332Y191941D03*
X1446199Y188727D03*
X1442956Y226141D03*
X1440156D03*
X1448026Y256535D03*
X1440053Y285690D03*
X1437553D03*
X1440053Y288190D03*
X1442853D03*
Y285690D03*
X1447079Y290755D03*
X1437553Y288190D03*
X1437758Y362584D03*
X1435019Y434508D03*
X1437757Y447201D03*
X1437879Y444269D03*
X1435810Y504699D03*
X1447036Y519518D03*
X1435512Y516979D03*
X1444536Y519518D03*
X1439536D03*
X1442036D03*
X1435241Y593796D03*
X1440930Y636005D03*
Y633205D03*
Y638805D03*
X1437784Y683532D03*
X1436567Y727532D03*
X1443000Y798500D03*
Y794500D03*
Y842500D03*
Y838500D03*
X1438188Y867633D03*
X1437703Y880067D03*
X1449072Y892581D03*
X1435288Y897500D03*
X1444453Y938806D03*
X1439449Y979009D03*
X1440610Y1021567D03*
X1435266Y1031522D03*
X1437064Y1098767D03*
X1441220Y1131935D03*
Y1139435D03*
Y1134435D03*
Y1136935D03*
X1434520Y1125801D03*
X1437020D03*
X1434520Y1129301D03*
X1437020D03*
X1441220Y1141935D03*
Y1144435D03*
Y1146935D03*
X1442448Y1152684D03*
X1434925Y1204617D03*
X1437240Y1200821D03*
Y1198321D03*
X1434925Y1207117D03*
Y1209617D03*
Y1212117D03*
X1436408Y1303462D03*
X1444438Y1308312D03*
X1439482D03*
X1441286Y1335776D03*
X1457718Y84140D03*
Y76140D03*
Y80140D03*
X1452650Y94017D03*
X1460163Y117557D03*
X1455171D03*
Y122513D03*
X1460163Y131731D03*
Y122513D03*
X1455171Y131731D03*
X1458262Y146461D03*
X1460163Y136687D03*
X1455171D03*
X1457164Y152367D03*
X1463547Y180527D03*
X1458864Y180572D03*
Y185165D03*
X1463502Y185121D03*
X1452832Y184619D03*
X1454812Y206760D03*
X1456026Y256535D03*
X1457056Y279208D03*
X1461160Y281307D03*
X1455079Y290755D03*
X1451079D03*
X1458982Y356861D03*
X1453000Y633450D03*
Y636250D03*
Y639050D03*
X1453032Y769032D03*
X1453775Y813032D03*
X1461241Y867475D03*
X1462694Y874859D03*
Y877859D03*
X1460472Y885985D03*
X1459420Y899226D03*
X1451005Y931848D03*
X1462819Y949996D03*
X1462000Y960378D03*
X1460655Y964253D03*
X1466076Y979746D03*
X1462388Y1006560D03*
X1455939Y1018368D03*
X1465503Y1030233D03*
X1460592Y1345691D03*
Y1350683D03*
X1465548Y1345691D03*
Y1350683D03*
X1460592Y1357603D03*
Y1362595D03*
X1465548Y1357603D03*
Y1362595D03*
X1460592Y1381801D03*
Y1374881D03*
Y1369889D03*
X1465548Y1381801D03*
Y1374881D03*
Y1369889D03*
X1460592Y1386793D03*
X1465548D03*
X1452000Y1644980D03*
X1480460Y60922D03*
X1475296Y55513D03*
X1471093Y117261D03*
X1478624Y113394D03*
X1481273Y110784D03*
X1481368Y130898D03*
X1478800Y180665D03*
Y172665D03*
X1467270Y192421D03*
X1478832Y200864D03*
Y212864D03*
Y216864D03*
Y221864D03*
X1480589Y252371D03*
X1473900Y433100D03*
X1478710Y685630D03*
X1473525Y710052D03*
X1474425Y716075D03*
X1479962Y727500D03*
X1471415Y748629D03*
X1474425Y760075D03*
X1473634Y864337D03*
X1481454Y911570D03*
X1474075Y920575D03*
X1474349Y949394D03*
X1468500Y974181D03*
X1479096Y997860D03*
X1471096D03*
X1475096D03*
X1467096D03*
X1471854Y1035088D03*
X1479624Y1035102D03*
X1468371Y1030701D03*
X1480193Y1102091D03*
X1474384D03*
X1480193Y1114691D03*
X1474384D03*
X1480193Y1127291D03*
X1474384D03*
X1480193Y1139891D03*
X1474384D03*
X1480193Y1152491D03*
X1474384D03*
X1480193Y1165091D03*
X1474384D03*
X1480193Y1177691D03*
X1474384D03*
X1480675Y1202103D03*
X1477788Y1350683D03*
Y1345691D03*
X1472832Y1350683D03*
Y1345691D03*
X1477788Y1357603D03*
Y1362595D03*
X1472832Y1357603D03*
Y1362595D03*
X1477788Y1381801D03*
Y1369795D03*
Y1374881D03*
X1472832Y1381801D03*
Y1369795D03*
Y1374881D03*
X1477788Y1386793D03*
Y1399079D03*
Y1393993D03*
X1472832Y1386793D03*
Y1393993D03*
Y1399079D03*
X1477788Y1405999D03*
Y1410991D03*
X1472832Y1405999D03*
Y1410991D03*
X1476094Y1465913D03*
Y1461182D03*
Y1456451D03*
Y1471805D03*
Y1481267D03*
Y1476536D03*
Y1491890D03*
Y1487159D03*
Y1496621D03*
Y1502514D03*
Y1511976D03*
Y1507245D03*
Y1563544D03*
Y1558813D03*
Y1568275D03*
Y1578898D03*
Y1574167D03*
Y1583629D03*
Y1594253D03*
Y1589522D03*
Y1609607D03*
Y1598984D03*
Y1604876D03*
Y1614338D03*
X1472000Y1644980D03*
X1493859Y109172D03*
X1496859D03*
X1495866Y106495D03*
X1488867Y133298D03*
X1495600Y146012D03*
X1497506Y141228D03*
X1483014Y134579D03*
X1495071Y253198D03*
X1486360Y358700D03*
Y354200D03*
X1496473Y769000D03*
X1491062Y793003D03*
X1491425Y801575D03*
X1496845Y813000D03*
X1491425Y845575D03*
X1489650Y836985D03*
X1489805Y866386D03*
X1497488Y873839D03*
X1491414Y875383D03*
X1494000Y884000D03*
X1498084Y894825D03*
X1492101Y894860D03*
X1496383Y898023D03*
X1496500Y919000D03*
X1496000Y922000D03*
X1487075Y920925D03*
X1485100Y943900D03*
X1496425Y943075D03*
X1496072Y950044D03*
X1482591Y961909D03*
X1486500Y947000D03*
X1485226Y973886D03*
X1492560Y974654D03*
X1495339Y1009354D03*
X1491839D03*
X1486030D03*
X1491096Y997860D03*
X1483096D03*
X1495096D03*
X1487096D03*
X1495339Y1021954D03*
X1491839D03*
X1486030D03*
X1483693Y1102091D03*
Y1114691D03*
Y1127291D03*
Y1139891D03*
Y1152491D03*
Y1165091D03*
Y1177691D03*
X1498197Y1209607D03*
X1492471Y1215195D03*
X1484055Y1223749D03*
X1497312Y1350683D03*
Y1345691D03*
X1485072D03*
Y1350683D03*
X1490028Y1345691D03*
Y1350683D03*
X1497312Y1357603D03*
Y1362595D03*
X1485072D03*
Y1357603D03*
X1490028D03*
Y1362595D03*
X1485072Y1369889D03*
Y1374881D03*
Y1381801D03*
X1490028Y1369889D03*
Y1374881D03*
Y1381801D03*
X1497312D03*
Y1374881D03*
Y1369889D03*
Y1386793D03*
Y1394087D03*
Y1399079D03*
X1485072Y1394087D03*
Y1399079D03*
Y1386793D03*
X1490028Y1399079D03*
Y1394087D03*
Y1386793D03*
X1497312Y1405999D03*
Y1410991D03*
X1485072Y1405999D03*
Y1410991D03*
X1490028Y1405999D03*
Y1410991D03*
X1484755Y1465513D03*
Y1460782D03*
X1493417Y1465913D03*
Y1456451D03*
Y1461182D03*
Y1471805D03*
Y1476536D03*
Y1481267D03*
X1484755Y1476136D03*
Y1470244D03*
Y1480867D03*
Y1496221D03*
X1493417Y1487159D03*
Y1491890D03*
Y1496621D03*
X1484755Y1491490D03*
Y1485598D03*
Y1506845D03*
Y1500952D03*
Y1511576D03*
X1493417Y1507245D03*
Y1502514D03*
Y1511976D03*
X1484755Y1516307D03*
Y1563144D03*
X1493417Y1558813D03*
Y1563544D03*
Y1578898D03*
X1484755Y1567875D03*
Y1578498D03*
Y1572606D03*
X1493417Y1568275D03*
Y1574167D03*
X1484755Y1583229D03*
Y1593853D03*
Y1587960D03*
X1493417Y1583629D03*
Y1589522D03*
Y1594253D03*
X1484755Y1609207D03*
Y1598584D03*
Y1603315D03*
X1493417Y1609607D03*
Y1604876D03*
Y1598984D03*
X1484755Y1613938D03*
Y1618669D03*
X1493417Y1614338D03*
X1492000Y1644980D03*
X1511610Y116496D03*
Y109410D03*
Y102323D03*
X1499610Y116497D03*
X1506910D03*
X1504410D03*
X1506910Y109410D03*
X1511610Y123583D03*
X1499610Y130670D03*
Y123584D03*
X1506910Y130670D03*
X1504410D03*
Y123584D03*
X1506910Y123583D03*
X1511610Y130670D03*
Y137756D03*
X1499610Y137757D03*
X1504410D03*
X1500394Y150847D03*
X1502362Y247292D03*
X1501807Y323766D03*
X1507864Y450750D03*
X1511963Y536382D03*
X1510280Y899732D03*
X1514354Y938811D03*
X1510500Y931500D03*
X1513955Y950396D03*
X1505888Y965964D03*
X1514000Y968739D03*
X1510740Y973740D03*
X1507096Y997860D03*
X1503096D03*
X1511096D03*
X1499096D03*
X1505130Y1105091D03*
Y1117691D03*
Y1130291D03*
Y1142891D03*
Y1155491D03*
Y1168091D03*
Y1180691D03*
X1509552Y1350683D03*
Y1345691D03*
X1514508Y1350683D03*
Y1345691D03*
X1502268Y1350683D03*
Y1345691D03*
X1509552Y1362595D03*
Y1357603D03*
X1514508D03*
Y1362595D03*
X1502268Y1357603D03*
Y1362595D03*
X1509552Y1374881D03*
Y1369889D03*
Y1381801D03*
X1514508Y1374881D03*
Y1369889D03*
Y1381801D03*
X1502268D03*
Y1374881D03*
Y1369889D03*
X1509552Y1394087D03*
Y1399079D03*
Y1386793D03*
X1514508Y1394087D03*
Y1399079D03*
Y1386793D03*
X1502268D03*
Y1399079D03*
Y1394087D03*
X1509552Y1405999D03*
Y1410991D03*
X1514508Y1405999D03*
Y1410991D03*
X1502268Y1405999D03*
Y1410991D03*
X1502078Y1465513D03*
Y1460782D03*
X1510740Y1465913D03*
Y1456451D03*
Y1461182D03*
X1502078Y1470244D03*
Y1480867D03*
X1510740Y1471805D03*
Y1476536D03*
Y1481267D03*
X1502078Y1476136D03*
Y1491490D03*
Y1485598D03*
Y1496221D03*
X1510740Y1487159D03*
Y1491890D03*
Y1496621D03*
Y1507245D03*
Y1502514D03*
Y1511976D03*
X1502078Y1506845D03*
Y1500952D03*
Y1511576D03*
Y1516307D03*
X1510740Y1563544D03*
X1502078Y1563144D03*
X1510740Y1558813D03*
Y1578898D03*
X1502078Y1567875D03*
Y1578498D03*
Y1572606D03*
X1510740Y1568275D03*
Y1574167D03*
X1502078Y1583229D03*
Y1593853D03*
Y1587960D03*
X1510740Y1583629D03*
Y1589522D03*
Y1594253D03*
X1502078Y1609207D03*
Y1598584D03*
Y1603315D03*
X1510740Y1609607D03*
Y1604876D03*
Y1598984D03*
X1502078Y1613938D03*
Y1618669D03*
X1510740Y1614338D03*
X1512000Y1644980D03*
X1520072Y82984D03*
Y75184D03*
Y77784D03*
Y80384D03*
X1522626Y92849D03*
X1520072Y85584D03*
X1529586Y103037D03*
X1529720Y116496D03*
Y109410D03*
Y130670D03*
Y123583D03*
X1526311Y137756D03*
X1528635Y555234D03*
X1528350Y562003D03*
X1519156Y596095D03*
X1516869Y594668D03*
X1518354Y592354D03*
X1518415Y589556D03*
X1519153Y599588D03*
X1516930Y597580D03*
X1519185Y615600D03*
X1519153Y607588D03*
X1523646Y634946D03*
X1519063Y876339D03*
X1517344Y896999D03*
X1515743Y888133D03*
X1517344Y903179D03*
X1517153Y908367D03*
X1523000Y923740D03*
X1526611Y921442D03*
X1525740Y928740D03*
X1528087Y936394D03*
X1524500Y949500D03*
X1530174Y956986D03*
X1525522Y971075D03*
X1523966Y980281D03*
X1515096Y997860D03*
X1531096D03*
X1519096D03*
X1523096D03*
X1516776Y1024954D03*
Y1012354D03*
X1526748Y1345691D03*
Y1350683D03*
X1521792Y1345691D03*
Y1350683D03*
X1526748Y1357603D03*
Y1362595D03*
X1521792Y1357603D03*
Y1362595D03*
X1526748Y1369889D03*
Y1374881D03*
Y1381801D03*
X1521792Y1374881D03*
Y1381801D03*
Y1369889D03*
X1526748Y1386793D03*
Y1399079D03*
Y1394087D03*
X1521792Y1386793D03*
Y1394087D03*
Y1399079D03*
X1526748Y1405999D03*
Y1410991D03*
X1521792Y1405999D03*
Y1410991D03*
X1519401Y1465513D03*
Y1460782D03*
X1528062Y1465913D03*
Y1456451D03*
Y1461182D03*
Y1481267D03*
X1519401Y1476136D03*
Y1470244D03*
Y1480867D03*
X1528062Y1471805D03*
Y1476536D03*
X1519401Y1491490D03*
Y1485598D03*
Y1496221D03*
X1528062Y1487159D03*
Y1491890D03*
Y1496621D03*
X1519401Y1506845D03*
Y1500952D03*
Y1511576D03*
X1528062Y1507245D03*
Y1502514D03*
Y1511976D03*
X1519401Y1516307D03*
Y1563144D03*
X1528062Y1558813D03*
Y1563544D03*
Y1578898D03*
X1519401Y1567875D03*
Y1578498D03*
Y1572606D03*
X1528062Y1568275D03*
Y1574167D03*
X1519401Y1587960D03*
X1528062Y1583629D03*
Y1589522D03*
Y1594253D03*
X1519401Y1583229D03*
Y1593853D03*
Y1609207D03*
Y1598584D03*
Y1603315D03*
X1528062Y1609607D03*
Y1604876D03*
Y1598984D03*
X1519401Y1613938D03*
Y1618669D03*
X1528062Y1614338D03*
X1547003Y94017D03*
X1543003D03*
X1547131Y110445D03*
Y115401D03*
Y129574D03*
Y124618D03*
X1545044Y151540D03*
X1548561Y188727D03*
X1542518Y226141D03*
X1545318D03*
X1531901Y293796D03*
X1539915Y288190D03*
X1542415Y285690D03*
X1539915D03*
X1542415Y288190D03*
X1545215D03*
Y285690D03*
X1534401Y293796D03*
X1541283Y354553D03*
X1546272Y1350683D03*
Y1345691D03*
X1534032Y1350683D03*
Y1345691D03*
X1538988D03*
Y1350683D03*
X1546272Y1357603D03*
Y1362595D03*
X1534032Y1357603D03*
Y1362595D03*
X1538988D03*
Y1357603D03*
X1546272Y1374881D03*
Y1369889D03*
Y1381801D03*
X1534032Y1369889D03*
Y1381801D03*
Y1374881D03*
X1538988Y1369889D03*
Y1381801D03*
Y1374881D03*
X1546272Y1386793D03*
Y1394087D03*
Y1399079D03*
X1534032Y1394087D03*
Y1399079D03*
Y1386793D03*
X1538988Y1394087D03*
Y1399079D03*
Y1386793D03*
X1546272Y1405999D03*
Y1410991D03*
X1534032Y1405999D03*
Y1410991D03*
X1538988Y1405999D03*
Y1410991D03*
X1545385Y1461183D03*
X1536724Y1465513D03*
Y1460782D03*
X1545385Y1465914D03*
Y1456452D03*
X1536724Y1476136D03*
Y1470244D03*
Y1480867D03*
X1545385Y1476537D03*
Y1471806D03*
Y1481268D03*
X1536724Y1491490D03*
Y1485598D03*
Y1496221D03*
X1545385Y1491891D03*
Y1487160D03*
Y1496622D03*
X1536724Y1506845D03*
Y1500952D03*
Y1511576D03*
X1545385Y1507246D03*
Y1502515D03*
Y1511977D03*
X1536724Y1516307D03*
X1545385Y1563544D03*
Y1558813D03*
X1536724Y1563144D03*
Y1567875D03*
X1545385Y1568275D03*
X1536724Y1578498D03*
Y1572606D03*
X1545385Y1578898D03*
Y1574167D03*
Y1594253D03*
Y1589522D03*
X1536724Y1583229D03*
X1545385Y1583629D03*
X1536724Y1593853D03*
Y1587960D03*
Y1609207D03*
Y1598584D03*
Y1603315D03*
X1545385Y1609607D03*
Y1598984D03*
Y1604876D03*
Y1614338D03*
X1536724Y1613938D03*
Y1618669D03*
X1532000Y1644980D03*
X1560080Y84140D03*
Y76140D03*
Y80140D03*
X1555012Y94017D03*
X1551003D03*
X1562525Y117557D03*
X1557533D03*
X1552123Y115401D03*
Y110445D03*
X1562525Y122513D03*
X1552123Y129574D03*
Y124618D03*
X1557533Y131731D03*
Y122513D03*
X1562525Y131731D03*
X1560624Y146461D03*
X1557533Y136687D03*
X1562525D03*
X1559526Y152367D03*
X1561226Y180572D03*
X1548694Y191941D03*
X1555194Y184619D03*
X1561226Y185165D03*
X1557174Y206760D03*
X1550388Y256535D03*
X1558388D03*
X1559418Y279208D03*
X1563522Y281307D03*
X1549441Y290755D03*
X1553441D03*
X1557441D03*
X1554403Y352363D03*
X1563248Y389154D03*
X1548629D03*
Y403327D03*
Y410413D03*
X1561778Y396240D03*
X1548629D03*
Y417500D03*
Y424587D03*
Y438760D03*
Y431673D03*
Y445847D03*
Y467539D03*
Y474626D03*
Y488799D03*
Y481713D03*
Y495886D03*
Y511673D03*
Y518760D03*
X1562089Y516841D03*
X1548629Y540020D03*
Y525847D03*
Y532933D03*
Y547106D03*
X1556914Y552872D03*
X1557036Y550123D03*
X1556359Y562443D03*
X1558668Y572334D03*
X1558127Y560675D03*
X1556900Y574102D03*
X1547910Y602197D03*
X1548374Y595108D03*
X1561535Y653161D03*
X1565132Y677843D03*
X1547813Y906581D03*
X1551099Y959096D03*
X1558512Y1345691D03*
Y1350683D03*
X1563468D03*
Y1345691D03*
X1551228Y1350683D03*
Y1345691D03*
X1563468Y1362595D03*
X1551228Y1357603D03*
Y1362595D03*
X1558512D03*
Y1357603D03*
X1563468D03*
X1558512Y1374881D03*
Y1369889D03*
Y1381801D03*
X1563468Y1374881D03*
Y1369889D03*
Y1381801D03*
X1551228Y1369889D03*
Y1381801D03*
Y1374881D03*
X1558512Y1399079D03*
Y1394087D03*
Y1386793D03*
X1563468Y1399079D03*
Y1394087D03*
Y1386793D03*
X1551228D03*
Y1394087D03*
Y1399079D03*
X1558512Y1405999D03*
Y1410991D03*
X1563468Y1405999D03*
Y1410991D03*
X1551228Y1405999D03*
Y1410991D03*
X1552000Y1644980D03*
X1576256Y-25273D03*
X1573003Y-25287D03*
X1576241Y-27788D03*
X1572988Y-27802D03*
X1579281Y-26693D03*
X1573455Y117261D03*
X1565909Y180527D03*
X1569632Y192421D03*
X1565864Y185121D03*
X1571625Y333549D03*
X1579340Y396240D03*
Y403327D03*
Y410413D03*
X1566555Y414823D03*
X1565863Y422864D03*
X1579340Y417500D03*
Y424586D03*
X1565933Y429832D03*
X1565538Y436447D03*
X1579340Y431673D03*
Y438760D03*
X1567573Y447953D03*
X1579340Y445847D03*
X1566740Y467539D03*
X1565482Y472772D03*
X1579340Y474626D03*
Y488799D03*
X1566216Y487711D03*
X1566329Y479104D03*
X1579340Y481712D03*
Y495886D03*
X1566740D03*
X1579340Y518760D03*
X1565050Y511673D03*
X1579340Y540020D03*
Y532933D03*
Y525846D03*
X1574222Y629872D03*
X1569926Y668885D03*
X1575950Y662981D03*
X1570331Y691851D03*
X1575942Y705043D03*
X1575708Y1345597D03*
X1570752Y1350683D03*
Y1345597D03*
X1575708Y1350683D03*
X1570752Y1357603D03*
Y1362595D03*
X1575708D03*
Y1357603D03*
Y1381801D03*
Y1374881D03*
Y1369889D03*
X1570752D03*
Y1381801D03*
Y1374881D03*
X1575708Y1386793D03*
Y1399079D03*
Y1393993D03*
X1570752Y1386793D03*
Y1393993D03*
Y1399079D03*
X1575708Y1405999D03*
Y1410991D03*
X1570752Y1405999D03*
Y1410991D03*
X1572000Y1644980D03*
X1586256Y-64207D03*
X1583003D03*
X1586241Y-66722D03*
X1582988D03*
X1589281Y-65613D03*
X1582822Y60922D03*
X1580327Y57448D03*
X1580986Y113394D03*
X1583635Y110784D03*
X1591229Y133298D03*
X1583229D03*
X1585376Y134579D03*
X1581162Y180665D03*
Y172665D03*
X1581194Y212864D03*
Y200864D03*
Y221864D03*
Y216864D03*
X1582951Y252371D03*
X1586640Y389153D03*
X1581840D03*
Y403326D03*
Y410413D03*
X1586640D03*
X1581840Y396240D03*
X1586640D03*
Y403326D03*
Y417499D03*
X1581840D03*
Y424586D03*
X1586640D03*
X1581840Y438760D03*
X1586640D03*
Y431673D03*
X1581840D03*
X1586640Y467539D03*
X1581840D03*
Y474626D03*
X1586640D03*
X1581840Y488799D03*
X1586640D03*
X1581840Y481712D03*
X1586640D03*
X1581840Y518760D03*
Y511673D03*
X1586640D03*
Y518760D03*
Y525846D03*
Y532933D03*
X1581840D03*
Y525846D03*
X1595185Y543925D03*
X1595760Y555000D03*
X1583720Y560500D03*
X1587948Y1350683D03*
Y1345691D03*
X1582992D03*
Y1350683D03*
X1587948Y1362595D03*
Y1357603D03*
X1582992Y1362595D03*
Y1357603D03*
Y1369889D03*
Y1381801D03*
Y1374881D03*
X1587948Y1369889D03*
Y1381801D03*
Y1374881D03*
X1582992Y1399079D03*
Y1394087D03*
Y1386793D03*
X1587948Y1399079D03*
Y1394087D03*
Y1386793D03*
X1582992Y1405999D03*
Y1410991D03*
X1587948Y1405999D03*
Y1410991D03*
X1592020Y1433061D03*
X1591610Y1469940D03*
X1591586Y1505130D03*
X1609272Y109410D03*
X1601972Y116497D03*
X1609272D03*
X1606772D03*
X1596221Y109172D03*
X1599221D03*
X1598228Y106495D03*
X1601972Y123584D03*
Y130670D03*
X1606772Y123584D03*
X1609272Y123583D03*
Y130670D03*
X1606772D03*
Y137757D03*
X1597962Y146012D03*
X1599868Y141228D03*
X1601972Y137757D03*
X1602756Y150847D03*
X1604724Y247292D03*
X1597433Y253198D03*
X1608240Y329000D03*
X1603664Y342596D03*
X1598223Y351003D03*
X1599127Y375587D03*
X1596714Y383003D03*
X1614338Y636842D03*
X1610620Y1345691D03*
Y1350683D03*
Y1357603D03*
Y1362595D03*
Y1381801D03*
Y1374881D03*
Y1369889D03*
Y1386793D03*
X1597225Y1437014D03*
X1603363Y1460570D03*
X1597457Y1452556D03*
X1598500Y1472500D03*
X1606745Y1474242D03*
X1602580Y1483108D03*
X1598000Y1486000D03*
X1604000Y1516000D03*
X1600700Y1534300D03*
X1622434Y82984D03*
Y80384D03*
Y75184D03*
Y77784D03*
X1624988Y92849D03*
X1622434Y85584D03*
X1613972Y116496D03*
Y102323D03*
Y109410D03*
Y130670D03*
Y123583D03*
Y137756D03*
X1625952Y431029D03*
X1626260Y427017D03*
X1625018Y435029D03*
X1625938Y449873D03*
X1625565Y472579D03*
Y479666D03*
Y486752D03*
Y493839D03*
Y523800D03*
Y516713D03*
Y537973D03*
Y530886D03*
Y566752D03*
Y588013D03*
Y573839D03*
Y580926D03*
Y602186D03*
Y595099D03*
Y609272D03*
Y616359D03*
X1620244Y638125D03*
X1617843Y665140D03*
X1613110Y678462D03*
X1624148Y708258D03*
X1627455Y759489D03*
X1619612Y783152D03*
X1620359Y774830D03*
X1619569Y796035D03*
X1620755Y787530D03*
X1613235Y808466D03*
X1620479Y815730D03*
X1620072Y801630D03*
X1616255Y824405D03*
X1619859Y839519D03*
X1615576Y1345691D03*
Y1350683D03*
X1622860D03*
Y1345691D03*
X1627816Y1350683D03*
Y1345691D03*
X1615576Y1357603D03*
Y1362595D03*
X1622860Y1357603D03*
Y1362595D03*
X1627816Y1357603D03*
Y1362595D03*
X1622860Y1381801D03*
Y1369795D03*
Y1374881D03*
X1627816Y1381801D03*
Y1369795D03*
Y1374881D03*
X1615576Y1381801D03*
Y1374881D03*
Y1369889D03*
Y1386793D03*
X1622860D03*
Y1393993D03*
Y1399079D03*
X1627816Y1386793D03*
Y1399079D03*
Y1393993D03*
X1622860Y1405999D03*
Y1410991D03*
X1627816Y1405999D03*
Y1410991D03*
X1618800Y1528558D03*
X1614200Y1519500D03*
X1614360Y1542860D03*
X1618600Y1532000D03*
X1631948Y103037D03*
X1632082Y116496D03*
Y109410D03*
Y130670D03*
Y123583D03*
X1628673Y137756D03*
X1644880Y226141D03*
X1644777Y288190D03*
X1642277Y285690D03*
X1644777D03*
X1642277Y288190D03*
X1636763Y293796D03*
X1634263D03*
X1635987Y335616D03*
X1630703Y350655D03*
X1636468Y345595D03*
X1636271Y410394D03*
Y403307D03*
X1637665Y458406D03*
Y451319D03*
X1637489Y462264D03*
X1632865Y465492D03*
X1637665D03*
Y472579D03*
X1632865D03*
X1630365D03*
Y479666D03*
X1632865D03*
X1637665Y479665D03*
Y486752D03*
X1630365D03*
X1632865D03*
X1630365Y493839D03*
X1637665D03*
X1632865Y509626D03*
Y516713D03*
X1630365D03*
Y523800D03*
X1632865D03*
X1637665Y523799D03*
Y516713D03*
Y509626D03*
X1630365Y530886D03*
X1637665D03*
X1632865D03*
X1637665Y537973D03*
X1630365D03*
X1637665Y559665D03*
Y566752D03*
X1630365D03*
X1632865D03*
Y559665D03*
Y573839D03*
X1630365Y580926D03*
X1632865D03*
X1637665D03*
Y588012D03*
X1630365Y588013D03*
X1632865Y588012D03*
X1637665Y573839D03*
X1630365D03*
X1632865Y602185D03*
X1630365Y602186D03*
X1637665Y602185D03*
Y595099D03*
X1632865D03*
X1630365D03*
Y616359D03*
X1632865Y609272D03*
X1630365D03*
X1637665Y616358D03*
Y609272D03*
X1637526Y699930D03*
X1637472Y717830D03*
X1631031Y732430D03*
X1628813Y727045D03*
X1631187Y750630D03*
X1629969Y740826D03*
X1644304Y891353D03*
X1640056Y1345691D03*
Y1350683D03*
X1635100Y1345691D03*
Y1350683D03*
X1640056Y1357603D03*
Y1362595D03*
X1635100D03*
Y1357603D03*
X1640056Y1369889D03*
Y1374881D03*
Y1381801D03*
X1635100Y1369889D03*
Y1374881D03*
Y1381801D03*
X1640056Y1399079D03*
Y1394087D03*
Y1386793D03*
X1635100Y1394087D03*
Y1399079D03*
Y1386793D03*
Y1405999D03*
Y1410991D03*
X1640056Y1405999D03*
Y1410991D03*
X1649365Y94017D03*
X1657374D03*
X1653365D03*
X1645365D03*
X1659895Y117557D03*
X1654485Y110445D03*
Y115401D03*
X1649493Y110445D03*
Y115401D03*
X1659895Y122513D03*
Y131731D03*
X1654485Y124618D03*
Y129574D03*
X1649493Y124618D03*
Y129574D03*
X1659895Y136687D03*
X1647406Y151540D03*
X1651056Y191941D03*
X1657556Y184619D03*
X1650923Y188727D03*
X1659536Y206760D03*
X1647680Y226141D03*
X1660750Y256535D03*
X1652750D03*
X1647577Y285690D03*
Y288190D03*
X1655803Y290755D03*
X1651803D03*
X1659803D03*
X1645685Y390500D03*
X1655335Y381500D03*
X1653507Y470136D03*
X1655776Y465492D03*
X1655742Y460250D03*
X1655776Y472579D03*
Y486752D03*
Y479665D03*
Y493839D03*
Y509626D03*
Y516713D03*
X1652236Y537973D03*
X1654716Y525483D03*
X1654637Y532756D03*
X1655776Y559665D03*
Y566752D03*
X1655626Y579978D03*
X1655776Y573839D03*
X1655840Y608117D03*
X1654572Y771702D03*
X1645128Y929263D03*
X1645342Y962120D03*
X1657091Y990823D03*
X1649571Y983857D03*
X1647340Y1350683D03*
Y1345691D03*
X1652296Y1350683D03*
Y1345691D03*
X1659580Y1350683D03*
Y1345691D03*
X1647340Y1357603D03*
Y1362595D03*
X1652296Y1357603D03*
Y1362595D03*
X1659580D03*
Y1357603D03*
X1647340Y1381801D03*
Y1374881D03*
Y1369889D03*
X1652296Y1381801D03*
Y1374881D03*
Y1369889D03*
X1659580Y1374881D03*
Y1369889D03*
Y1381801D03*
X1647340Y1386793D03*
Y1394087D03*
Y1399079D03*
X1652296Y1386793D03*
Y1399079D03*
Y1394087D03*
X1659580D03*
Y1399079D03*
Y1386793D03*
X1647340Y1405999D03*
Y1410991D03*
X1652296Y1405999D03*
Y1410991D03*
X1659580Y1405999D03*
Y1410991D03*
X1657983Y1460782D03*
X1649322Y1456451D03*
Y1465913D03*
X1657983Y1465513D03*
X1649322Y1461182D03*
Y1476536D03*
X1657983Y1476136D03*
Y1470244D03*
X1649322Y1471805D03*
Y1481267D03*
X1657983Y1480867D03*
X1649322Y1487159D03*
Y1496621D03*
X1657983Y1496221D03*
X1649322Y1491890D03*
X1657983Y1491490D03*
Y1485598D03*
Y1500952D03*
X1649322Y1502514D03*
X1657983Y1511576D03*
X1649322Y1511976D03*
Y1507245D03*
X1657983Y1506845D03*
Y1516307D03*
X1649322Y1558813D03*
Y1563544D03*
X1657983Y1563144D03*
Y1572606D03*
X1649322Y1574167D03*
Y1568275D03*
X1657983Y1567875D03*
X1649322Y1578898D03*
X1657983Y1578498D03*
X1649322Y1583629D03*
X1657983Y1583229D03*
X1649322Y1594253D03*
X1657983Y1593853D03*
Y1587960D03*
X1649322Y1589522D03*
Y1609607D03*
X1657983Y1609207D03*
X1649322Y1598984D03*
X1657983Y1598584D03*
Y1603315D03*
X1649322Y1604876D03*
Y1614338D03*
X1657983Y1613938D03*
Y1618669D03*
X1652000Y1644980D03*
X1662442Y84140D03*
Y76140D03*
Y80140D03*
X1675817Y117261D03*
X1664887Y117557D03*
Y122513D03*
Y131731D03*
X1662986Y146461D03*
X1664887Y136687D03*
X1661888Y152367D03*
X1663588Y180572D03*
X1668271Y180527D03*
X1671994Y192421D03*
X1663588Y185165D03*
X1668226Y185121D03*
X1661780Y279208D03*
X1665884Y281307D03*
X1669767Y445908D03*
X1673717Y445787D03*
X1664536Y1350683D03*
Y1345691D03*
X1671820D03*
Y1350683D03*
X1676776Y1345691D03*
Y1350683D03*
X1664536Y1357603D03*
Y1362595D03*
X1671820Y1357603D03*
Y1362595D03*
X1676776Y1357603D03*
Y1362595D03*
X1664536Y1374881D03*
Y1369889D03*
Y1381801D03*
X1671820Y1374881D03*
Y1381801D03*
Y1369889D03*
X1676776D03*
Y1374881D03*
Y1381801D03*
X1664536Y1394087D03*
Y1399079D03*
Y1386793D03*
X1671820D03*
Y1394087D03*
Y1399079D03*
X1676776Y1386793D03*
Y1399079D03*
Y1394087D03*
X1664536Y1405999D03*
Y1410991D03*
X1671820Y1405999D03*
Y1410991D03*
X1676776Y1405999D03*
Y1410991D03*
X1666645Y1465913D03*
Y1456451D03*
Y1461182D03*
X1675306Y1465513D03*
Y1460782D03*
X1666645Y1471805D03*
Y1476536D03*
Y1481267D03*
X1675306Y1476136D03*
Y1470244D03*
Y1480867D03*
X1666645Y1487159D03*
Y1491890D03*
Y1496621D03*
X1675306Y1491490D03*
Y1485598D03*
Y1496221D03*
Y1511576D03*
X1666645Y1511976D03*
Y1507245D03*
Y1502514D03*
X1675306Y1506845D03*
Y1500952D03*
Y1516307D03*
X1666645Y1558813D03*
Y1563544D03*
X1675306Y1563144D03*
Y1578498D03*
Y1572606D03*
X1666645Y1568275D03*
X1675306Y1567875D03*
X1666645Y1574167D03*
Y1578898D03*
Y1583629D03*
X1675306Y1583229D03*
X1666645Y1589522D03*
Y1594253D03*
X1675306Y1593853D03*
Y1587960D03*
X1666645Y1604876D03*
Y1598984D03*
X1675306Y1609207D03*
Y1598584D03*
Y1603315D03*
X1666645Y1609607D03*
Y1614338D03*
X1675306Y1613938D03*
Y1618669D03*
X1672000Y1644980D03*
X1685184Y60922D03*
X1680020Y55513D03*
X1683348Y113394D03*
X1685997Y110784D03*
X1686171Y130898D03*
X1693591Y133298D03*
X1687738Y134579D03*
X1683524Y172665D03*
Y180665D03*
X1683556Y200864D03*
Y212864D03*
Y221864D03*
Y216864D03*
X1685313Y252371D03*
X1687164Y336324D03*
X1678072Y342319D03*
X1691743Y353506D03*
X1680518Y385912D03*
Y393924D03*
Y389912D03*
Y409924D03*
Y405924D03*
Y401924D03*
X1677933Y418838D03*
X1689016Y1345691D03*
Y1350683D03*
X1684060D03*
Y1345691D03*
X1689016Y1362595D03*
Y1357603D03*
X1684060D03*
Y1362595D03*
X1689016Y1369889D03*
Y1381801D03*
Y1374881D03*
X1684060Y1369889D03*
Y1381801D03*
Y1374881D03*
X1689016Y1394087D03*
Y1399079D03*
Y1386793D03*
X1684060Y1394087D03*
Y1399079D03*
Y1386793D03*
X1689016Y1405999D03*
Y1410991D03*
X1684060Y1405999D03*
Y1410991D03*
X1683968Y1465913D03*
Y1456451D03*
Y1461182D03*
X1692629Y1465513D03*
Y1460782D03*
X1683968Y1471805D03*
Y1476536D03*
Y1481267D03*
X1692629Y1476136D03*
Y1470244D03*
Y1480867D03*
X1683968Y1487159D03*
Y1491890D03*
Y1496621D03*
X1692629Y1491490D03*
Y1485598D03*
Y1496221D03*
X1683968Y1502514D03*
Y1511976D03*
X1692629Y1506845D03*
Y1500952D03*
Y1511576D03*
X1683968Y1507245D03*
X1692629Y1516307D03*
X1683968Y1558813D03*
Y1563544D03*
X1692629Y1563144D03*
Y1572606D03*
X1683968Y1568275D03*
Y1574167D03*
Y1578898D03*
X1692629Y1567875D03*
Y1578498D03*
X1683968Y1583629D03*
Y1589522D03*
Y1594253D03*
X1692629Y1583229D03*
Y1593853D03*
Y1587960D03*
X1683968Y1598984D03*
X1692629Y1609207D03*
Y1598584D03*
Y1603315D03*
X1683968Y1609607D03*
Y1604876D03*
Y1614338D03*
X1692629Y1613938D03*
Y1618669D03*
X1692000Y1644980D03*
X1698583Y109172D03*
X1701583D03*
X1700590Y106495D03*
X1709134Y116497D03*
X1704334D03*
X1709134Y123584D03*
Y130670D03*
X1704334Y123584D03*
Y130670D03*
X1700324Y146012D03*
X1702230Y141228D03*
X1709134Y137757D03*
X1704334D03*
X1705118Y150847D03*
X1707086Y247292D03*
X1699795Y253198D03*
X1701495Y289735D03*
X1695142Y303839D03*
X1708889Y1189221D03*
X1696300Y1350683D03*
Y1345691D03*
X1701256Y1350683D03*
Y1345691D03*
X1708540D03*
Y1350683D03*
X1696300Y1357603D03*
Y1362595D03*
X1701256Y1357603D03*
Y1362595D03*
X1708540D03*
Y1357603D03*
X1696300Y1374881D03*
Y1369889D03*
Y1381801D03*
X1701256Y1369889D03*
Y1381801D03*
Y1374881D03*
X1708540D03*
Y1369889D03*
Y1381801D03*
X1696300Y1386793D03*
Y1394087D03*
Y1399079D03*
X1701256Y1386793D03*
Y1394087D03*
Y1399079D03*
X1708540D03*
Y1394087D03*
Y1386793D03*
X1696300Y1405999D03*
Y1410991D03*
X1701256Y1405999D03*
Y1410991D03*
X1708540Y1405999D03*
Y1410991D03*
X1701290Y1465913D03*
Y1456451D03*
Y1461182D03*
Y1471805D03*
Y1476536D03*
Y1481267D03*
Y1487159D03*
Y1491890D03*
Y1496621D03*
Y1507245D03*
Y1502514D03*
Y1511976D03*
Y1558813D03*
Y1563544D03*
Y1568275D03*
Y1574167D03*
Y1578898D03*
Y1583629D03*
Y1589522D03*
Y1594253D03*
Y1609607D03*
Y1604876D03*
Y1598984D03*
Y1614338D03*
X1724796Y82984D03*
Y77784D03*
Y80384D03*
Y75184D03*
Y85584D03*
X1716334Y116496D03*
Y109410D03*
Y102323D03*
X1711634Y116497D03*
Y109410D03*
X1716334Y130670D03*
Y123583D03*
X1711634D03*
Y130670D03*
X1716334Y137756D03*
X1720960Y1148000D03*
X1723796Y1160168D03*
X1725660Y1193019D03*
X1721660D03*
X1711783Y1193848D03*
X1713496Y1350683D03*
Y1345691D03*
X1720780Y1350683D03*
Y1345597D03*
X1725736Y1350683D03*
Y1345597D03*
X1713496Y1357603D03*
Y1362595D03*
X1720780Y1357603D03*
Y1362595D03*
X1725736Y1357603D03*
Y1362595D03*
X1713496Y1374881D03*
Y1369889D03*
Y1381801D03*
X1720780Y1369889D03*
Y1381801D03*
Y1374881D03*
X1725736Y1381801D03*
Y1374881D03*
Y1369889D03*
X1713496Y1399079D03*
Y1394087D03*
Y1386793D03*
X1720780D03*
Y1393993D03*
Y1399079D03*
X1725736Y1386793D03*
Y1399079D03*
Y1393993D03*
X1713496Y1405999D03*
Y1410991D03*
X1720780Y1405999D03*
Y1410991D03*
X1725736Y1405999D03*
Y1410991D03*
X1709952Y1465513D03*
Y1460782D03*
X1718613Y1465914D03*
Y1456452D03*
Y1461183D03*
Y1476537D03*
Y1471806D03*
Y1481268D03*
X1709952Y1476136D03*
Y1470244D03*
Y1480867D03*
Y1491490D03*
Y1485598D03*
Y1496221D03*
X1718613Y1491891D03*
Y1487160D03*
Y1496622D03*
Y1502515D03*
Y1511977D03*
X1709952Y1506845D03*
Y1500952D03*
Y1511576D03*
X1718613Y1507246D03*
X1709952Y1516307D03*
Y1563144D03*
X1718613Y1563544D03*
Y1558813D03*
X1709952Y1567875D03*
X1718613Y1568275D03*
X1709952Y1578498D03*
Y1572606D03*
X1718613Y1578898D03*
Y1574167D03*
Y1589522D03*
X1709952Y1583229D03*
X1718613Y1583629D03*
X1709952Y1593853D03*
Y1587960D03*
X1718613Y1594253D03*
Y1609607D03*
Y1598984D03*
Y1604876D03*
X1709952Y1609207D03*
Y1598584D03*
Y1603315D03*
Y1618669D03*
X1718613Y1614338D03*
X1709952Y1613938D03*
X1712000Y1644980D03*
X1727350Y92849D03*
X1734310Y103037D03*
X1734444Y116496D03*
Y109410D03*
Y130670D03*
Y123583D03*
X1730647Y137756D03*
X1739125Y293796D03*
X1736625D03*
X1737703Y472189D03*
X1728038Y491870D03*
X1730538D03*
X1730675Y1132361D03*
X1726963Y1132319D03*
X1739917Y1146937D03*
X1729207Y1159455D03*
X1737393Y1162817D03*
X1733660Y1193019D03*
X1729660D03*
X1737660D03*
X1733695Y1212164D03*
X1735989Y1214458D03*
X1731619Y1210089D03*
X1740785Y1219254D03*
X1737976Y1350683D03*
Y1345691D03*
X1733020D03*
Y1350683D03*
X1737976Y1362595D03*
Y1357603D03*
X1733020Y1362595D03*
Y1357603D03*
X1737976Y1369889D03*
Y1374881D03*
X1733020Y1369889D03*
Y1381801D03*
Y1374881D03*
X1737976Y1381801D03*
Y1399079D03*
Y1394087D03*
Y1386793D03*
X1733020Y1399079D03*
Y1394087D03*
Y1386793D03*
X1737976Y1405999D03*
Y1410991D03*
X1733020Y1405999D03*
Y1410991D03*
X1732000Y1644980D03*
X1755727Y94017D03*
X1747727D03*
X1751727D03*
X1751855Y110445D03*
Y115401D03*
X1756847D03*
Y110445D03*
X1751855Y129574D03*
Y124618D03*
X1756847D03*
Y129574D03*
X1753418Y191941D03*
X1753285Y188727D03*
X1747242Y226141D03*
X1750042D03*
X1755112Y256535D03*
X1749939Y288190D03*
X1747139D03*
X1744639D03*
X1749939Y285690D03*
X1744639D03*
X1747139D03*
X1758165Y290755D03*
X1754165D03*
X1744524Y370010D03*
X1753474Y542699D03*
X1757402Y825111D03*
Y820155D03*
X1744937Y912517D03*
X1747937D03*
X1750751Y910785D03*
X1748081Y984379D03*
X1756192Y996132D03*
X1743224Y1119055D03*
X1752000Y1644980D03*
X1764804Y84140D03*
Y76140D03*
Y80140D03*
X1759736Y94017D03*
X1767249Y117557D03*
X1762257D03*
Y122513D03*
Y131731D03*
X1767249Y122513D03*
Y131731D03*
X1762257Y136687D03*
X1767249D03*
X1765950Y180572D03*
X1770633Y180527D03*
X1774356Y192421D03*
X1759918Y184619D03*
X1770588Y185121D03*
X1765950Y185165D03*
X1761898Y206760D03*
X1763112Y256535D03*
X1764142Y279208D03*
X1768246Y281307D03*
X1762165Y290755D03*
X1765497Y370899D03*
X1766204Y398949D03*
X1770778Y402642D03*
X1773278D03*
X1763704Y401949D03*
X1767953Y413611D03*
X1770453D03*
X1772953D03*
X1772893Y423944D03*
X1770393D03*
X1767893D03*
X1765093D03*
X1765153Y413611D03*
X1764912Y482382D03*
X1765006Y478382D03*
X1761953Y706827D03*
Y865160D03*
X1772599Y993053D03*
X1762898Y992883D03*
X1764744Y1101930D03*
Y1097879D03*
X1766899Y1121122D03*
X1769499D03*
X1772099D03*
X1774799D03*
X1766999Y1130822D03*
X1772199D03*
X1769599D03*
X1774339Y1437975D03*
X1774216Y1470165D03*
X1772000Y1644980D03*
X1788884Y59871D03*
X1782382Y55513D03*
X1778179Y117261D03*
X1785886Y172665D03*
Y180665D03*
X1785918Y200864D03*
Y212864D03*
Y216864D03*
Y221864D03*
X1790014Y468607D03*
X1784602Y564092D03*
X1782600Y874500D03*
X1774899Y1130822D03*
Y1139822D03*
X1777399D03*
Y1147822D03*
X1774899D03*
X1785961Y1224892D03*
X1791099Y1260421D03*
X1779868Y1446668D03*
X1786564Y1478858D03*
X1777131Y1604357D03*
X1791570Y74535D03*
X1793149Y662810D03*
X1798705Y718793D03*
X1805013Y1091877D03*
X1792847Y1099210D03*
X1799012Y1095893D03*
X1805013Y1096470D03*
X1792863Y1103246D03*
X1801147Y1208555D03*
X1802844Y1227695D03*
X1793976Y1440762D03*
X1807270Y1468535D03*
X1793879Y1472952D03*
X1792000Y1644980D03*
X1816322Y977215D03*
X1823074Y992833D03*
X1812296Y1075688D03*
X1809696Y1091832D03*
X1809651Y1096426D03*
X1823028Y1124289D03*
X1817728D03*
X1815128D03*
X1820328D03*
X1822928Y1114589D03*
X1820228D03*
X1815028D03*
X1817628D03*
X1815865Y1133356D03*
X1809897Y1237285D03*
Y1230385D03*
Y1232885D03*
Y1239785D03*
Y1244185D03*
Y1246685D03*
X1807393Y1436345D03*
X1812000Y1644980D03*
X1831511Y978888D03*
X1831914Y992877D03*
X1824706Y1081145D03*
Y1089145D03*
X1837933Y1636171D03*
X1832000Y1644980D03*
G54D36*
X141337Y1228542D03*
X141336Y1247242D03*
Y1239762D03*
X161909Y1129429D03*
X160039Y1228543D03*
X169389Y1121948D03*
X167519Y1198621D03*
Y1213582D03*
X174999Y1228543D03*
X182480D03*
X167519D03*
X189960D03*
X197440D03*
X210531Y1211712D03*
X212401Y1228543D03*
X204921D03*
X213969Y1453293D03*
Y1464293D03*
X218011Y1211712D03*
X227362Y1228543D03*
X219881D03*
X227249Y1464293D03*
Y1453293D03*
X242322Y1250984D03*
X234842D03*
Y1254724D03*
X242322D03*
X249803Y1250984D03*
X257283D03*
Y1254724D03*
X249803D03*
X294685Y1127558D03*
Y1135039D03*
Y1194881D03*
Y1202362D03*
X290944Y1191141D03*
X294685Y1209842D03*
X302165Y1108858D03*
X298425Y1112598D03*
X309645D03*
Y1120078D03*
X305905Y1116338D03*
X298425Y1120078D03*
X305905Y1123818D03*
X309645Y1135039D03*
Y1127558D03*
X311515Y1136909D03*
X304035Y1140649D03*
X305905Y1131299D03*
X296555Y1151869D03*
X304035Y1155610D03*
Y1148129D03*
X296555Y1144389D03*
X311515D03*
Y1151869D03*
X296555Y1159350D03*
Y1166830D03*
X304035Y1170570D03*
X300295D03*
X311515Y1159350D03*
X300295Y1185531D03*
Y1178051D03*
X296555Y1174310D03*
X298425Y1187401D03*
X304035Y1185531D03*
Y1178051D03*
Y1193011D03*
X302165Y1198621D03*
X305905Y1206102D03*
X302165Y1213582D03*
Y1206102D03*
X298425Y1221062D03*
Y1217322D03*
X313385Y1105117D03*
X317125Y1116338D03*
Y1123818D03*
X313385D03*
Y1116338D03*
X315255Y1136909D03*
X313384Y1131299D03*
X315255Y1144389D03*
Y1151869D03*
Y1159350D03*
Y1166830D03*
Y1181791D03*
Y1189271D03*
Y1174310D03*
X313385Y1198621D03*
Y1206102D03*
X320866Y1217322D03*
X317125Y1221062D03*
X313385Y1213582D03*
X324606Y1209842D03*
Y1217322D03*
X320866Y1221062D03*
X324606D03*
X320866Y1236023D03*
Y1224803D03*
X324606Y1232283D03*
Y1236023D03*
Y1224803D03*
Y1243503D03*
X598424Y1228542D03*
X598423Y1239762D03*
Y1247242D03*
X618996Y1129429D03*
X617126Y1228543D03*
X626476Y1121948D03*
X624606Y1198621D03*
Y1213582D03*
X632086Y1228543D03*
X624606D03*
X639567D03*
X647047D03*
X667618Y1211712D03*
X654527Y1228543D03*
X662008D03*
X669488D03*
X675098Y1211712D03*
X676968Y1228543D03*
X684449D03*
X729331Y1250984D03*
X721850D03*
Y1254724D03*
X729331D03*
X748031Y1194881D03*
X744291Y1254724D03*
Y1250984D03*
X736811Y1254724D03*
Y1250984D03*
X762992Y1116338D03*
X766732Y1120078D03*
X762992Y1123818D03*
X766732Y1112598D03*
X759252Y1108858D03*
X755512Y1120078D03*
X761122Y1140649D03*
X762992Y1131299D03*
X766732Y1135039D03*
Y1127558D03*
X751772D03*
Y1135039D03*
X753642Y1144389D03*
X761122Y1148129D03*
Y1155610D03*
X753642Y1151869D03*
X757382Y1170570D03*
X761122D03*
X753642Y1166830D03*
Y1159350D03*
Y1181791D03*
Y1174310D03*
X757382Y1178051D03*
Y1185531D03*
X761122Y1178051D03*
Y1185531D03*
X753642Y1189271D03*
X759252Y1191141D03*
X762992D03*
X755512Y1194881D03*
X759252Y1198621D03*
X751772Y1202362D03*
X755512Y1221062D03*
Y1217322D03*
X759252Y1213582D03*
X762992Y1206102D03*
X759252D03*
X751772Y1209842D03*
X770472Y1105117D03*
Y1123818D03*
X774212D03*
X770472Y1116338D03*
X774212D03*
X770471Y1131299D03*
X770472Y1138779D03*
X772342Y1151869D03*
Y1144389D03*
X768602Y1151869D03*
Y1144389D03*
X772342Y1166830D03*
X768602Y1159350D03*
X772342D03*
Y1174310D03*
Y1181791D03*
Y1196751D03*
X770472Y1198621D03*
X781693Y1217322D03*
X777953D03*
X774212Y1221062D03*
X781693Y1209842D03*
X770472Y1213582D03*
Y1206102D03*
X781693Y1224803D03*
X777953D03*
X781693Y1232283D03*
X777953Y1236023D03*
X781693D03*
Y1243503D03*
X1055510Y1228542D03*
X1055509Y1239762D03*
Y1247242D03*
X1074212Y1228543D03*
X1083562Y1121948D03*
X1076082Y1129429D03*
X1081692Y1198621D03*
Y1213582D03*
Y1228543D03*
X1089172D03*
X1104133D03*
X1096653D03*
X1124704Y1211712D03*
X1119094Y1228543D03*
X1111613D03*
X1132184Y1211712D03*
X1126574Y1228543D03*
X1134054D03*
X1141535D03*
X1149015Y1254724D03*
X1156495D03*
X1149015Y1250984D03*
X1156495D03*
X1171456D03*
X1163976D03*
X1171456Y1254724D03*
X1163976D03*
X1203247Y1193011D03*
X1216338Y1108858D03*
X1212598Y1120078D03*
X1220078Y1116338D03*
Y1123818D03*
X1218208Y1140649D03*
X1208858Y1127558D03*
X1220078Y1131299D03*
X1208858Y1135039D03*
X1210728Y1151869D03*
X1218208Y1155610D03*
Y1148129D03*
X1210728Y1144389D03*
Y1159350D03*
Y1166830D03*
X1218208Y1170570D03*
X1214468D03*
X1210728Y1181791D03*
Y1189271D03*
X1218208Y1185531D03*
Y1178051D03*
X1214468Y1185531D03*
Y1178051D03*
X1210728Y1174310D03*
X1212598Y1194881D03*
X1218208Y1193011D03*
X1214468D03*
X1216338Y1198621D03*
X1208858Y1202362D03*
X1220078Y1206102D03*
X1216338D03*
X1212598Y1221062D03*
Y1217322D03*
X1216338Y1213582D03*
X1208858Y1209842D03*
X1227558Y1105117D03*
X1223818Y1112598D03*
Y1120078D03*
X1227558Y1116338D03*
X1231298D03*
X1227558Y1123818D03*
X1231298D03*
X1229428Y1136909D03*
X1223818Y1127558D03*
X1227557Y1131299D03*
X1223818Y1135039D03*
X1225688Y1144389D03*
Y1151869D03*
X1229428Y1144389D03*
Y1151869D03*
Y1159350D03*
X1225688D03*
X1229428Y1166830D03*
Y1181791D03*
Y1189271D03*
Y1174310D03*
Y1196751D03*
X1227558Y1198621D03*
Y1206102D03*
X1235039Y1217322D03*
X1231298Y1221062D03*
X1227558Y1213582D03*
X1235039Y1221062D03*
Y1224803D03*
Y1236023D03*
X1238779Y1217322D03*
Y1209842D03*
Y1221062D03*
Y1224803D03*
Y1232283D03*
Y1236023D03*
Y1243503D03*
X1514468Y1166829D03*
Y1174309D03*
Y1181790D03*
X1512597Y1228542D03*
X1512596Y1239762D03*
Y1247242D03*
X1540649Y1121948D03*
X1533169Y1129429D03*
X1538779Y1198621D03*
Y1213582D03*
X1531299Y1228543D03*
X1538779D03*
X1546259D03*
X1561220D03*
X1553740D03*
X1576181D03*
X1568700D03*
X1589271Y1211712D03*
X1581791D03*
X1583661Y1228543D03*
X1591141D03*
X1598622D03*
X1636023Y1254724D03*
Y1250984D03*
X1643504D03*
Y1254724D03*
X1660334Y1204232D03*
Y1200491D03*
Y1193011D03*
Y1196751D03*
Y1207972D03*
X1650984Y1250984D03*
Y1254724D03*
X1658464D03*
Y1250984D03*
X1673425Y1108858D03*
X1669685Y1112598D03*
Y1120078D03*
X1675295Y1140649D03*
X1665945Y1127558D03*
Y1135039D03*
X1667815Y1151869D03*
X1675295Y1155610D03*
Y1148129D03*
X1667815Y1144389D03*
Y1159350D03*
Y1166830D03*
X1675295Y1170570D03*
X1671555D03*
Y1185531D03*
Y1178051D03*
X1667815Y1174310D03*
Y1181791D03*
Y1189271D03*
X1675295Y1185531D03*
Y1178051D03*
X1669685Y1194881D03*
X1675295Y1193011D03*
X1671555D03*
X1665945Y1202362D03*
X1673425Y1198621D03*
X1669685Y1221062D03*
Y1217322D03*
X1673425Y1213582D03*
X1665945Y1209842D03*
X1673425Y1206102D03*
X1684645Y1105117D03*
X1677165Y1116338D03*
X1680905Y1112598D03*
X1677165Y1123818D03*
X1680905Y1120078D03*
X1684645Y1116338D03*
X1688385D03*
X1684645Y1123818D03*
X1688385D03*
X1686515Y1136909D03*
X1682775D03*
X1680905Y1127558D03*
X1677165Y1131299D03*
X1684644D03*
X1680905Y1135039D03*
X1682775Y1144389D03*
Y1151869D03*
X1686515Y1144389D03*
Y1151869D03*
Y1159350D03*
X1682775D03*
X1686515Y1166830D03*
Y1174310D03*
Y1181791D03*
Y1189271D03*
X1684645Y1198621D03*
X1692126Y1217322D03*
X1688385Y1221062D03*
X1684645Y1213582D03*
Y1206102D03*
X1677165D03*
X1692126Y1224803D03*
Y1236023D03*
X1695866Y1217322D03*
Y1209842D03*
Y1232283D03*
Y1236023D03*
Y1224803D03*
Y1243503D03*
G54D27*
X73872Y1348187D03*
X81752D03*
X73872Y1360099D03*
X81752D03*
X73872Y1384297D03*
Y1372385D03*
X81752Y1384297D03*
Y1372385D03*
X86112Y1348187D03*
X98352D03*
X93992D03*
X86112Y1360099D03*
X98352D03*
X93992D03*
X86112Y1384297D03*
Y1372385D03*
X98352Y1384297D03*
Y1372385D03*
X93992D03*
Y1384297D03*
X86112Y1396583D03*
X93992D03*
X98352D03*
X86112Y1408495D03*
X93992D03*
X98352D03*
X110592Y1348187D03*
X106232D03*
X110592Y1360099D03*
X106232D03*
X110592Y1384297D03*
X106232D03*
Y1372385D03*
X110592D03*
Y1396583D03*
X106232D03*
X110592Y1408495D03*
X106232D03*
X118472Y1348187D03*
X122832D03*
X130712D03*
X118472Y1360099D03*
X122832D03*
X130712D03*
X118472Y1384297D03*
Y1372385D03*
X122832Y1384297D03*
Y1372385D03*
X130712Y1384297D03*
Y1372385D03*
X118472Y1396583D03*
X122832D03*
X130712D03*
X118472Y1408495D03*
X122832D03*
X130712D03*
X146948Y1080806D03*
Y1103247D03*
X143208D03*
X146948Y1133169D03*
Y1140649D03*
X139468Y1136909D03*
X143208Y1125688D03*
Y1133169D03*
Y1140649D03*
X146948Y1125688D03*
X143208Y1144389D03*
Y1151870D03*
X146948Y1144389D03*
Y1151870D03*
X140707Y1170569D03*
X143208Y1159350D03*
X146948D03*
X148818Y1183661D03*
X140707Y1178050D03*
X145078Y1187401D03*
Y1183661D03*
X148818Y1187401D03*
X146947Y1174310D03*
X141337Y1191142D03*
X145078Y1194881D03*
Y1202362D03*
X148818Y1194881D03*
Y1202362D03*
X141337Y1198622D03*
Y1206103D03*
X145078Y1209842D03*
Y1217322D03*
X148818Y1209842D03*
Y1217322D03*
X141337Y1213583D03*
Y1221063D03*
X148818Y1224803D03*
X145078Y1232283D03*
Y1236023D03*
X148818Y1232283D03*
Y1236023D03*
X145078Y1224803D03*
X148818Y1254724D03*
X135072Y1348187D03*
X142952D03*
X147312D03*
X135072Y1360099D03*
X147312D03*
X142952D03*
X135072Y1384297D03*
Y1372385D03*
X147312Y1384297D03*
Y1372385D03*
X142952Y1384297D03*
Y1372385D03*
X135072Y1396583D03*
X147312D03*
X142952D03*
X135072Y1408495D03*
X147312D03*
X142952D03*
X150688Y1077066D03*
X158169Y1106988D03*
X165649D03*
X161909D03*
X158169Y1118208D03*
Y1121948D03*
X154429D03*
X150689D03*
X165649Y1114468D03*
X161909D03*
X158169Y1133169D03*
X161909Y1140649D03*
X158169Y1125688D03*
X154429Y1129429D03*
X150689D03*
Y1136909D03*
X154429Y1140649D03*
X150689D03*
X165649D03*
Y1129429D03*
Y1136909D03*
X158169Y1140649D03*
X150689Y1151870D03*
X158169Y1155610D03*
X154429D03*
X150689D03*
X161909Y1144389D03*
Y1148129D03*
Y1151870D03*
Y1155610D03*
X150689Y1144389D03*
Y1148129D03*
Y1159350D03*
X158169Y1166830D03*
X150688D03*
X154429Y1170570D03*
X150688D03*
X161909Y1159350D03*
X160039Y1187401D03*
X156299Y1183661D03*
X152559D03*
X161909Y1174310D03*
Y1178051D03*
X165649Y1181791D03*
X161909D03*
X158169Y1174310D03*
X154429D03*
X150688Y1178051D03*
Y1174310D03*
X156299Y1179921D03*
X160039Y1183661D03*
X163779D03*
X156299Y1198621D03*
X152559D03*
X163779D03*
X160039D03*
X152559Y1191141D03*
X156299D03*
X160039D03*
X163779D03*
X160039Y1206102D03*
X156299D03*
X152559D03*
X163779D03*
X156299Y1213582D03*
X152559D03*
X160039Y1221062D03*
X156299D03*
X152559D03*
X163779D03*
X152559Y1228543D03*
X160039Y1224803D03*
X152559D03*
X156299Y1232283D03*
Y1236023D03*
X163779D03*
Y1232283D03*
X160039Y1239763D03*
X152559D03*
Y1243503D03*
X160039D03*
X163779Y1239763D03*
X152559Y1258465D03*
X160039D03*
X159552Y1348187D03*
X155192D03*
X159552Y1360099D03*
X155192D03*
X159552Y1372385D03*
Y1384297D03*
X155192D03*
Y1372385D03*
X159552Y1396583D03*
X155192D03*
X159552Y1408495D03*
X155192D03*
X174998Y1071455D03*
X182479D03*
X178740Y1090157D03*
X174999D03*
X171259D03*
X182480D03*
X178740Y1093897D03*
Y1097637D03*
X174999Y1101377D03*
X169389Y1106988D03*
X171259Y1093897D03*
X174999Y1105117D03*
X182480Y1101377D03*
Y1105117D03*
X174999Y1108858D03*
X178740D03*
X176870Y1114468D03*
Y1118208D03*
Y1121948D03*
X178740Y1112598D03*
X173129Y1110728D03*
X169389D03*
X180610Y1114468D03*
Y1118208D03*
Y1121948D03*
X182480Y1112598D03*
Y1108858D03*
X180610Y1136909D03*
X173129Y1133169D03*
X169389D03*
X176870Y1140649D03*
Y1125688D03*
Y1129429D03*
Y1133169D03*
Y1136909D03*
X173129Y1140649D03*
X169389D03*
X180610D03*
Y1125688D03*
Y1129429D03*
Y1133169D03*
Y1148129D03*
X173129Y1144389D03*
X169389D03*
X173129Y1148129D03*
Y1155610D03*
Y1151870D03*
X180610Y1155610D03*
Y1151870D03*
Y1144389D03*
X176870Y1170570D03*
X173129Y1159350D03*
Y1166830D03*
Y1170570D03*
X180610Y1166830D03*
Y1159350D03*
Y1174310D03*
Y1181791D03*
X173129Y1174310D03*
Y1178051D03*
Y1181791D03*
X171259Y1187401D03*
X174999D03*
X180610Y1178051D03*
X167519Y1183661D03*
X178740Y1187401D03*
X182480D03*
X176870Y1185531D03*
X173129D03*
X171259Y1202362D03*
Y1194881D03*
X174999Y1202362D03*
Y1194881D03*
X167519Y1191141D03*
X178740D03*
Y1194881D03*
Y1198621D03*
Y1202362D03*
X182480Y1191141D03*
Y1198621D03*
Y1202362D03*
X171259Y1209842D03*
X174999Y1217322D03*
X171259Y1221062D03*
X174999D03*
X171259Y1217322D03*
X167519Y1206102D03*
X178740D03*
Y1209842D03*
Y1213582D03*
Y1221062D03*
X182480D03*
X178740Y1217322D03*
X182480Y1206102D03*
Y1209842D03*
Y1213582D03*
Y1217322D03*
X178740Y1228543D03*
X171259Y1224803D03*
Y1228543D03*
X178740Y1224803D03*
Y1232283D03*
Y1236023D03*
X171259Y1232283D03*
X174999Y1224803D03*
X171259Y1236023D03*
X182480Y1224803D03*
X167519D03*
X182480Y1243503D03*
X171259Y1250984D03*
X174999Y1247243D03*
Y1239763D03*
X171259D03*
X167519D03*
Y1243503D03*
X175000Y1258465D03*
X182480D03*
X167519D03*
X167432Y1348187D03*
X171792D03*
X179672D03*
X167432Y1360099D03*
X171792D03*
X179672D03*
X167432Y1384297D03*
Y1372385D03*
X171792Y1384297D03*
Y1372385D03*
X179672Y1384297D03*
Y1372385D03*
X171792Y1396583D03*
X179672D03*
X167432D03*
Y1408495D03*
X171792D03*
X179672D03*
X197439Y1071455D03*
X189959D03*
X193700Y1090157D03*
X189960D03*
X186220D03*
X197440D03*
X193700Y1093897D03*
X189960Y1101377D03*
X186220Y1097637D03*
X189960Y1105117D03*
X186220Y1093897D03*
X193700Y1097637D03*
X197440Y1101377D03*
Y1105117D03*
X189960Y1093897D03*
X195570Y1121948D03*
X191830Y1118208D03*
X188090D03*
X184350D03*
X191830Y1121948D03*
X188090D03*
X184350D03*
X195570Y1118208D03*
X186220Y1108858D03*
X189960D03*
X193700D03*
X197440D03*
X191830Y1125688D03*
X188090D03*
X184350D03*
X188090Y1129429D03*
X184350D03*
X188090Y1133169D03*
X184350D03*
X188090Y1136909D03*
Y1140649D03*
X184350D03*
X195570Y1133169D03*
Y1129429D03*
Y1125688D03*
Y1136909D03*
X188090Y1144389D03*
Y1151870D03*
X191830Y1155610D03*
Y1148129D03*
X195570Y1151869D03*
Y1144389D03*
X188090Y1159350D03*
Y1170570D03*
X191830Y1166830D03*
X195570Y1159350D03*
Y1170570D03*
X188090Y1185531D03*
X195570Y1189271D03*
X191830Y1181791D03*
Y1174310D03*
X195570Y1185531D03*
Y1178051D03*
X188090Y1196751D03*
Y1200491D03*
Y1204232D03*
X191830D03*
Y1196751D03*
Y1200491D03*
X184350Y1193011D03*
Y1196751D03*
X195570Y1200491D03*
Y1196751D03*
Y1193011D03*
Y1204232D03*
X186220Y1198621D03*
X193700Y1209842D03*
X191830Y1207972D03*
X189960Y1209842D03*
X195570Y1207972D03*
X193700Y1213582D03*
X191830Y1219192D03*
X186220Y1221062D03*
X189960D03*
X193700D03*
X197440D03*
X186220Y1206102D03*
Y1209842D03*
Y1213582D03*
X197440Y1209842D03*
X186220Y1224803D03*
X193700Y1228543D03*
X197440Y1224803D03*
X193700Y1232283D03*
X186220D03*
X189960Y1224803D03*
X193700Y1236023D03*
X186220D03*
Y1228543D03*
X193700Y1224803D03*
X197440Y1239763D03*
Y1243503D03*
X193700Y1239763D03*
X186220D03*
X189960Y1243503D03*
Y1258465D03*
X197441D03*
X184032Y1348187D03*
X191912D03*
X196272D03*
X184032Y1360099D03*
X196272D03*
X191912D03*
X184032Y1384297D03*
Y1372385D03*
X196272Y1384297D03*
Y1372385D03*
X191912Y1384297D03*
Y1372385D03*
X184032Y1396583D03*
X191912D03*
X196272D03*
X184032Y1408495D03*
X191912D03*
X196272D03*
X204920Y1071455D03*
X212400D03*
X204921Y1090157D03*
X212401D03*
X208661D03*
X201181D03*
X204921Y1101377D03*
X208661Y1097637D03*
X201181D03*
X204921Y1105117D03*
X212401Y1101377D03*
Y1105117D03*
X201181Y1093897D03*
X208661D03*
X199311Y1118208D03*
Y1121948D03*
X206791Y1118208D03*
X203051D03*
Y1121948D03*
X206791D03*
X210531Y1118208D03*
X214271Y1110728D03*
X210531Y1121948D03*
X214271Y1118208D03*
Y1121948D03*
X201181Y1108858D03*
X204921D03*
X208661D03*
X212401D03*
X199311Y1140649D03*
X203051D03*
X206791D03*
X199311Y1125688D03*
X203051D03*
X206791D03*
Y1133169D03*
X203051D03*
X199311D03*
X210531D03*
Y1140649D03*
X214271D03*
Y1125688D03*
X210531D03*
X214271Y1133169D03*
X203051Y1148129D03*
X199311D03*
X206791D03*
X214271D03*
X210531D03*
X199311Y1155610D03*
X206791D03*
X214271D03*
X206791Y1166830D03*
X203051Y1159350D03*
X199311Y1166830D03*
X203051Y1170570D03*
X214271Y1166830D03*
X210531Y1159350D03*
Y1170570D03*
X206791Y1181791D03*
X203051D03*
X199311D03*
X206791Y1189271D03*
X203051D03*
X199311D03*
X214271Y1181791D03*
X210531D03*
X214271Y1189271D03*
X210531D03*
X199311Y1174310D03*
X206791D03*
X214271D03*
X206791Y1196751D03*
X203051D03*
X199311D03*
Y1204232D03*
X203051D03*
X206791D03*
X214271Y1196751D03*
X210531D03*
Y1204232D03*
X214271D03*
X206791Y1207972D03*
X203051D03*
X199311D03*
X210531D03*
X214271D03*
X212401Y1221062D03*
X208661D03*
X204921D03*
X201181D03*
Y1224803D03*
X208661Y1228543D03*
X212401Y1224803D03*
X208661Y1232283D03*
X201181D03*
X204921Y1224803D03*
X201181Y1236023D03*
X208661D03*
Y1224803D03*
X201181Y1228543D03*
X212401Y1243503D03*
X208661Y1239763D03*
X204921Y1243503D03*
X208661D03*
X204921Y1250984D03*
X208661Y1247243D03*
X212401Y1254724D03*
X201181Y1243503D03*
X212401Y1250984D03*
X201181Y1247243D03*
X204921Y1254724D03*
X212401Y1258465D03*
X204921D03*
X204152Y1348187D03*
Y1360099D03*
Y1384297D03*
Y1372385D03*
Y1396583D03*
Y1408495D03*
X219880Y1071455D03*
X227361D03*
X227362Y1090157D03*
X223622D03*
X219881D03*
X231102D03*
X216141D03*
X223622Y1093897D03*
X231102D03*
Y1097637D03*
X227362Y1101377D03*
Y1105117D03*
X219881Y1101377D03*
Y1105117D03*
X223622Y1097637D03*
X216141D03*
Y1093897D03*
X225492Y1118208D03*
Y1121948D03*
X218011Y1118208D03*
X221751D03*
X218011Y1121948D03*
X221751D03*
X229232D03*
Y1118208D03*
Y1114468D03*
X216141Y1108858D03*
X219881D03*
X223622D03*
X227362D03*
X231102D03*
X225492Y1133169D03*
Y1140649D03*
Y1125688D03*
X218011Y1140649D03*
X221751D03*
X218011Y1125688D03*
X221751D03*
Y1133169D03*
X218011D03*
X229330Y1132677D03*
X229232Y1140649D03*
Y1125688D03*
X225492Y1148129D03*
X221751D03*
X218011D03*
X229232D03*
X221751Y1155610D03*
X229232D03*
X225492Y1170570D03*
Y1159350D03*
X218011Y1170570D03*
X221752Y1166830D03*
X218011Y1159350D03*
X229232Y1166830D03*
X225492Y1181791D03*
Y1189271D03*
X221751Y1181791D03*
X218011D03*
X221751Y1189271D03*
X218011D03*
X229232Y1181791D03*
Y1189271D03*
X221751Y1174310D03*
X229232D03*
X218011Y1204232D03*
X229232Y1196751D03*
Y1204232D03*
X225492Y1196751D03*
Y1204232D03*
X221751D03*
Y1196751D03*
X218011D03*
X225492Y1207972D03*
X221751D03*
X218011D03*
X229232D03*
X231102Y1221062D03*
X227362D03*
X219881Y1217322D03*
X223622Y1221062D03*
X219881D03*
X216141D03*
X227362Y1224803D03*
X223622Y1232283D03*
X219881Y1224803D03*
X223622Y1236023D03*
X231102Y1232283D03*
Y1236023D03*
X216141Y1232283D03*
Y1236023D03*
Y1224803D03*
X223622D03*
Y1228543D03*
X216141D03*
X223622Y1239763D03*
X231102D03*
X227362Y1243503D03*
X219881D03*
X216141Y1239763D03*
X231102Y1243503D03*
Y1247243D03*
X223622Y1243503D03*
X216141Y1247243D03*
X223622D03*
X216141Y1243503D03*
X219881Y1250984D03*
Y1254724D03*
X227362D03*
Y1250984D03*
X219882Y1258465D03*
X227363D03*
X246062Y1075196D03*
X234841Y1071454D03*
X242321Y1071455D03*
X238582Y1075196D03*
X234842Y1090157D03*
X246062D03*
Y1078936D03*
X238582Y1090157D03*
X242322Y1086417D03*
X234842Y1082677D03*
Y1086417D03*
X242322Y1090157D03*
X246062Y1097637D03*
Y1093897D03*
X242322Y1105117D03*
X234842Y1101377D03*
X238582Y1093897D03*
X242322Y1101377D03*
X234842Y1105117D03*
X236712Y1121948D03*
X240452D03*
X244192D03*
X234842Y1108858D03*
X238582D03*
X242322D03*
X246062D03*
X236712Y1133464D03*
X240452Y1133169D03*
X236712Y1140649D03*
X240452D03*
X236712Y1125688D03*
X240452D03*
X244192Y1133169D03*
Y1140649D03*
Y1125688D03*
X236712Y1148129D03*
X240452D03*
X244192D03*
X240452Y1155610D03*
Y1166830D03*
X236712Y1170570D03*
Y1159350D03*
X244192Y1170570D03*
Y1159350D03*
X240452Y1181791D03*
X236712D03*
Y1189271D03*
X240452D03*
X244192Y1181791D03*
Y1189271D03*
X240452Y1174310D03*
Y1204232D03*
X236712D03*
Y1196751D03*
X240452D03*
X244192Y1204232D03*
Y1196751D03*
X240452Y1207972D03*
Y1211712D03*
X242322Y1221062D03*
X244192Y1211712D03*
Y1207972D03*
X236712D03*
X234842Y1221062D03*
X238582D03*
X246062Y1232283D03*
Y1236023D03*
X238582Y1232283D03*
X234842Y1228543D03*
Y1224803D03*
X238582Y1236023D03*
X242322Y1228543D03*
Y1224803D03*
X246062Y1239763D03*
X238582D03*
Y1247243D03*
X246062Y1243503D03*
Y1247243D03*
X238582Y1243503D03*
X234842Y1258465D03*
X242322D03*
X239383Y1348187D03*
X247263D03*
Y1360099D03*
X239383D03*
X247263Y1384297D03*
Y1372385D03*
X239383Y1384297D03*
Y1372385D03*
X253543Y1075196D03*
X261023D03*
X249802Y1071455D03*
X257282D03*
X253543Y1090157D03*
X249803D03*
Y1086417D03*
X253543Y1078936D03*
X257283Y1090157D03*
Y1086417D03*
X261023Y1090157D03*
Y1078936D03*
X249803Y1105117D03*
X253543Y1093897D03*
Y1097637D03*
X257283Y1105117D03*
X261023Y1093897D03*
Y1097637D03*
X249802D03*
X257282D03*
X249802Y1093897D03*
X257282D03*
X255413Y1121948D03*
X251673D03*
X247933D03*
X262893D03*
X259153D03*
X249803Y1108858D03*
X253543D03*
X257283D03*
X261023D03*
X247933Y1133169D03*
X251673D03*
X255413D03*
X247933Y1140649D03*
X251673D03*
X255413D03*
X247933Y1125688D03*
X251673D03*
X255413D03*
X259153Y1133169D03*
X262893D03*
Y1140649D03*
X259153Y1125688D03*
X262893D03*
X259153Y1140649D03*
Y1148129D03*
X262893D03*
Y1155610D03*
X247933Y1148129D03*
X251673D03*
X255413D03*
X247933Y1155610D03*
X255413D03*
X262893Y1166830D03*
X251673Y1170570D03*
X255413Y1166830D03*
X247933D03*
X251673Y1159350D03*
X259153D03*
Y1170570D03*
X247933Y1181791D03*
X251673D03*
X255413D03*
X247933Y1189271D03*
X251673D03*
X255413D03*
X262893D03*
Y1174310D03*
X259153Y1181791D03*
X262893D03*
X259153Y1189271D03*
X255413Y1174310D03*
X247933D03*
Y1204232D03*
X255413D03*
X251673D03*
X247933Y1196751D03*
X251673D03*
X255413D03*
X259153Y1204232D03*
X262893D03*
X259153Y1196751D03*
X262893D03*
X247933Y1207972D03*
X251673D03*
X255413Y1211712D03*
Y1207972D03*
X262893D03*
X259153D03*
X262893Y1211712D03*
X259153D03*
X249803Y1228543D03*
X257283D03*
X249803Y1224803D03*
X253543Y1236023D03*
X257283Y1224803D03*
X261023Y1236023D03*
X253543Y1232283D03*
X261023D03*
X257283Y1239763D03*
X253543Y1247243D03*
Y1243503D03*
X249803Y1258465D03*
X257283D03*
X263863Y1348187D03*
X259503D03*
X251623D03*
X263863Y1360099D03*
X259503D03*
X251623D03*
X263863Y1384297D03*
Y1372385D03*
X259503Y1384297D03*
Y1372385D03*
X251623D03*
Y1384297D03*
X263863Y1396583D03*
X259503D03*
X251623D03*
X263863Y1408495D03*
X259503D03*
X251623D03*
X279723Y1071455D03*
X264762D03*
X272243D03*
X268503Y1075196D03*
X275984D03*
X279724Y1090157D03*
X272244Y1082677D03*
X275984Y1090157D03*
X272244Y1086417D03*
X268503Y1078936D03*
Y1090157D03*
X264763Y1086417D03*
X272244Y1090157D03*
X264763D03*
X268503Y1093897D03*
Y1097637D03*
X272244Y1105117D03*
X279724D03*
X275984Y1093897D03*
X264763Y1105117D03*
X274114Y1118208D03*
X270373D03*
X266633Y1121948D03*
X270373D03*
X277854Y1118208D03*
X264763Y1108858D03*
X268503D03*
X272244D03*
X275984D03*
X279724D03*
X274114Y1125688D03*
X270373Y1136909D03*
X266633Y1133169D03*
X270373D03*
X266633Y1140649D03*
X270373Y1125688D03*
Y1129429D03*
X266633Y1125688D03*
X270373Y1140649D03*
X277854Y1136909D03*
Y1140649D03*
X274114Y1155610D03*
Y1151869D03*
Y1148129D03*
X266633D03*
X270373Y1144389D03*
Y1148129D03*
Y1151869D03*
X277854Y1144389D03*
Y1148129D03*
Y1151870D03*
X270373Y1155610D03*
X274114Y1166830D03*
Y1159350D03*
Y1170570D03*
X266633Y1181791D03*
X270373Y1189271D03*
X277854Y1178051D03*
Y1189271D03*
Y1185531D03*
X270373Y1174310D03*
X277854Y1181791D03*
X274114D03*
Y1174310D03*
X266633Y1189271D03*
X270373Y1178051D03*
Y1185531D03*
X274114Y1196751D03*
X270393Y1196732D03*
X270373Y1204232D03*
X266633D03*
X270373Y1200491D03*
X266633Y1196751D03*
X270373Y1193011D03*
X277854D03*
X274114Y1207972D03*
X270373Y1211712D03*
X266633Y1207972D03*
Y1211712D03*
X270373Y1207972D03*
X277854Y1211712D03*
X279724Y1221062D03*
X275984D03*
X272244D03*
X268503D03*
X279724Y1224803D03*
X272244D03*
X268503Y1236023D03*
Y1232283D03*
X272244Y1228543D03*
X264763Y1224803D03*
X275984Y1232283D03*
Y1236023D03*
X264763Y1228543D03*
X279724D03*
X268503Y1239763D03*
X279724Y1258465D03*
X264763D03*
X272244D03*
X276103Y1348187D03*
X271743D03*
X276103Y1360099D03*
X271743D03*
X276103Y1384297D03*
Y1372385D03*
X271743Y1384297D03*
Y1372385D03*
X276103Y1396583D03*
X271743D03*
Y1408495D03*
X276103D03*
X294684Y1071455D03*
X290944Y1075196D03*
X287203Y1071455D03*
X283464Y1075196D03*
X287204Y1090157D03*
X283464Y1078936D03*
Y1090157D03*
X290943D03*
X290944Y1093897D03*
X287204Y1101377D03*
Y1105117D03*
X294685D03*
X294684Y1120078D03*
Y1112598D03*
X283464Y1108858D03*
X287204D03*
X290944D03*
X294685D03*
X290944Y1112598D03*
Y1116338D03*
Y1120078D03*
Y1123818D03*
X281594Y1140649D03*
Y1136909D03*
X290944Y1127558D03*
Y1131299D03*
Y1135039D03*
Y1138779D03*
X281594Y1148129D03*
Y1155610D03*
Y1151869D03*
X285334D03*
X289074D03*
Y1155610D03*
X292814Y1151869D03*
Y1144389D03*
X281594Y1159350D03*
X289074Y1166830D03*
Y1170570D03*
Y1159350D03*
X281594Y1170570D03*
Y1166830D03*
X292814Y1159350D03*
Y1166830D03*
Y1181791D03*
X285334Y1185531D03*
X289074Y1174310D03*
Y1178051D03*
Y1185531D03*
X281594Y1189271D03*
Y1185531D03*
X285334Y1181791D03*
X281594Y1178051D03*
Y1174310D03*
X292814D03*
Y1189271D03*
X281594Y1196751D03*
Y1204232D03*
Y1193011D03*
X285334D03*
X290944Y1194881D03*
Y1198621D03*
Y1202362D03*
X294685Y1221062D03*
Y1217322D03*
X290944Y1221062D03*
X287204D03*
X283464D03*
X290944Y1206102D03*
Y1209842D03*
Y1213582D03*
Y1217322D03*
X294685Y1228543D03*
Y1224803D03*
X290944Y1232283D03*
Y1236023D03*
X283464Y1232283D03*
X287204Y1228543D03*
X283464Y1236023D03*
X287204Y1224803D03*
X283464Y1239763D03*
X290944D03*
X294685Y1254724D03*
Y1250984D03*
X290944Y1247243D03*
Y1243503D03*
X294685Y1258465D03*
X287204D03*
X288343Y1348187D03*
X296223D03*
X283983D03*
X288343Y1360099D03*
X296223D03*
X283983D03*
X288343Y1384297D03*
Y1372385D03*
X296223Y1384297D03*
Y1372385D03*
X283983D03*
Y1384297D03*
X288343Y1396583D03*
X296223D03*
X283983D03*
X288343Y1408495D03*
X296223D03*
X283983D03*
X309645Y1071455D03*
X302165D03*
X298425Y1075196D03*
X305906D03*
X298424Y1090157D03*
X298426Y1078936D03*
X305906D03*
X302165Y1105117D03*
X309645D03*
X298425Y1093897D03*
X305905D03*
X302165Y1123818D03*
X305904Y1108857D03*
X302165Y1116338D03*
X298425Y1108858D03*
X300295Y1140649D03*
X302165Y1131299D03*
X300295Y1148129D03*
Y1159350D03*
Y1166830D03*
X311515D03*
X307775Y1170570D03*
X300295Y1181791D03*
Y1174310D03*
Y1189271D03*
X311515Y1174310D03*
X307775Y1178051D03*
X311515Y1181791D03*
X307775Y1185531D03*
X311515Y1189271D03*
X298425Y1202362D03*
Y1194881D03*
X309645Y1198621D03*
X307775Y1193011D03*
X311515Y1196751D03*
X305905Y1198621D03*
X309645Y1202362D03*
X298425Y1209842D03*
X302165Y1221062D03*
X309645Y1217322D03*
Y1209842D03*
X305905Y1213582D03*
X309645D03*
Y1206102D03*
Y1221062D03*
X305905D03*
X298425Y1236023D03*
Y1232283D03*
X302165Y1228543D03*
Y1224803D03*
X305905Y1232283D03*
X309645Y1228543D03*
Y1224803D03*
X305905Y1236023D03*
X298425Y1239763D03*
X309645D03*
Y1254724D03*
X298425Y1247243D03*
X309645Y1250984D03*
X298425Y1243503D03*
X305905D03*
Y1247243D03*
X302165Y1254724D03*
Y1250984D03*
X309645Y1258465D03*
X302165D03*
X308463Y1348187D03*
X300583D03*
X308463Y1360099D03*
X300583D03*
X308463Y1372385D03*
X300583D03*
Y1384297D03*
X308463D03*
Y1396583D03*
X300583D03*
X308463Y1408495D03*
X300583D03*
X317125Y1071455D03*
X320866Y1075196D03*
X313386D03*
X320866Y1078936D03*
X313384Y1090157D03*
X313386Y1078936D03*
X328347Y1082677D03*
Y1090158D03*
X324606Y1078936D03*
X313385Y1093897D03*
X328347Y1101378D03*
Y1116339D03*
Y1123819D03*
Y1108859D03*
X313385Y1108858D03*
X328347Y1131300D03*
X318996Y1140649D03*
Y1155610D03*
Y1148129D03*
X322736Y1170570D03*
X318996D03*
Y1185531D03*
Y1178051D03*
X322736D03*
Y1185531D03*
X328347Y1198621D03*
X322736Y1193011D03*
X320866Y1202362D03*
X318996Y1193011D03*
X326416D03*
X324606Y1202362D03*
X328347Y1206102D03*
Y1221062D03*
Y1213582D03*
X320866Y1209842D03*
X313385Y1221062D03*
X320866Y1206102D03*
Y1232283D03*
X313385D03*
X317125Y1228543D03*
Y1224803D03*
X313385Y1236023D03*
X328347Y1228543D03*
Y1239762D03*
Y1247243D03*
X324606Y1250984D03*
X317125Y1254724D03*
X324606Y1239763D03*
X313385Y1247243D03*
X317125Y1250984D03*
X320866Y1239763D03*
X313385Y1243503D03*
X317125Y1258465D03*
X320703Y1348187D03*
X312823D03*
X325063D03*
X320703Y1360099D03*
X312823D03*
X325063D03*
X320703Y1372385D03*
Y1384297D03*
X312823Y1372385D03*
Y1384297D03*
X325063Y1372385D03*
Y1384297D03*
Y1396583D03*
X320703D03*
X312823D03*
X320703Y1408495D03*
X312823D03*
X325063D03*
X318448Y1750941D03*
Y1760941D03*
X318348Y1796941D03*
Y1806941D03*
X337303Y1348187D03*
X332943D03*
Y1360099D03*
X337303D03*
X332943Y1384297D03*
Y1372385D03*
X337303D03*
Y1384297D03*
X332943Y1396583D03*
X337303D03*
X332943Y1408495D03*
X337303D03*
X349543Y1348187D03*
X357423D03*
X345183D03*
X349543Y1360099D03*
X357423D03*
X345183D03*
Y1372385D03*
Y1384297D03*
X349543D03*
Y1372385D03*
X357423D03*
Y1384297D03*
X345183Y1396583D03*
X349543D03*
X357423D03*
X345183Y1408495D03*
X349543D03*
X357423D03*
X369663Y1348187D03*
X361783D03*
X369663Y1360099D03*
X361783D03*
X369663Y1372385D03*
Y1384297D03*
X361783D03*
Y1372385D03*
X369663Y1396583D03*
X361783D03*
X369663Y1408495D03*
X361783D03*
X458282Y1348187D03*
X446042D03*
X458282Y1360099D03*
X446042D03*
X458282Y1372385D03*
X446042D03*
X458282Y1384297D03*
X446042D03*
X458282Y1396583D03*
Y1408495D03*
X470522Y1348187D03*
Y1360099D03*
Y1384297D03*
Y1372385D03*
Y1396583D03*
Y1408495D03*
X482762Y1348187D03*
Y1360099D03*
Y1384297D03*
Y1372385D03*
Y1396583D03*
Y1408495D03*
X507242Y1348187D03*
X495002D03*
X507242Y1360099D03*
X495002D03*
Y1384297D03*
X507242D03*
X495002Y1372385D03*
X507242D03*
Y1396583D03*
X495002D03*
X507242Y1408495D03*
X495002D03*
X519482Y1348187D03*
Y1360099D03*
Y1384297D03*
Y1372385D03*
Y1396583D03*
Y1408495D03*
X531722Y1348187D03*
Y1360099D03*
Y1384297D03*
Y1372385D03*
Y1396583D03*
Y1408495D03*
X556202Y1348187D03*
X543962D03*
X556202Y1360099D03*
X543962D03*
Y1372385D03*
Y1384297D03*
X556202D03*
Y1372385D03*
Y1396583D03*
X543962D03*
X556202Y1408495D03*
X543962D03*
X568442Y1348187D03*
Y1360099D03*
Y1384297D03*
Y1372385D03*
Y1396583D03*
Y1408495D03*
X604035Y1080806D03*
Y1103247D03*
X600295D03*
Y1125688D03*
Y1133169D03*
Y1140649D03*
X604035Y1125688D03*
Y1133169D03*
Y1140649D03*
X600295Y1144389D03*
Y1151870D03*
X604035Y1144389D03*
Y1151870D03*
X600295Y1159350D03*
X604035D03*
X597795Y1170570D03*
X604034Y1174310D03*
X597795Y1178050D03*
X602165Y1183661D03*
Y1187401D03*
Y1202362D03*
Y1194881D03*
X598424Y1198622D03*
Y1191142D03*
X602165Y1191141D03*
Y1198621D03*
Y1217322D03*
Y1209842D03*
X598424Y1221063D03*
Y1213583D03*
Y1206103D03*
X602165Y1221062D03*
Y1206102D03*
Y1213582D03*
Y1224803D03*
Y1236023D03*
Y1232283D03*
Y1247243D03*
Y1239763D03*
X605386Y1728583D03*
Y1738583D03*
X605312Y1774624D03*
Y1784624D03*
X607775Y1077066D03*
X615256Y1106988D03*
X618996D03*
X615256Y1118208D03*
Y1121948D03*
X611516D03*
X607776D03*
X618996Y1114468D03*
X615256Y1125688D03*
X611516Y1129429D03*
X607776D03*
Y1136909D03*
X615256Y1140649D03*
X611516D03*
X607776D03*
X618996D03*
Y1144389D03*
Y1148129D03*
Y1151870D03*
Y1155610D03*
X607776Y1144389D03*
Y1148129D03*
Y1151870D03*
X615256Y1155610D03*
X611516D03*
X607776D03*
Y1159350D03*
X615256Y1166830D03*
X607775D03*
X611516Y1170570D03*
X607775D03*
X618996Y1159350D03*
Y1174310D03*
Y1178051D03*
X607775Y1174310D03*
Y1178051D03*
X611516Y1174310D03*
X615256D03*
X613386Y1183661D03*
X617126Y1187401D03*
Y1183661D03*
X613386Y1179921D03*
X620866Y1183661D03*
X609646D03*
X605905D03*
Y1187401D03*
X613386D03*
X609646D03*
X620866D03*
X613386Y1198621D03*
X609646Y1191141D03*
X613386D03*
X617126Y1198621D03*
X620866D03*
X617126Y1191141D03*
X620866D03*
X605905Y1202362D03*
Y1194881D03*
X609646Y1198621D03*
X605905Y1191141D03*
X613386Y1194881D03*
X605905Y1198621D03*
X609646Y1194881D03*
Y1202362D03*
X613386D03*
X620866D03*
Y1194881D03*
X613386Y1221062D03*
X609646D03*
Y1213582D03*
X613386D03*
X620866Y1206102D03*
X617126D03*
X620866Y1221062D03*
X617126D03*
X613386Y1206102D03*
X605905Y1217322D03*
Y1209842D03*
X609646Y1206102D03*
X613386Y1217322D03*
X605905Y1221062D03*
X609646Y1217322D03*
Y1209842D03*
X605905Y1206102D03*
Y1213582D03*
X620866Y1209842D03*
X613386D03*
X620866Y1217322D03*
X605905Y1224803D03*
Y1232283D03*
Y1236023D03*
X620866D03*
Y1232283D03*
X617126Y1224803D03*
X609646D03*
Y1228543D03*
X613386Y1232283D03*
Y1236023D03*
X620866Y1228543D03*
Y1224803D03*
X613386Y1228543D03*
Y1224803D03*
X617126Y1243503D03*
Y1239763D03*
X620866D03*
X609646Y1243503D03*
Y1239763D03*
X605905Y1247243D03*
X617126Y1250984D03*
X620866Y1243503D03*
Y1247243D03*
X609646Y1254724D03*
X613386Y1247243D03*
X617126Y1254724D03*
X613386Y1243503D03*
X609646Y1250984D03*
X605905Y1239763D03*
X617126Y1258465D03*
X609646D03*
X632085Y1071455D03*
X626476Y1092027D03*
X635827Y1090157D03*
X628346D03*
X632086D03*
X630216Y1099507D03*
X626476Y1106988D03*
X622736D03*
X626476Y1095767D03*
X630216Y1103247D03*
X635827Y1093897D03*
X632086Y1101377D03*
Y1105117D03*
X628346Y1093897D03*
X635827Y1097637D03*
X633957Y1110728D03*
X630216D03*
X626476D03*
X622736Y1114468D03*
X630216Y1118208D03*
X626476D03*
X633957Y1114468D03*
Y1118208D03*
Y1121948D03*
X635827Y1108858D03*
X632086D03*
X633957Y1140649D03*
Y1125688D03*
Y1129429D03*
Y1133169D03*
Y1136909D03*
X630216Y1140649D03*
X626476D03*
X622736D03*
Y1129429D03*
X630216Y1144389D03*
X626476D03*
X630216Y1148129D03*
Y1155610D03*
Y1151870D03*
Y1159350D03*
Y1166830D03*
Y1170570D03*
X633957D03*
Y1185531D03*
X628346Y1183661D03*
X630216Y1174310D03*
Y1178051D03*
Y1181791D03*
X632086Y1187401D03*
X628346D03*
X624606Y1183661D03*
X635827Y1187401D03*
X624606D03*
Y1191141D03*
X632086Y1202362D03*
X628346D03*
X632086Y1194881D03*
X628346D03*
X635827Y1191141D03*
Y1194881D03*
Y1198621D03*
Y1202362D03*
X628346Y1191141D03*
X624606Y1194881D03*
X632086Y1191141D03*
X628346Y1198621D03*
X624606Y1202362D03*
X632086Y1198621D03*
X624606Y1206102D03*
X628346Y1209842D03*
Y1217322D03*
Y1221062D03*
X632086D03*
Y1217322D03*
X635827Y1221062D03*
Y1206102D03*
Y1209842D03*
Y1213582D03*
Y1217322D03*
X628346Y1206102D03*
X632086D03*
X624606Y1217322D03*
X628346Y1213582D03*
X632086D03*
X624606Y1209842D03*
X632086Y1224803D03*
X624606D03*
X628346Y1236023D03*
Y1232283D03*
X635827Y1236023D03*
Y1232283D03*
X628346Y1224803D03*
Y1228543D03*
X635827D03*
Y1224803D03*
X632086Y1247243D03*
Y1239763D03*
X628346D03*
Y1250984D03*
X624606Y1243503D03*
Y1239763D03*
Y1254724D03*
Y1250984D03*
X632086Y1254724D03*
X635827Y1243503D03*
X632086Y1250984D03*
X635827Y1247243D03*
X628346Y1243503D03*
Y1247243D03*
X632087Y1258465D03*
X624606D03*
X631928Y1396583D03*
Y1408495D03*
X647046Y1071455D03*
X639566D03*
X643307Y1090157D03*
X639567D03*
X650787D03*
X647047D03*
X639567Y1101377D03*
Y1105117D03*
X647047D03*
Y1101377D03*
X650787Y1097637D03*
X643307D03*
Y1093897D03*
X650787D03*
X647047D03*
X637697Y1114468D03*
X648917Y1118208D03*
X645177D03*
X641437D03*
X637697D03*
X648917Y1121948D03*
X645177D03*
X641437D03*
X637697D03*
Y1110728D03*
X652657Y1118208D03*
Y1121948D03*
X650787Y1108858D03*
X647047D03*
X643307D03*
X639567D03*
X641437Y1133169D03*
X637697D03*
X645177Y1136909D03*
X637697D03*
X645177Y1140649D03*
X641437D03*
X652657Y1133169D03*
Y1129429D03*
Y1125688D03*
Y1136909D03*
X637697Y1140649D03*
X648917Y1125688D03*
X645177D03*
X641437D03*
X637697D03*
X645177Y1129429D03*
X641437D03*
X637697D03*
X645177Y1133169D03*
X637697Y1155610D03*
Y1151870D03*
X645177Y1144389D03*
X637697D03*
Y1148129D03*
X645177Y1151870D03*
X648917Y1155610D03*
Y1148129D03*
X652657Y1151869D03*
Y1144389D03*
X645177Y1170570D03*
X637697Y1166830D03*
X645177Y1159350D03*
X637697D03*
X648917Y1166830D03*
X652657Y1159350D03*
Y1170570D03*
X637697Y1189271D03*
X645177Y1185531D03*
X637697D03*
Y1178051D03*
Y1174310D03*
Y1181791D03*
X652657Y1189271D03*
X648917Y1181791D03*
Y1174310D03*
X652657Y1185531D03*
Y1178051D03*
Y1193011D03*
Y1204232D03*
X637697Y1193011D03*
X645177Y1196751D03*
Y1200491D03*
X641437D03*
Y1204232D03*
X645177D03*
X648917D03*
Y1196751D03*
Y1200491D03*
X641437Y1193011D03*
Y1196751D03*
X652657Y1200491D03*
Y1196751D03*
Y1211712D03*
X648917Y1219192D03*
X641437D03*
Y1211712D03*
X645177D03*
X648917D03*
Y1207972D03*
X645177D03*
X641437D03*
X652657D03*
X639567Y1221062D03*
X647047D03*
X643307D03*
X650787D03*
X639567Y1224803D03*
X643307Y1236023D03*
Y1232283D03*
X650787Y1236023D03*
X647047Y1224803D03*
X650787Y1232283D03*
X643307Y1224803D03*
Y1228543D03*
X650787D03*
Y1224803D03*
X639567Y1243503D03*
X647047D03*
X650787Y1239763D03*
X643307D03*
X639567Y1250984D03*
Y1254724D03*
X650787Y1247243D03*
Y1243503D03*
X647047Y1254724D03*
Y1250984D03*
X643307Y1247243D03*
Y1243503D03*
X647047Y1258465D03*
X639567D03*
X644168Y1384297D03*
Y1372385D03*
Y1396583D03*
Y1408495D03*
X669487Y1071455D03*
X662007D03*
X654526D03*
X669488Y1090157D03*
X665748D03*
X654527D03*
X658268D03*
X662008D03*
Y1101377D03*
X665748Y1093897D03*
X658268D03*
X654527Y1105117D03*
Y1101377D03*
X662008Y1105117D03*
X658268Y1097637D03*
X669488Y1101377D03*
Y1105117D03*
X665748Y1097637D03*
X656398Y1118208D03*
Y1121948D03*
X663878Y1118208D03*
X660138D03*
Y1121948D03*
X663878D03*
X667618Y1118208D03*
Y1121948D03*
X669488Y1108858D03*
X665748D03*
X662008D03*
X658268D03*
X654527D03*
X656398Y1140649D03*
X660138D03*
X663878D03*
X656398Y1125688D03*
X660138D03*
X663878D03*
Y1133169D03*
X660138D03*
X656398D03*
X667618D03*
Y1140649D03*
Y1125688D03*
Y1148129D03*
X660138D03*
X656398D03*
X663878D03*
X656398Y1155610D03*
X663878D03*
Y1166830D03*
X660138Y1159350D03*
X656398Y1166830D03*
X660138Y1170570D03*
X667618Y1159350D03*
Y1170570D03*
X663878Y1181791D03*
X660138D03*
X656398D03*
X663878Y1189271D03*
X660138D03*
X656398D03*
X667618Y1181791D03*
Y1189271D03*
X656398Y1174310D03*
X663878D03*
Y1196751D03*
X660138D03*
X656398D03*
Y1204232D03*
X660138D03*
X663878D03*
X667618Y1196751D03*
Y1204232D03*
X663878Y1207972D03*
X660138D03*
X656398D03*
X667618D03*
X654527Y1221062D03*
X658268D03*
X662008D03*
X665748D03*
X669488D03*
X654527Y1224803D03*
X658268Y1236023D03*
Y1232283D03*
X662008Y1224803D03*
X665748Y1236023D03*
Y1232283D03*
X669488Y1224803D03*
X654527Y1239763D03*
Y1243503D03*
X665748Y1239763D03*
X669488Y1243503D03*
X662008D03*
X654527Y1254724D03*
Y1250984D03*
X662008Y1258465D03*
X669488D03*
X654528D03*
X668648Y1348187D03*
X656408D03*
X668648Y1360099D03*
X656408D03*
Y1384297D03*
Y1372385D03*
X668648D03*
Y1384297D03*
Y1396583D03*
X656408D03*
X668648Y1408495D03*
X656408D03*
X684448Y1071455D03*
X676967D03*
X680709Y1090157D03*
X676968D03*
X684449D03*
X673228D03*
X676968Y1105117D03*
X684449Y1101377D03*
Y1105117D03*
X680709Y1093897D03*
X676968Y1101377D03*
X680709Y1097637D03*
X673228D03*
Y1093897D03*
X682579Y1118208D03*
Y1121948D03*
X671358Y1118208D03*
X675098D03*
X678838D03*
X675098Y1121948D03*
X678838D03*
X671358D03*
X684449Y1108858D03*
X680709D03*
X676968D03*
X673228D03*
X682579Y1133169D03*
Y1140649D03*
Y1125688D03*
X671358Y1140649D03*
X675098D03*
X678838D03*
X675098Y1125688D03*
X671358D03*
X678838D03*
Y1133169D03*
X675098D03*
X671358D03*
X682579Y1148129D03*
X678838D03*
X675098D03*
X671358D03*
Y1155610D03*
X678838D03*
X682579Y1170570D03*
Y1159350D03*
X675098Y1170570D03*
X678839Y1166830D03*
X671358D03*
X675098Y1159350D03*
Y1181791D03*
X671358D03*
X678838Y1189271D03*
X675098D03*
X671358D03*
X682579Y1181791D03*
Y1189271D03*
X678838Y1181791D03*
X671358Y1174310D03*
X678838D03*
X682579Y1196751D03*
Y1204232D03*
X678838D03*
Y1196751D03*
X675098D03*
X671358D03*
Y1204232D03*
X675098D03*
X682579Y1207972D03*
X678838Y1219192D03*
Y1207972D03*
X675098D03*
X671358D03*
X673228Y1221062D03*
X676968D03*
X680709D03*
X684449D03*
X673228Y1236023D03*
Y1232283D03*
X676968Y1224803D03*
X680709Y1236023D03*
Y1232283D03*
X684449Y1224803D03*
X673228Y1239763D03*
X680709D03*
X676968Y1243503D03*
X684449D03*
X684450Y1258465D03*
X676969D03*
X680888Y1348187D03*
Y1360099D03*
Y1372385D03*
Y1384297D03*
Y1396583D03*
Y1408495D03*
X695669Y1075196D03*
X699408Y1071455D03*
X691928Y1071454D03*
X688189Y1090157D03*
X691929Y1082677D03*
Y1086417D03*
X695669Y1090157D03*
X699409D03*
Y1086417D03*
X691929Y1090157D03*
X688189Y1097637D03*
X695669Y1093897D03*
X688189D03*
X699409Y1105117D03*
X691929Y1101377D03*
X699409D03*
X691929Y1105117D03*
X693799Y1121948D03*
X697539D03*
X701279D03*
X686319D03*
Y1118208D03*
Y1114468D03*
X699409Y1108858D03*
X695669D03*
X691929D03*
X688189D03*
X693799Y1133464D03*
X697539Y1133169D03*
X686417Y1132677D03*
X693799Y1140649D03*
X697539D03*
X693799Y1125688D03*
X697539D03*
X701279D03*
Y1140649D03*
Y1133169D03*
X686319Y1140649D03*
Y1125688D03*
X697539Y1148129D03*
X701279D03*
X693799D03*
X697539Y1155610D03*
X686319Y1148129D03*
Y1155610D03*
X697539Y1166830D03*
X693799Y1170570D03*
Y1159350D03*
X701279D03*
Y1170570D03*
X686319Y1166830D03*
X693799Y1181791D03*
Y1189271D03*
X697539D03*
X701279D03*
Y1181791D03*
X697539D03*
Y1174310D03*
X686319Y1181791D03*
Y1189271D03*
Y1174310D03*
X697539Y1204232D03*
X693799D03*
Y1196751D03*
X697539D03*
X701279D03*
Y1204232D03*
X686319Y1196751D03*
Y1204232D03*
X693799Y1207972D03*
X697539D03*
Y1211712D03*
X701279Y1207972D03*
Y1211712D03*
X686319Y1207972D03*
X695669Y1221062D03*
X699409D03*
X691929D03*
X688189D03*
Y1236023D03*
Y1232283D03*
X691929Y1224803D03*
Y1228543D03*
X699409Y1224803D03*
Y1228543D03*
X695669Y1236023D03*
Y1232283D03*
X688189Y1239763D03*
X695669D03*
X699409Y1258465D03*
X691929D03*
X693128Y1348187D03*
Y1360099D03*
Y1372385D03*
Y1384297D03*
Y1396583D03*
Y1408495D03*
X703149Y1075196D03*
X718110D03*
X710630D03*
X714369Y1071455D03*
X706889D03*
X710630Y1078936D03*
X706890Y1086417D03*
Y1090157D03*
X718110Y1078936D03*
X714370Y1086417D03*
Y1090157D03*
X710630D03*
X718110D03*
X703149Y1078936D03*
Y1090157D03*
X706890Y1105117D03*
X714370D03*
X710630Y1097637D03*
Y1093897D03*
X718110Y1097637D03*
Y1093897D03*
X703149D03*
Y1097637D03*
X714369D03*
X706889Y1093897D03*
X714369D03*
X706889Y1097637D03*
X716240Y1121948D03*
X705020D03*
X708760D03*
X712500D03*
X718110Y1108858D03*
X714370D03*
X710630D03*
X706890D03*
X703149D03*
X716240Y1140649D03*
Y1125688D03*
Y1133169D03*
X712500Y1125688D03*
X708760D03*
X705020D03*
X712500Y1140649D03*
X708760D03*
X705020D03*
X712500Y1133169D03*
X708760D03*
X705020D03*
X716240Y1148129D03*
X712500D03*
X708760D03*
X705020D03*
X712500Y1155610D03*
X705020D03*
X716240Y1170570D03*
Y1159350D03*
X708760D03*
X705020Y1166830D03*
X712500D03*
X708760Y1170570D03*
X716240Y1189271D03*
Y1181791D03*
X712500Y1189271D03*
X708760D03*
X705020D03*
X712500Y1181791D03*
X708760D03*
X705020D03*
Y1174310D03*
X712500D03*
X716240Y1196751D03*
Y1204232D03*
X712500Y1196751D03*
X708760D03*
X705020D03*
X708760Y1204232D03*
X712500D03*
X705020D03*
X716240Y1211712D03*
Y1207972D03*
X712500D03*
Y1211712D03*
X708760Y1207972D03*
X705020D03*
X703149Y1221062D03*
X706890D03*
X710630D03*
X714370D03*
X718110D03*
X703149Y1236023D03*
Y1232283D03*
X710630Y1236023D03*
X718110D03*
Y1232283D03*
X710630D03*
X714370Y1224803D03*
Y1228543D03*
X706890Y1224803D03*
Y1228543D03*
X703149Y1239763D03*
X714370D03*
X718110Y1243503D03*
Y1247243D03*
X714370Y1258465D03*
X706890D03*
X705368Y1348187D03*
X717608D03*
X705368Y1360099D03*
X717608D03*
X705368Y1372385D03*
Y1384297D03*
X717608Y1372385D03*
Y1384297D03*
Y1396583D03*
X705368D03*
X717608Y1408495D03*
X705368D03*
X725590Y1075196D03*
X733071D03*
X729330Y1071455D03*
X721849D03*
X729331Y1086417D03*
Y1082677D03*
X733071Y1090157D03*
X729331D03*
X725590D03*
X721850D03*
X725590Y1078936D03*
X721850Y1086417D03*
X725590Y1097637D03*
X721850Y1105117D03*
X725590Y1093897D03*
X729331Y1105117D03*
X733071Y1093897D03*
X734941Y1118208D03*
X727460Y1121948D03*
X719980D03*
X723720D03*
X727460Y1118208D03*
X731201D03*
X733071Y1108858D03*
X729331D03*
X725590D03*
X721850D03*
X734941Y1140649D03*
Y1136909D03*
X727460Y1140649D03*
X723720Y1125688D03*
X719980D03*
X727460Y1129429D03*
Y1125688D03*
X723720Y1140649D03*
X719980D03*
X727460Y1133169D03*
X723720D03*
X719980D03*
X727460Y1136909D03*
X731201Y1125688D03*
X727460Y1151869D03*
Y1148129D03*
Y1144389D03*
X723720Y1148129D03*
X719980D03*
X731201D03*
Y1151869D03*
Y1155610D03*
X734941Y1151870D03*
Y1148129D03*
Y1144389D03*
X719980Y1155610D03*
X727460D03*
X731201Y1170570D03*
X719980Y1166830D03*
X731201Y1159350D03*
Y1166830D03*
X727460Y1185531D03*
X734941Y1181791D03*
Y1185531D03*
Y1189271D03*
Y1178051D03*
X727460Y1189271D03*
X723720Y1181791D03*
X719980D03*
Y1174310D03*
X727460Y1178051D03*
X723720Y1189271D03*
X719980D03*
X731201Y1174310D03*
Y1181791D03*
X727460Y1174310D03*
X719980Y1204232D03*
X727460D03*
X727480Y1196732D03*
X731201Y1196751D03*
X734941Y1193011D03*
X727460D03*
X723720Y1196751D03*
X719980D03*
X727460Y1200491D03*
X723720Y1204232D03*
X734941Y1211712D03*
X727460Y1207972D03*
X723720Y1211712D03*
Y1207972D03*
X719980Y1211712D03*
Y1207972D03*
X727460Y1211712D03*
X731201Y1207972D03*
X733071Y1221062D03*
X721850D03*
X725590D03*
X729331D03*
Y1224803D03*
Y1228543D03*
X733071Y1236023D03*
Y1232283D03*
X725590Y1236023D03*
Y1232283D03*
X721850Y1224803D03*
Y1228543D03*
X725590Y1239763D03*
X733071Y1247243D03*
X725590Y1243503D03*
X733071D03*
X725590Y1247243D03*
X729331Y1258465D03*
X721850D03*
X729848Y1348187D03*
Y1360099D03*
Y1372385D03*
Y1384297D03*
Y1396489D03*
Y1408401D03*
X740551Y1075196D03*
X748031D03*
X744290Y1071455D03*
X736810D03*
X748030Y1090157D03*
X744291D03*
X740551Y1078936D03*
Y1090157D03*
X736811D03*
X744291Y1101377D03*
X748031Y1093897D03*
X744291Y1105117D03*
X736811D03*
X748031Y1123818D03*
Y1120078D03*
Y1116338D03*
Y1112598D03*
Y1108858D03*
X744291D03*
X740551D03*
X736811D03*
X738681Y1136909D03*
Y1140649D03*
X748031Y1138779D03*
Y1135039D03*
Y1131299D03*
Y1127558D03*
X738681Y1155610D03*
Y1148129D03*
X749901Y1144389D03*
Y1151869D03*
X746161Y1155610D03*
Y1151869D03*
X742421D03*
X738681D03*
Y1166830D03*
X746161Y1170570D03*
Y1166830D03*
X738681Y1159350D03*
X749901Y1166830D03*
Y1159350D03*
X738681Y1170570D03*
X746161Y1159350D03*
X749901Y1181791D03*
Y1174310D03*
X738681D03*
Y1178051D03*
X742421Y1181791D03*
X738681Y1185531D03*
Y1189271D03*
X746161Y1185531D03*
Y1178051D03*
Y1174310D03*
X742421Y1185531D03*
X748031Y1191141D03*
X738681Y1204232D03*
Y1193011D03*
Y1196751D03*
X742421Y1193011D03*
X748031Y1202362D03*
Y1198621D03*
X736811Y1221062D03*
X740551D03*
X748031D03*
X744291D03*
X748031Y1217322D03*
Y1213582D03*
Y1209842D03*
Y1206102D03*
X736811Y1224803D03*
Y1228543D03*
X748031Y1236023D03*
Y1232283D03*
X740551Y1236023D03*
X744291Y1228543D03*
X740551Y1232283D03*
X744291Y1224803D03*
X748031Y1239763D03*
X740551D03*
Y1243503D03*
Y1247243D03*
X744291Y1258465D03*
X736811D03*
X742088Y1348187D03*
Y1360099D03*
Y1384297D03*
Y1372385D03*
Y1396489D03*
Y1408401D03*
X755512Y1075196D03*
X762993D03*
X766732Y1071455D03*
X759252D03*
X751771D03*
X755511Y1090157D03*
X762993Y1078936D03*
X755513D03*
X751772Y1105117D03*
X762992Y1093897D03*
X759252Y1105117D03*
X766732D03*
X755512Y1093897D03*
X762991Y1108857D03*
X755512Y1108858D03*
X751772D03*
X759252Y1116338D03*
Y1123818D03*
X751771Y1112598D03*
Y1120078D03*
X757382Y1140649D03*
X759252Y1131299D03*
X757382Y1148129D03*
X764862Y1170570D03*
X757382Y1166830D03*
Y1159350D03*
Y1174310D03*
Y1181791D03*
X764862Y1185531D03*
Y1178051D03*
X755512Y1187401D03*
X764862Y1189271D03*
X766732Y1194881D03*
X751772D03*
X755512Y1202362D03*
X766732D03*
Y1198621D03*
X762992D03*
X766732Y1221062D03*
Y1217322D03*
X762992Y1221062D03*
X759252D03*
X762992Y1213582D03*
X766732D03*
Y1209842D03*
X755512D03*
X766732Y1206102D03*
X751772Y1221062D03*
Y1217322D03*
X759252Y1224803D03*
Y1228543D03*
X755512Y1232283D03*
Y1236023D03*
X766732Y1224803D03*
Y1228543D03*
X762992Y1232283D03*
Y1236023D03*
X751772Y1224803D03*
Y1228543D03*
X755512Y1239763D03*
X766732D03*
Y1258465D03*
X759252D03*
X751772D03*
X766568Y1348187D03*
X754328D03*
X766568Y1360099D03*
X754328D03*
Y1372385D03*
Y1384297D03*
X766568Y1372385D03*
Y1384297D03*
X777953Y1075196D03*
X770473D03*
X774212Y1071455D03*
X777953Y1078936D03*
X781693D03*
X770473D03*
X770471Y1090157D03*
X770472Y1093897D03*
Y1108858D03*
X776083Y1140649D03*
Y1148129D03*
Y1155610D03*
Y1170570D03*
X768602Y1166830D03*
X779823Y1170570D03*
X776083Y1178051D03*
Y1185531D03*
X779823D03*
Y1178051D03*
X768602Y1181791D03*
Y1174310D03*
X772342Y1189271D03*
X783503Y1193011D03*
X776083D03*
X779823D03*
X781693Y1202362D03*
X777953D03*
X770472Y1221062D03*
X777953Y1209842D03*
X774212Y1224803D03*
Y1228543D03*
X770472Y1236023D03*
Y1232283D03*
X777953D03*
X781693Y1250984D03*
X774212Y1258465D03*
X778808Y1348187D03*
Y1360099D03*
X785434Y1090158D03*
Y1082677D03*
Y1101378D03*
Y1123819D03*
Y1116339D03*
Y1108859D03*
Y1131300D03*
Y1198621D03*
Y1221062D03*
Y1213582D03*
Y1206102D03*
Y1228543D03*
Y1247243D03*
Y1239762D03*
X892183Y1728286D03*
Y1738286D03*
X891761Y1775438D03*
Y1785438D03*
X1057381Y1103247D03*
Y1140649D03*
Y1133169D03*
Y1125688D03*
Y1151870D03*
Y1144389D03*
X1054881Y1170570D03*
X1057381Y1159350D03*
X1054881Y1178050D03*
X1059251Y1187401D03*
Y1183661D03*
Y1194881D03*
Y1202362D03*
X1055510Y1198622D03*
Y1191142D03*
X1059251Y1209842D03*
Y1217322D03*
X1055510Y1221063D03*
Y1213583D03*
Y1206103D03*
X1059251Y1232283D03*
Y1236023D03*
Y1224803D03*
X1052473Y1348187D03*
Y1360099D03*
Y1384297D03*
Y1372385D03*
X1064861Y1077066D03*
X1061121Y1080806D03*
X1072342Y1106988D03*
X1061121Y1103247D03*
X1072342Y1121948D03*
Y1118208D03*
X1064862Y1121948D03*
X1068602D03*
X1072342Y1140649D03*
Y1125688D03*
X1061121D03*
Y1140649D03*
X1064862D03*
X1068602D03*
X1064862Y1136909D03*
X1061121Y1133169D03*
X1064862Y1129429D03*
X1068602D03*
X1072342Y1155610D03*
X1064862D03*
X1068602D03*
X1061121Y1151870D03*
X1064862D03*
Y1148129D03*
X1061121Y1144389D03*
X1064862D03*
X1072342Y1166830D03*
X1064861Y1170570D03*
X1068602D03*
X1064861Y1166830D03*
X1061121Y1159350D03*
X1064862D03*
X1072342Y1181791D03*
Y1174310D03*
X1061120Y1181791D03*
X1064861D03*
X1068602D03*
Y1174310D03*
X1064861Y1178051D03*
X1061120Y1174310D03*
X1064861D03*
X1074212Y1187401D03*
X1062991D03*
Y1183661D03*
X1066732D03*
X1070472D03*
X1074212D03*
Y1191141D03*
Y1198621D03*
X1070472Y1191141D03*
X1066732D03*
X1070472Y1198621D03*
X1066732D03*
X1062991Y1194881D03*
Y1202362D03*
X1074212Y1206102D03*
X1066732D03*
X1070472D03*
Y1213582D03*
X1066732D03*
X1062991Y1209842D03*
Y1217322D03*
X1074212Y1221062D03*
X1066732D03*
X1070472D03*
Y1236023D03*
Y1232283D03*
X1066732Y1228543D03*
Y1224803D03*
X1074212D03*
X1062991Y1236023D03*
Y1232283D03*
Y1224803D03*
X1066732Y1239763D03*
Y1243503D03*
X1074212Y1239763D03*
Y1243503D03*
Y1258465D03*
X1066732D03*
X1072593Y1348187D03*
X1064713D03*
X1060353D03*
X1072593Y1360099D03*
X1064713D03*
X1060353D03*
X1072593Y1384297D03*
Y1372385D03*
X1064713D03*
Y1384297D03*
X1060353D03*
Y1372385D03*
X1072593Y1396583D03*
X1064713D03*
X1072593Y1408495D03*
X1064713D03*
X1089171Y1071455D03*
X1083562Y1092027D03*
X1089172Y1090157D03*
X1083562Y1095767D03*
X1087302Y1106988D03*
X1079822D03*
X1083562D03*
X1076082D03*
X1089172Y1101377D03*
Y1105117D03*
X1083562Y1118208D03*
X1087302D03*
X1079822Y1114468D03*
X1083562Y1110728D03*
X1087302D03*
X1091043D03*
Y1121948D03*
Y1118208D03*
Y1114468D03*
X1076082D03*
X1089172Y1108858D03*
X1091043Y1125688D03*
Y1140649D03*
X1079822Y1129429D03*
Y1140649D03*
X1083562D03*
X1087302D03*
X1091043Y1136909D03*
Y1133169D03*
Y1129429D03*
X1076082Y1140649D03*
X1087302Y1151870D03*
Y1155610D03*
Y1148129D03*
X1083562Y1144389D03*
X1087302D03*
X1076082Y1155610D03*
Y1151870D03*
Y1148129D03*
Y1144389D03*
X1087302Y1170570D03*
Y1166830D03*
Y1159350D03*
X1091043Y1170570D03*
X1076082Y1159350D03*
X1081692Y1179921D03*
X1083562Y1181791D03*
X1087302D03*
Y1178051D03*
Y1174310D03*
X1076082Y1181791D03*
Y1178051D03*
Y1174310D03*
X1077952Y1183661D03*
X1081692D03*
X1085432D03*
X1089172Y1187401D03*
X1085432D03*
X1091043Y1185531D03*
X1077952Y1191141D03*
Y1198621D03*
X1081692Y1191141D03*
X1085432Y1194881D03*
X1089172D03*
X1085432Y1202362D03*
X1089172D03*
X1077952Y1206102D03*
X1081692D03*
X1085432Y1209842D03*
X1077952Y1221062D03*
X1089172Y1217322D03*
Y1221062D03*
X1085432D03*
Y1217322D03*
X1077952Y1232283D03*
Y1236023D03*
X1085432Y1232283D03*
Y1236023D03*
X1081692Y1224803D03*
X1089172D03*
X1085432D03*
Y1228543D03*
X1077952Y1239763D03*
X1081692D03*
Y1243503D03*
X1085432Y1250984D03*
Y1239763D03*
X1089172D03*
Y1247243D03*
X1089173Y1258465D03*
X1081692D03*
X1089193Y1348187D03*
X1084833D03*
X1076953D03*
X1089193Y1360099D03*
X1084833D03*
X1076953D03*
X1089193Y1384297D03*
Y1372385D03*
X1084833Y1384297D03*
Y1372385D03*
X1076953Y1384297D03*
Y1372385D03*
X1089193Y1396583D03*
X1084833D03*
X1076953D03*
X1089193Y1408495D03*
X1084833D03*
X1076953D03*
X1104132Y1071455D03*
X1096652D03*
X1092913Y1090157D03*
X1104133D03*
X1107873D03*
X1100393D03*
X1096653D03*
X1104133Y1093897D03*
X1092913D03*
Y1097637D03*
X1107873Y1093897D03*
Y1097637D03*
X1104133Y1101377D03*
X1100393Y1097637D03*
Y1093897D03*
X1096653Y1101377D03*
X1104133Y1105117D03*
X1096653D03*
X1094783Y1110728D03*
Y1121948D03*
X1098523D03*
X1102263D03*
X1106003D03*
X1094783Y1118208D03*
X1098523D03*
X1102263D03*
X1106003D03*
X1094783Y1114468D03*
X1107873Y1108858D03*
X1104133D03*
X1100393D03*
X1096653D03*
X1092913D03*
X1098523Y1140649D03*
X1102263D03*
X1094783Y1136909D03*
X1102263D03*
X1094783Y1133169D03*
X1098523D03*
X1102263D03*
X1094783Y1129429D03*
X1098523D03*
X1102263D03*
X1094783Y1125688D03*
X1098523D03*
X1102263D03*
X1106003D03*
X1094783Y1140649D03*
Y1151870D03*
Y1155610D03*
X1102263Y1151870D03*
X1094783Y1148129D03*
Y1144389D03*
X1102263D03*
X1106003Y1148129D03*
Y1155610D03*
X1102263Y1170570D03*
X1094783Y1159350D03*
X1102263D03*
X1094783Y1166830D03*
X1106003D03*
X1094783Y1181791D03*
X1102263Y1185531D03*
X1094783Y1174310D03*
Y1178051D03*
X1106003Y1181791D03*
Y1174310D03*
X1092913Y1187401D03*
X1098523Y1196751D03*
Y1193011D03*
X1106003Y1200491D03*
Y1196751D03*
Y1204232D03*
X1102263D03*
X1098523D03*
Y1200491D03*
X1102263D03*
Y1196751D03*
X1092913Y1191141D03*
Y1194881D03*
Y1198621D03*
Y1202362D03*
X1098523Y1207972D03*
X1102263D03*
X1106003D03*
Y1211712D03*
X1102263D03*
X1098523D03*
Y1219192D03*
X1106003D03*
X1092913Y1206102D03*
Y1209842D03*
Y1213582D03*
Y1217322D03*
X1107873Y1221062D03*
X1104133D03*
X1100393D03*
X1096653D03*
X1092913D03*
Y1232283D03*
Y1236023D03*
X1107873Y1232283D03*
X1104133Y1224803D03*
X1107873Y1236023D03*
X1100393Y1232283D03*
Y1236023D03*
X1096653Y1224803D03*
X1100393Y1228543D03*
X1092913Y1224803D03*
X1107873D03*
X1100393D03*
X1107873Y1228543D03*
X1092913D03*
X1100393Y1239763D03*
X1107873D03*
X1104133Y1243503D03*
X1096653D03*
X1104133Y1258465D03*
X1096653D03*
X1101433Y1348187D03*
X1097073D03*
X1101433Y1360099D03*
X1097073D03*
X1101433Y1384297D03*
Y1372385D03*
X1097073D03*
Y1384297D03*
X1101433Y1396583D03*
X1097073D03*
X1101433Y1408495D03*
X1097073D03*
X1119093Y1071455D03*
X1111612D03*
X1115354Y1090157D03*
X1119094D03*
X1122834D03*
X1111613D03*
X1122834Y1093897D03*
X1115354D03*
X1122834Y1097637D03*
X1115354D03*
X1119094Y1101377D03*
X1111613D03*
X1119094Y1105117D03*
X1111613D03*
X1117224Y1121948D03*
Y1118208D03*
X1120964D03*
X1109743Y1121948D03*
X1113484D03*
X1109743Y1118208D03*
X1113484D03*
X1124704Y1121948D03*
Y1118208D03*
X1120964Y1121948D03*
X1122834Y1108858D03*
X1119094D03*
X1115354D03*
X1111613D03*
X1109743Y1136909D03*
X1124704Y1125688D03*
Y1140649D03*
Y1133169D03*
X1113484D03*
X1117224D03*
X1120964D03*
X1109743Y1125688D03*
X1120964D03*
X1117224D03*
X1113484D03*
X1120964Y1140649D03*
X1117224D03*
X1113484D03*
X1109743Y1129429D03*
Y1133169D03*
X1113484Y1155610D03*
X1109743Y1144389D03*
X1120964Y1155610D03*
X1109743Y1151869D03*
X1120964Y1148129D03*
X1113484D03*
X1117224D03*
X1124704D03*
X1117224Y1170570D03*
X1109743D03*
X1113484Y1166830D03*
X1117224Y1159350D03*
X1120964Y1166830D03*
X1109743Y1159350D03*
X1124704Y1170570D03*
Y1159350D03*
X1109743Y1189271D03*
X1113484D03*
X1117224D03*
X1120964D03*
X1113484Y1181791D03*
X1117224D03*
X1120964D03*
X1124704Y1189271D03*
Y1181791D03*
X1109743Y1178051D03*
X1120964Y1174310D03*
X1109743Y1185531D03*
X1113484Y1174310D03*
X1124704Y1204232D03*
Y1196751D03*
X1120964Y1204232D03*
X1117224D03*
X1113484D03*
X1109743D03*
Y1193011D03*
Y1196751D03*
Y1200491D03*
X1113484Y1196751D03*
X1117224D03*
X1120964D03*
X1113484Y1207972D03*
X1117224D03*
X1120964D03*
X1109743Y1211712D03*
Y1207972D03*
X1124704D03*
X1122834Y1221062D03*
X1119094D03*
X1115354D03*
X1111613D03*
X1122834Y1224803D03*
Y1232283D03*
Y1236023D03*
X1119094Y1224803D03*
X1115354Y1232283D03*
Y1236023D03*
X1111613Y1224803D03*
X1115354Y1228543D03*
Y1224803D03*
X1122834Y1228543D03*
X1119094Y1243503D03*
X1122834Y1239763D03*
X1111613Y1243503D03*
Y1239763D03*
X1122834Y1243503D03*
X1119094Y1250984D03*
Y1254724D03*
X1122834Y1247243D03*
X1115354Y1243503D03*
Y1247243D03*
X1119094Y1258465D03*
X1111614D03*
X1113673Y1348187D03*
X1121553D03*
X1109313D03*
X1113673Y1360099D03*
X1121553D03*
X1109313D03*
X1113673Y1372385D03*
Y1384297D03*
X1121553Y1372385D03*
Y1384297D03*
X1109313D03*
Y1372385D03*
X1113673Y1396583D03*
X1121553D03*
X1109313D03*
X1113673Y1408495D03*
X1121553D03*
X1109313D03*
X1134053Y1071455D03*
X1126573D03*
X1126574Y1090157D03*
X1130314D03*
X1134054D03*
X1137795D03*
X1126574Y1101377D03*
X1130314Y1097637D03*
Y1093897D03*
X1137795D03*
Y1097637D03*
X1134054Y1101377D03*
X1126574Y1105117D03*
X1134054D03*
X1139665Y1121948D03*
X1130314Y1112598D03*
X1128444Y1118208D03*
X1132184D03*
X1135924D03*
X1132184Y1121948D03*
X1135924D03*
X1128444D03*
X1139665Y1118208D03*
X1137795Y1108858D03*
X1134054D03*
X1130314D03*
X1126574D03*
X1139665Y1125688D03*
X1128444Y1140649D03*
X1132184D03*
X1135924D03*
X1132184Y1125688D03*
X1128444D03*
X1135924D03*
Y1133169D03*
X1132184D03*
X1128444D03*
X1139665D03*
Y1140649D03*
X1135924Y1148129D03*
X1132184D03*
X1128444D03*
X1139665D03*
X1128444Y1155610D03*
X1135924D03*
X1139665Y1170570D03*
Y1159350D03*
X1132184Y1170570D03*
X1135925Y1166830D03*
X1128444D03*
X1132184Y1159350D03*
X1135924Y1181791D03*
X1132184D03*
X1128444D03*
X1135924Y1189271D03*
X1132184D03*
X1128444D03*
Y1174310D03*
X1135924D03*
X1139665Y1181791D03*
Y1189271D03*
Y1196751D03*
Y1204232D03*
X1135924D03*
Y1196751D03*
X1132184D03*
X1128444D03*
Y1204232D03*
X1132184D03*
X1139665Y1207972D03*
X1134054Y1217322D03*
X1135924Y1207972D03*
X1132184D03*
X1128444D03*
X1137795Y1221062D03*
X1134054D03*
X1130314D03*
X1126574D03*
Y1224803D03*
X1137795Y1232283D03*
Y1236023D03*
X1134054Y1224803D03*
X1130314Y1232283D03*
Y1236023D03*
X1137795Y1228543D03*
Y1224803D03*
X1130314Y1228543D03*
Y1224803D03*
X1126574Y1243503D03*
X1134054D03*
X1137795Y1239763D03*
X1130314D03*
X1126574Y1254724D03*
X1137795Y1243503D03*
X1130314Y1247243D03*
X1126574Y1250984D03*
X1137795Y1247243D03*
X1130314Y1243503D03*
X1134054Y1250984D03*
Y1254724D03*
X1134055Y1258465D03*
X1126574D03*
X1138153Y1348187D03*
X1133793D03*
X1125913D03*
X1138153Y1360099D03*
X1133793D03*
X1125913D03*
X1138153Y1384297D03*
Y1372385D03*
X1133793Y1384297D03*
Y1372385D03*
X1125913Y1384297D03*
Y1372385D03*
X1138153Y1396583D03*
X1133793D03*
X1125913D03*
X1138153Y1408495D03*
X1133793D03*
X1125913D03*
X1152755Y1075196D03*
X1156494Y1071455D03*
X1149014Y1071454D03*
X1141534Y1071455D03*
X1141535Y1090157D03*
X1149015Y1082677D03*
Y1086417D03*
X1152755Y1090157D03*
X1156495D03*
Y1086417D03*
X1149015Y1090157D03*
X1145275D03*
X1141535Y1101377D03*
X1149015D03*
X1152755Y1093897D03*
X1156495Y1101377D03*
X1145275Y1093897D03*
Y1097637D03*
X1141535Y1105117D03*
X1149015D03*
X1156495D03*
X1150885Y1121948D03*
X1143405D03*
Y1118208D03*
Y1114468D03*
X1154625Y1121948D03*
X1156495Y1108858D03*
X1152755D03*
X1149015D03*
X1145275D03*
X1141535D03*
X1154625Y1125688D03*
X1150885Y1133464D03*
X1154625Y1133169D03*
X1143503Y1132677D03*
X1143405Y1140649D03*
Y1125688D03*
X1150885Y1140649D03*
X1154625D03*
X1150885Y1125688D03*
X1143405Y1148129D03*
X1150885D03*
X1154625D03*
X1143405Y1155610D03*
X1154625D03*
Y1166830D03*
X1150885Y1170570D03*
X1143405Y1166830D03*
X1150885Y1159350D03*
X1143405Y1181791D03*
X1154625D03*
X1150885D03*
Y1189271D03*
X1154625D03*
X1143405D03*
Y1174310D03*
X1154625D03*
X1150885Y1196751D03*
X1154625Y1204232D03*
X1150885D03*
X1154625Y1196751D03*
X1143405D03*
Y1204232D03*
X1150885Y1207972D03*
X1154625D03*
Y1211712D03*
X1143405Y1207972D03*
X1149015Y1221062D03*
X1156495D03*
X1152755D03*
X1145275D03*
X1141535D03*
Y1224803D03*
X1152755Y1232283D03*
Y1236023D03*
X1156495Y1228543D03*
Y1224803D03*
X1149015Y1228543D03*
Y1224803D03*
X1145275Y1232283D03*
Y1236023D03*
X1141535Y1243503D03*
X1152755Y1239763D03*
X1145275D03*
X1141535Y1254724D03*
Y1250984D03*
X1145275Y1247243D03*
X1152755Y1243503D03*
X1145275D03*
X1152755Y1247243D03*
X1156495Y1258465D03*
X1149015D03*
X1141536D03*
X1150393Y1348187D03*
X1146033D03*
X1150393Y1360099D03*
X1146033D03*
X1150393Y1384297D03*
Y1372385D03*
X1146033D03*
Y1384297D03*
X1150393Y1396583D03*
X1146033D03*
X1150393Y1408495D03*
X1146033D03*
X1167716Y1075196D03*
X1160235D03*
X1171455Y1071455D03*
X1163975D03*
X1167716Y1078936D03*
X1163976Y1086417D03*
Y1090157D03*
X1171456Y1086417D03*
Y1090157D03*
X1167716D03*
X1160235Y1078936D03*
Y1090157D03*
X1167716Y1097637D03*
Y1093897D03*
X1160235D03*
Y1097637D03*
X1163976Y1105117D03*
X1171456D03*
X1171455Y1093897D03*
Y1097637D03*
X1163975Y1093897D03*
Y1097637D03*
X1169586Y1121948D03*
X1165846D03*
X1162106D03*
X1158365D03*
X1173326D03*
X1171456Y1108858D03*
X1167716D03*
X1163976D03*
X1160235D03*
X1162106Y1133169D03*
X1165846D03*
X1169586D03*
X1158365Y1140649D03*
X1162106D03*
X1165846D03*
X1169586D03*
X1158365Y1125688D03*
X1162106D03*
X1165846D03*
X1169586D03*
X1173326Y1133169D03*
Y1125688D03*
Y1140649D03*
X1158365Y1133169D03*
X1173326Y1148129D03*
X1158365D03*
X1162106D03*
X1165846D03*
X1169586D03*
X1162106Y1155610D03*
X1169586D03*
X1158365Y1170570D03*
X1165846D03*
X1169586Y1166830D03*
X1158365Y1159350D03*
X1162106Y1166830D03*
X1165846Y1159350D03*
X1173326D03*
Y1170570D03*
Y1189271D03*
X1158365Y1181791D03*
X1162106D03*
X1165846D03*
X1169586D03*
X1158365Y1189271D03*
X1162106D03*
X1165846D03*
X1169586D03*
X1173326Y1181791D03*
X1169586Y1174310D03*
X1162106D03*
Y1204232D03*
X1158365D03*
X1169586D03*
X1165846D03*
X1158365Y1196751D03*
X1162106D03*
X1165846D03*
X1169586D03*
X1173326Y1204232D03*
Y1196751D03*
X1158365Y1211712D03*
Y1207972D03*
X1173326D03*
Y1211712D03*
X1162106Y1207972D03*
X1165846D03*
X1169586Y1211712D03*
Y1207972D03*
X1171456Y1221062D03*
X1167716D03*
X1163976D03*
X1160235D03*
X1163976Y1228543D03*
Y1224803D03*
X1171456Y1228543D03*
Y1224803D03*
X1167716Y1232283D03*
Y1236023D03*
X1160235Y1232283D03*
Y1236023D03*
X1171456Y1239763D03*
X1160235D03*
X1167716Y1247243D03*
X1160235D03*
Y1243503D03*
X1167716D03*
X1171456Y1258465D03*
X1163976D03*
X1162633Y1348187D03*
X1170513D03*
X1158273D03*
X1162633Y1360099D03*
X1170513D03*
X1158273D03*
X1162633Y1372385D03*
Y1384297D03*
X1170513Y1372385D03*
Y1384297D03*
X1158273D03*
Y1372385D03*
X1162633Y1396583D03*
X1170513D03*
X1158273D03*
X1162633Y1408495D03*
X1170513D03*
X1158273D03*
X1175196Y1075196D03*
X1182676D03*
X1186416Y1071455D03*
X1178935D03*
X1175196Y1078936D03*
Y1090157D03*
X1178936D03*
X1182676Y1078936D03*
X1178936Y1086417D03*
X1182676Y1090157D03*
X1186417D03*
Y1086417D03*
Y1082677D03*
X1175196Y1097637D03*
Y1093897D03*
X1182676Y1097637D03*
Y1093897D03*
X1178936Y1105117D03*
X1186417D03*
X1188287Y1118208D03*
X1184546D03*
X1180806Y1121948D03*
X1177066D03*
X1184546D03*
X1186417Y1108858D03*
X1182676D03*
X1178936D03*
X1175196D03*
X1188287Y1125688D03*
X1184546Y1136909D03*
X1177066Y1133169D03*
X1180806D03*
X1184546D03*
X1177066Y1140649D03*
X1180806D03*
X1184546Y1125688D03*
Y1129429D03*
X1177066Y1125688D03*
X1180806D03*
X1184546Y1140649D03*
X1188287Y1155610D03*
Y1151869D03*
Y1148129D03*
X1177066D03*
X1180806D03*
X1184546Y1144389D03*
Y1148129D03*
Y1151869D03*
X1177066Y1155610D03*
X1184546D03*
X1177066Y1166830D03*
X1188287D03*
Y1159350D03*
Y1170570D03*
Y1181791D03*
Y1174310D03*
X1177066Y1189271D03*
X1180806D03*
X1184546Y1178051D03*
X1177066Y1174310D03*
X1184546Y1185531D03*
X1177066Y1181791D03*
X1180806D03*
X1184546Y1189271D03*
Y1174310D03*
Y1204232D03*
X1177066D03*
X1180806D03*
X1184546Y1200491D03*
X1177066Y1196751D03*
X1180806D03*
X1184546Y1193011D03*
X1188287Y1196751D03*
X1184566Y1196732D03*
X1188287Y1207972D03*
X1184546Y1211712D03*
X1177066Y1207972D03*
Y1211712D03*
X1180806Y1207972D03*
Y1211712D03*
X1184546Y1207972D03*
X1186417Y1221062D03*
X1182676D03*
X1178936D03*
X1175196D03*
Y1232283D03*
Y1236023D03*
X1178936Y1228543D03*
Y1224803D03*
X1182676Y1232283D03*
Y1236023D03*
X1186417Y1228543D03*
Y1224803D03*
X1182676Y1239763D03*
X1186417Y1258465D03*
X1178936D03*
X1182753Y1348187D03*
X1174873D03*
X1182753Y1360099D03*
X1174873D03*
X1182753Y1384297D03*
Y1372385D03*
X1174873Y1384297D03*
Y1372385D03*
X1182753Y1396583D03*
X1174873D03*
X1182753Y1408495D03*
X1174873D03*
X1179329Y1728990D03*
Y1738990D03*
X1179123Y1776014D03*
Y1786014D03*
X1190157Y1075196D03*
X1197637D03*
X1205117D03*
X1201376Y1071455D03*
X1193896D03*
X1190157Y1090157D03*
X1197637Y1078936D03*
Y1090157D03*
X1201377D03*
X1205116D03*
X1193897D03*
X1190157Y1093897D03*
X1201377Y1101377D03*
X1205117Y1093897D03*
X1201377Y1105117D03*
X1193897D03*
X1192027Y1118208D03*
X1205117Y1123818D03*
Y1120078D03*
Y1116338D03*
Y1108858D03*
X1201377D03*
X1197637D03*
X1193897D03*
X1190157D03*
X1192027Y1136909D03*
X1195767Y1140649D03*
X1192027D03*
X1195767Y1136909D03*
X1205117Y1135039D03*
Y1131299D03*
Y1127558D03*
X1195767Y1148129D03*
X1192027Y1144389D03*
X1195767Y1155610D03*
X1192027Y1148129D03*
X1195767Y1151869D03*
X1199507D03*
X1203247D03*
Y1155610D03*
X1192027Y1151870D03*
X1195767Y1170570D03*
Y1159350D03*
X1203247Y1166830D03*
Y1170570D03*
Y1159350D03*
X1195767Y1166830D03*
X1192027Y1181791D03*
X1199507Y1185531D03*
X1203247Y1174310D03*
Y1178051D03*
Y1185531D03*
X1192027Y1178051D03*
Y1189271D03*
X1195767D03*
X1192027Y1185531D03*
X1195767D03*
X1199507Y1181791D03*
X1195767Y1178051D03*
Y1174310D03*
Y1204232D03*
X1199507Y1193011D03*
X1195767Y1196751D03*
Y1193011D03*
X1192027D03*
X1205117Y1198621D03*
Y1202362D03*
X1192027Y1211712D03*
X1205117Y1206102D03*
Y1209842D03*
Y1213582D03*
Y1217322D03*
Y1221062D03*
X1201377D03*
X1197637D03*
X1193897D03*
X1190157D03*
Y1232283D03*
Y1236023D03*
X1197637Y1232283D03*
X1201377Y1228543D03*
X1197637Y1236023D03*
X1201377Y1224803D03*
X1205117Y1232283D03*
Y1236023D03*
X1193897Y1228543D03*
Y1224803D03*
X1197637Y1239763D03*
X1205117D03*
Y1243503D03*
Y1247243D03*
X1201377Y1258465D03*
X1193897D03*
X1212598Y1075196D03*
X1220079D03*
X1216338Y1071455D03*
X1208857D03*
X1220079Y1078936D03*
X1212599D03*
X1212597Y1090157D03*
X1212598Y1093897D03*
X1220078D03*
X1216338Y1105117D03*
X1208858D03*
X1212598Y1108858D03*
X1216338Y1116338D03*
Y1123818D03*
X1208857Y1112598D03*
Y1120078D03*
X1220077Y1108857D03*
X1208858Y1108858D03*
X1214468Y1140649D03*
X1206987Y1136909D03*
X1216338Y1131299D03*
X1206987Y1151869D03*
X1214468Y1148129D03*
X1206987Y1144389D03*
Y1159350D03*
X1214468D03*
X1206987Y1166830D03*
X1214468D03*
X1221948Y1170570D03*
X1206987Y1181791D03*
X1214468Y1189271D03*
X1221948Y1178051D03*
Y1185531D03*
X1206987Y1174310D03*
Y1189271D03*
X1214468Y1181791D03*
Y1174310D03*
X1208858Y1194881D03*
X1221948Y1193011D03*
X1212598Y1202362D03*
X1220078Y1198621D03*
Y1221062D03*
X1216338D03*
X1220078Y1213582D03*
X1212598Y1209842D03*
X1208858Y1221062D03*
Y1217322D03*
X1216338Y1224803D03*
Y1228543D03*
X1212598Y1232283D03*
Y1236023D03*
X1220078Y1232283D03*
Y1236023D03*
X1208858Y1224803D03*
Y1228543D03*
X1212598Y1239763D03*
Y1243503D03*
X1220078Y1247243D03*
Y1243503D03*
X1212598Y1247243D03*
X1208858Y1254724D03*
Y1250984D03*
X1216338Y1254724D03*
Y1250984D03*
Y1258465D03*
X1208858D03*
X1227559Y1075196D03*
X1235039D03*
X1231298Y1071455D03*
X1223818D03*
X1235039Y1078936D03*
X1227559D03*
X1227557Y1090157D03*
X1227558Y1093897D03*
X1223818Y1105117D03*
X1227558Y1108858D03*
X1233169Y1140649D03*
Y1155610D03*
Y1148129D03*
X1236909Y1170570D03*
X1225688Y1166830D03*
X1233169Y1170570D03*
X1236909Y1178051D03*
Y1185531D03*
X1233169D03*
Y1178051D03*
X1225688Y1174310D03*
Y1181791D03*
Y1189271D03*
X1233169Y1193011D03*
X1223818Y1194881D03*
X1236909Y1193011D03*
X1223818Y1202362D03*
Y1198621D03*
X1235039Y1202362D03*
X1223818Y1206102D03*
Y1221062D03*
Y1217322D03*
Y1213582D03*
Y1209842D03*
X1227558Y1221062D03*
X1235039Y1209842D03*
Y1206102D03*
X1223818Y1224803D03*
Y1228543D03*
X1231298Y1224803D03*
Y1228543D03*
X1227558Y1236023D03*
Y1232283D03*
X1235039D03*
X1225688Y1222932D03*
X1223818Y1239763D03*
X1227558Y1247243D03*
X1231298Y1254724D03*
X1223818D03*
Y1250984D03*
X1235039Y1239763D03*
X1227558Y1243503D03*
X1231298Y1250984D03*
Y1258465D03*
X1223818D03*
X1235966Y1348187D03*
X1228086D03*
X1235966Y1360099D03*
X1228086D03*
X1235966Y1372385D03*
Y1384297D03*
X1228086Y1372385D03*
Y1384297D03*
X1238779Y1078936D03*
X1242520Y1090158D03*
Y1082677D03*
Y1101378D03*
Y1123819D03*
Y1116339D03*
Y1108859D03*
Y1131300D03*
X1240589Y1193011D03*
X1238779Y1202362D03*
X1242520Y1198621D03*
Y1221062D03*
Y1213582D03*
Y1206102D03*
Y1228543D03*
X1238779Y1250984D03*
X1242520Y1247243D03*
Y1239762D03*
X1238779Y1239763D03*
X1252566Y1348187D03*
X1240326D03*
X1248206D03*
X1252566Y1360099D03*
X1240326D03*
X1248206D03*
X1252566Y1372385D03*
Y1384297D03*
X1240326D03*
Y1372385D03*
X1248206D03*
Y1384297D03*
X1252566Y1396583D03*
X1240326D03*
X1248206D03*
X1252566Y1408495D03*
X1240326D03*
X1248206D03*
X1264806Y1348187D03*
X1260446D03*
X1264806Y1360099D03*
X1260446D03*
X1264806Y1372385D03*
Y1384297D03*
X1260446Y1372385D03*
Y1384297D03*
X1264806Y1396583D03*
X1260446D03*
X1264806Y1408495D03*
X1260446D03*
X1284926Y1348187D03*
X1277046D03*
X1272686D03*
X1284926Y1360099D03*
X1277046D03*
X1272686D03*
X1284926Y1372385D03*
Y1384297D03*
X1277046Y1372385D03*
Y1384297D03*
X1272686D03*
Y1372385D03*
X1284926Y1396583D03*
X1277046D03*
X1272686D03*
X1284926Y1408495D03*
X1277046D03*
X1272686D03*
X1301526Y1348187D03*
X1289286D03*
X1297166D03*
X1301526Y1360099D03*
X1289286D03*
X1297166D03*
X1301526Y1372385D03*
Y1384297D03*
X1289286D03*
Y1372385D03*
X1297166Y1384297D03*
Y1372385D03*
X1301526Y1396583D03*
X1289286D03*
X1297166D03*
X1301526Y1408495D03*
X1289286D03*
X1297166D03*
X1313766Y1348187D03*
X1309406D03*
X1313766Y1360099D03*
X1309406D03*
X1313766Y1372385D03*
Y1384297D03*
X1309406Y1372385D03*
Y1384297D03*
X1313766Y1396583D03*
X1309406D03*
X1313766Y1408495D03*
X1309406D03*
X1333886Y1348187D03*
X1326006D03*
X1321646D03*
X1333886Y1360099D03*
X1326006D03*
X1321646D03*
X1333886Y1372385D03*
Y1384297D03*
X1326006Y1372385D03*
Y1384297D03*
X1321646D03*
Y1372385D03*
X1333886Y1396583D03*
X1326006D03*
X1321646D03*
X1333886Y1408495D03*
X1326006D03*
X1321646D03*
X1350486Y1348187D03*
X1338246D03*
X1346126D03*
X1350486Y1360099D03*
X1338246D03*
X1346126D03*
X1350486Y1372385D03*
Y1384297D03*
X1338246D03*
Y1372385D03*
X1346126Y1384297D03*
Y1372385D03*
X1350486Y1396583D03*
X1338246D03*
X1346126D03*
X1350486Y1408495D03*
X1338246D03*
X1346126D03*
X1358366Y1348187D03*
Y1360099D03*
Y1372385D03*
Y1384297D03*
Y1396583D03*
Y1408495D03*
X1459130Y1348187D03*
Y1360099D03*
Y1384297D03*
Y1372385D03*
X1479250Y1348187D03*
X1471370D03*
X1467010D03*
X1479250Y1360099D03*
X1471370D03*
X1467010D03*
X1479250Y1384297D03*
Y1372385D03*
X1471370D03*
Y1384297D03*
X1467010D03*
Y1372385D03*
X1479250Y1396583D03*
X1471370D03*
X1479250Y1408495D03*
X1471370D03*
X1495850Y1348187D03*
X1483610D03*
X1491490D03*
X1495850Y1360099D03*
X1483610D03*
X1491490D03*
X1483610Y1384297D03*
Y1372385D03*
X1491490Y1384297D03*
Y1372385D03*
X1495850Y1384297D03*
Y1372385D03*
Y1396583D03*
X1483610D03*
X1491490D03*
X1495850Y1408495D03*
X1483610D03*
X1491490D03*
X1514468Y1103247D03*
Y1125688D03*
Y1133169D03*
Y1140649D03*
Y1144389D03*
Y1151870D03*
Y1159350D03*
X1512597Y1198622D03*
Y1191142D03*
Y1221063D03*
Y1213583D03*
Y1206103D03*
X1508090Y1348187D03*
X1503730D03*
X1508090Y1360099D03*
X1503730D03*
X1508090Y1384297D03*
Y1372385D03*
X1503730D03*
Y1384297D03*
X1508090Y1396583D03*
X1503730D03*
X1508090Y1408495D03*
X1503730D03*
X1521948Y1077066D03*
X1518208Y1080806D03*
Y1103247D03*
X1529429Y1106988D03*
Y1118208D03*
Y1121948D03*
X1525689D03*
X1521949D03*
X1529429Y1125688D03*
X1518208D03*
X1525689Y1129429D03*
X1521949D03*
X1518208Y1133169D03*
X1521949Y1136909D03*
X1529429Y1140649D03*
X1525689D03*
X1521949D03*
X1518208D03*
X1521949Y1144389D03*
X1518208D03*
X1521949Y1148129D03*
Y1151870D03*
X1518208D03*
X1529429Y1155610D03*
X1525689D03*
X1521949D03*
Y1159350D03*
X1518208D03*
X1529429Y1166830D03*
X1521948D03*
X1525689Y1170570D03*
X1521948D03*
Y1174310D03*
X1518207D03*
X1521948Y1178051D03*
X1525689Y1174310D03*
X1529429D03*
X1527559Y1179921D03*
X1523819D03*
X1518207Y1181791D03*
X1516338Y1187401D03*
X1520078D03*
X1527559Y1183661D03*
X1523819D03*
X1520078D03*
X1516338D03*
X1523819Y1187401D03*
X1527559D03*
X1516338Y1194881D03*
Y1202362D03*
X1527559Y1191141D03*
X1523819D03*
X1527559Y1198621D03*
X1523819D03*
X1520078Y1194881D03*
Y1202362D03*
X1516338Y1198621D03*
X1523819Y1194881D03*
X1520078Y1198621D03*
X1523819Y1202362D03*
X1516338Y1191141D03*
X1527559Y1202362D03*
Y1194881D03*
X1520078Y1191141D03*
X1516338Y1209842D03*
Y1217322D03*
X1523819Y1206102D03*
X1527559D03*
Y1213582D03*
X1523819D03*
X1520078Y1209842D03*
Y1217322D03*
X1523819Y1221062D03*
X1527559D03*
X1520078D03*
X1516338Y1213582D03*
Y1206102D03*
X1520078D03*
X1527559Y1217322D03*
X1523819Y1209842D03*
X1516338Y1221062D03*
X1527559Y1209842D03*
X1523819Y1217322D03*
X1520078Y1213582D03*
X1527559Y1228543D03*
X1516338Y1232283D03*
Y1236023D03*
Y1224803D03*
X1527559Y1236023D03*
Y1232283D03*
X1523819Y1228543D03*
Y1224803D03*
X1520078Y1236023D03*
Y1232283D03*
Y1224803D03*
X1527559D03*
X1516338Y1239763D03*
X1523819D03*
Y1243503D03*
X1520078Y1239763D03*
Y1247243D03*
X1516338D03*
X1527559Y1243503D03*
Y1247243D03*
X1523819Y1250984D03*
Y1254724D03*
Y1258465D03*
X1528210Y1348187D03*
X1520330D03*
X1515970D03*
X1528210Y1360099D03*
X1520330D03*
X1515970D03*
X1528210Y1372385D03*
Y1384297D03*
X1520330Y1372385D03*
Y1384297D03*
X1515970D03*
Y1372385D03*
X1528210Y1396583D03*
X1520330D03*
X1515970D03*
X1528210Y1408495D03*
X1520330D03*
X1515970D03*
X1546258Y1071455D03*
X1540649Y1092027D03*
X1546259Y1090157D03*
X1544389Y1099507D03*
X1540649Y1106988D03*
X1536909D03*
X1533169D03*
X1544389D03*
X1540649Y1095767D03*
X1546259Y1101377D03*
Y1105117D03*
X1544389Y1118208D03*
X1540649D03*
X1544389Y1110728D03*
X1540649D03*
X1536909Y1114468D03*
X1533169D03*
X1544389Y1140649D03*
X1540649D03*
X1536909D03*
X1533169D03*
X1536909Y1129429D03*
X1544389Y1144389D03*
X1540649D03*
X1533169D03*
Y1148129D03*
Y1151870D03*
Y1155610D03*
X1544389Y1148129D03*
Y1155610D03*
Y1151870D03*
X1533169Y1159350D03*
X1544389D03*
Y1166830D03*
Y1170570D03*
X1535039Y1187401D03*
X1533169Y1174310D03*
Y1178051D03*
X1544389Y1174310D03*
Y1178051D03*
Y1181791D03*
X1540649D03*
X1538779Y1179921D03*
X1531299D03*
Y1187401D03*
X1546259D03*
X1542519D03*
Y1183661D03*
X1538779D03*
X1535039D03*
X1531299D03*
X1538779Y1187401D03*
X1542519Y1191141D03*
X1538779Y1202362D03*
X1535039Y1194881D03*
X1542519Y1198621D03*
X1535039Y1191141D03*
X1531299D03*
X1535039Y1198621D03*
X1531299D03*
X1538779Y1191141D03*
X1542519Y1194881D03*
X1546259D03*
X1542519Y1202362D03*
X1546259D03*
Y1198621D03*
Y1191141D03*
X1535039Y1202362D03*
X1538779Y1194881D03*
X1542519Y1213582D03*
Y1206102D03*
X1546259Y1213582D03*
X1535039Y1209842D03*
X1531299Y1206102D03*
X1535039D03*
X1538779D03*
X1542519Y1209842D03*
X1531299Y1221062D03*
X1535039D03*
X1546259Y1217322D03*
Y1221062D03*
X1542519D03*
Y1217322D03*
X1535039D03*
X1546259Y1206102D03*
X1538779Y1209842D03*
Y1217322D03*
X1535039Y1224803D03*
X1542519Y1228543D03*
X1535039D03*
X1531299Y1224803D03*
X1535039Y1232283D03*
Y1236023D03*
X1542519Y1232283D03*
Y1236023D03*
X1538779Y1224803D03*
X1546259D03*
X1542519D03*
X1535039Y1239763D03*
X1531299D03*
Y1243503D03*
X1538779Y1239763D03*
Y1243503D03*
X1542519Y1250984D03*
Y1239763D03*
X1546259D03*
Y1247243D03*
Y1250984D03*
X1542519Y1243503D03*
X1546259Y1254724D03*
X1542519Y1247243D03*
X1538779Y1250984D03*
Y1254724D03*
X1535039Y1243503D03*
X1531299Y1250984D03*
X1535039Y1247243D03*
X1531299Y1254724D03*
X1546260Y1258465D03*
X1538779D03*
X1531299D03*
X1544810Y1348187D03*
X1532570D03*
X1540450D03*
X1544810Y1360099D03*
X1532570D03*
X1540450D03*
X1544810Y1384297D03*
Y1372385D03*
X1532570Y1384297D03*
Y1372385D03*
X1540450Y1384297D03*
Y1372385D03*
X1544810Y1396583D03*
X1532570D03*
X1540450D03*
X1544810Y1408495D03*
X1532570D03*
X1540450D03*
X1561219Y1071455D03*
X1553739D03*
X1561220Y1090157D03*
X1557480D03*
X1553740D03*
X1550000D03*
X1561220Y1093897D03*
Y1105117D03*
X1553740D03*
X1561220Y1101377D03*
X1557480Y1097637D03*
Y1093897D03*
X1553740Y1101377D03*
X1550000Y1093897D03*
Y1097637D03*
X1551870Y1114468D03*
X1548130D03*
X1563090Y1118208D03*
X1559350D03*
X1555610D03*
X1551870D03*
X1548130D03*
X1563090Y1121948D03*
X1559350D03*
X1555610D03*
X1551870D03*
X1548130D03*
Y1110728D03*
X1561220Y1108858D03*
X1557480D03*
X1553740D03*
X1550000D03*
X1551870Y1110728D03*
X1548130Y1140649D03*
X1563090Y1125688D03*
X1559350D03*
X1555610D03*
X1551870D03*
X1548130D03*
X1559350Y1129429D03*
X1555610D03*
X1551870D03*
X1548130D03*
X1559350Y1133169D03*
X1555610D03*
X1551870D03*
X1548130D03*
X1559350Y1136909D03*
X1551870D03*
X1548130D03*
X1559350Y1140649D03*
X1555610D03*
X1551870D03*
Y1155610D03*
Y1151870D03*
X1559350Y1144389D03*
X1551870D03*
Y1148129D03*
X1559350Y1151870D03*
X1563090Y1155610D03*
Y1148129D03*
X1559350Y1170570D03*
X1551870Y1166830D03*
X1559350Y1159350D03*
X1551870D03*
X1548130Y1170570D03*
X1563090Y1166830D03*
X1551870Y1189271D03*
X1559350Y1185531D03*
X1551870D03*
Y1178051D03*
Y1174310D03*
Y1181791D03*
X1563090D03*
Y1174310D03*
X1550000Y1187401D03*
X1548130Y1185531D03*
X1551870Y1193011D03*
X1559350Y1196751D03*
Y1200491D03*
X1555610D03*
Y1204232D03*
X1559350D03*
X1563090D03*
Y1196751D03*
Y1200491D03*
X1555610Y1193011D03*
Y1196751D03*
X1550000Y1191141D03*
Y1194881D03*
Y1198621D03*
Y1202362D03*
X1555610Y1211712D03*
X1559350D03*
X1563090D03*
Y1207972D03*
X1559350D03*
X1555610D03*
X1563090Y1219192D03*
X1550000Y1221062D03*
X1553740D03*
X1557480D03*
X1561220D03*
X1550000Y1206102D03*
Y1209842D03*
Y1213582D03*
Y1217322D03*
X1553740D03*
X1550000Y1228543D03*
Y1224803D03*
X1557480Y1228543D03*
X1550000Y1232283D03*
Y1236023D03*
X1561220Y1224803D03*
X1557480Y1232283D03*
Y1236023D03*
X1553740Y1224803D03*
X1557480D03*
Y1239763D03*
X1561220Y1243503D03*
X1553740D03*
X1561220Y1250984D03*
Y1254724D03*
X1550000Y1243503D03*
X1557480Y1247243D03*
X1550000D03*
X1557480Y1243503D03*
X1553740Y1250984D03*
Y1254724D03*
X1561220Y1258465D03*
X1553740D03*
X1557050Y1348187D03*
X1552690D03*
Y1360099D03*
X1557050D03*
Y1384297D03*
Y1372385D03*
X1552690D03*
Y1384297D03*
X1557050Y1396583D03*
X1552690D03*
X1557050Y1408495D03*
X1552690D03*
X1576180Y1071455D03*
X1568699D03*
X1564960Y1090157D03*
X1572441D03*
X1576181D03*
X1568700D03*
X1576181Y1105117D03*
X1568700D03*
X1564960Y1093897D03*
Y1097637D03*
X1572441Y1093897D03*
Y1097637D03*
X1576181Y1101377D03*
X1568700D03*
X1566830Y1121948D03*
X1578051Y1118208D03*
X1574311D03*
Y1121948D03*
X1578051D03*
X1570571Y1118208D03*
X1566830D03*
X1570571Y1121948D03*
X1576181Y1108858D03*
X1572441D03*
X1568700D03*
X1564960D03*
X1566830Y1133169D03*
Y1129429D03*
X1570571Y1140649D03*
X1574311D03*
X1578051D03*
X1570571Y1125688D03*
X1574311D03*
X1578051D03*
X1566830D03*
X1578051Y1133169D03*
X1574311D03*
X1570571D03*
X1566830Y1136909D03*
X1574311Y1148129D03*
X1570571D03*
X1578051D03*
X1570571Y1155610D03*
X1566830Y1151869D03*
X1578051Y1155610D03*
X1566830Y1144389D03*
Y1159350D03*
X1578051Y1166830D03*
X1574311Y1159350D03*
X1570571Y1166830D03*
X1566830Y1170570D03*
X1574311D03*
X1578051Y1181791D03*
X1574311D03*
X1570571D03*
X1578051Y1189271D03*
X1574311D03*
X1570571D03*
X1566830D03*
Y1178051D03*
X1570571Y1174310D03*
X1566830Y1185531D03*
X1578051Y1174310D03*
X1574311Y1204232D03*
X1578051D03*
Y1196751D03*
X1574311D03*
X1570571D03*
X1566830Y1200491D03*
Y1196751D03*
Y1193011D03*
Y1204232D03*
X1570571D03*
X1566830Y1207972D03*
Y1211712D03*
X1578051Y1207972D03*
X1574311D03*
X1570571D03*
X1564960Y1221062D03*
X1568700D03*
X1572441D03*
X1576181D03*
X1564960Y1224803D03*
Y1232283D03*
Y1236023D03*
X1576181Y1224803D03*
X1572441Y1232283D03*
Y1236023D03*
X1568700Y1224803D03*
X1564960Y1228543D03*
Y1239763D03*
X1576181Y1243503D03*
X1568700D03*
Y1239763D03*
Y1254724D03*
X1564960Y1243503D03*
Y1247243D03*
X1568700Y1250984D03*
X1576181Y1258465D03*
X1568701D03*
X1564930Y1348187D03*
X1569290D03*
X1577170D03*
X1569290Y1360099D03*
X1577170D03*
X1564930D03*
X1577170Y1372385D03*
Y1384297D03*
X1569290Y1372385D03*
Y1384297D03*
X1564930D03*
Y1372385D03*
X1577170Y1396583D03*
X1569290D03*
X1564930D03*
X1577170Y1408495D03*
X1569290D03*
X1564930D03*
X1591140Y1071455D03*
X1583660D03*
X1579921Y1090157D03*
X1583661D03*
X1587401D03*
X1591141D03*
X1594882D03*
X1583661Y1105117D03*
X1591141D03*
X1579921Y1093897D03*
Y1097637D03*
X1583661Y1101377D03*
X1587401Y1097637D03*
Y1093897D03*
X1594882D03*
Y1097637D03*
X1591141Y1101377D03*
X1581791Y1121948D03*
X1585531Y1118208D03*
X1589271D03*
X1593011D03*
X1589271Y1121948D03*
X1593011D03*
X1585531D03*
X1581791Y1118208D03*
X1594882Y1108858D03*
X1591141D03*
X1587401D03*
X1583661D03*
X1579921D03*
X1587401Y1112598D03*
X1581791Y1133169D03*
Y1140649D03*
X1585531D03*
X1589271D03*
X1593011D03*
X1589271Y1125688D03*
X1585531D03*
X1581791D03*
X1593011D03*
Y1133169D03*
X1589271D03*
X1585531D03*
X1593011Y1148129D03*
X1589271D03*
X1585531D03*
X1581791D03*
X1593011Y1155610D03*
X1585531D03*
X1589271Y1170570D03*
X1593012Y1166830D03*
X1585531D03*
X1581791Y1159350D03*
X1589271D03*
X1581791Y1170570D03*
X1593011Y1181791D03*
X1589271D03*
X1585531D03*
X1581791D03*
X1593011Y1189271D03*
X1589271D03*
X1585531D03*
X1581791D03*
X1585531Y1174310D03*
X1593011D03*
Y1204232D03*
Y1196751D03*
X1589271D03*
X1585531D03*
X1581791D03*
Y1204232D03*
X1585531D03*
X1589271D03*
X1593011Y1219192D03*
X1591141Y1217322D03*
X1593011Y1207972D03*
X1589271D03*
X1585531D03*
X1581791D03*
X1591141Y1221062D03*
X1587401D03*
X1579921D03*
X1583661D03*
X1594882D03*
X1583661Y1224803D03*
X1579921Y1232283D03*
Y1236023D03*
X1594882Y1232283D03*
Y1236023D03*
X1591141Y1224803D03*
X1587401Y1232283D03*
Y1236023D03*
X1583661Y1243503D03*
X1579921Y1239763D03*
X1591141Y1243503D03*
X1594882Y1239763D03*
X1587401D03*
X1591142Y1258465D03*
X1583661D03*
X1589410Y1348187D03*
X1581530D03*
X1589410Y1360099D03*
X1581530D03*
Y1384297D03*
Y1372385D03*
X1589410Y1384297D03*
Y1372385D03*
X1581530Y1396583D03*
X1589410D03*
X1581530Y1408495D03*
X1589410D03*
X1609842Y1075196D03*
X1606101Y1071454D03*
X1598621Y1071455D03*
X1598622Y1090157D03*
X1606102Y1082677D03*
Y1086417D03*
X1609842Y1090157D03*
X1606102D03*
X1602362D03*
X1598622Y1105117D03*
X1606102D03*
X1598622Y1101377D03*
X1606102D03*
X1609842Y1093897D03*
X1602362D03*
Y1097637D03*
X1596752Y1121948D03*
X1600492Y1118208D03*
Y1114468D03*
X1611712Y1121948D03*
X1607972D03*
X1596752Y1118208D03*
X1600492Y1121948D03*
X1609842Y1108858D03*
X1606102D03*
X1602362D03*
X1598622D03*
X1607972Y1125688D03*
X1611712D03*
X1607972Y1133464D03*
X1611712Y1133169D03*
X1600590Y1132677D03*
X1596752Y1133169D03*
Y1140649D03*
X1600492D03*
Y1125688D03*
X1596752D03*
X1607972Y1140649D03*
X1611712D03*
X1600492Y1148129D03*
X1596752D03*
X1607972D03*
X1611712D03*
X1600492Y1155610D03*
X1611712D03*
X1596752Y1170570D03*
Y1159350D03*
X1611712Y1166830D03*
X1607972Y1170570D03*
X1600492Y1166830D03*
X1607972Y1159350D03*
X1600492Y1181791D03*
X1611712D03*
X1607972D03*
Y1189271D03*
X1611712D03*
X1596752Y1181791D03*
X1600492Y1189271D03*
X1596752D03*
X1600492Y1174310D03*
X1611712D03*
Y1204232D03*
X1607972D03*
Y1196751D03*
X1611712D03*
X1600492D03*
X1596752D03*
Y1204232D03*
X1600492D03*
X1606102Y1221062D03*
X1596752Y1207972D03*
X1607972D03*
X1611712D03*
Y1211712D03*
X1596752Y1219192D03*
X1600492Y1207972D03*
X1598622Y1221062D03*
X1609842D03*
X1602362D03*
X1598622Y1224803D03*
X1609842Y1232283D03*
Y1236023D03*
X1606102Y1228543D03*
Y1224803D03*
X1602362Y1232283D03*
Y1236023D03*
X1598622Y1243503D03*
X1609842Y1239763D03*
X1602362D03*
X1606102Y1258465D03*
X1598623D03*
X1609158Y1348187D03*
Y1360099D03*
Y1384297D03*
Y1372385D03*
X1624803Y1075196D03*
X1617322D03*
X1621062Y1071455D03*
X1613581D03*
X1617322Y1090157D03*
Y1078936D03*
X1613582Y1090157D03*
Y1086417D03*
X1624803Y1078936D03*
X1621063Y1086417D03*
Y1090157D03*
X1624803D03*
X1621062Y1093897D03*
X1617322D03*
Y1097637D03*
X1624803Y1093897D03*
Y1097637D03*
X1621063Y1105117D03*
X1613582D03*
Y1101377D03*
X1621062Y1097637D03*
X1626673Y1121948D03*
X1622933D03*
X1619193D03*
X1615452D03*
X1624803Y1108858D03*
X1621063D03*
X1617322D03*
X1613582D03*
X1615452Y1133169D03*
X1619193D03*
X1622933D03*
X1626673D03*
X1615452Y1140649D03*
X1619193D03*
X1622933D03*
X1626673D03*
X1615452Y1125688D03*
X1619193D03*
X1622933D03*
X1626673D03*
X1615452Y1148129D03*
X1619193D03*
X1622933D03*
X1626673D03*
X1619193Y1155610D03*
X1626673D03*
X1615452Y1170570D03*
X1622933D03*
X1626673Y1166830D03*
X1615452Y1159350D03*
X1619193Y1166830D03*
X1622933Y1159350D03*
X1615452Y1181791D03*
X1619193D03*
X1622933D03*
X1626673D03*
X1615452Y1189271D03*
X1619193D03*
X1622933D03*
X1626673D03*
Y1174310D03*
X1619193D03*
Y1204232D03*
X1615452D03*
X1626673D03*
X1622933D03*
X1615452Y1196751D03*
X1619193D03*
X1622933D03*
X1626673D03*
X1617322Y1221062D03*
X1619193Y1207972D03*
X1622933D03*
X1626673Y1211712D03*
Y1207972D03*
X1615452Y1211712D03*
Y1207972D03*
X1621063Y1221062D03*
X1613582D03*
X1624803D03*
X1613582Y1228543D03*
Y1224803D03*
X1621063Y1228543D03*
Y1224803D03*
X1624803Y1232283D03*
Y1236023D03*
X1617322Y1232283D03*
Y1236023D03*
Y1239763D03*
X1621063Y1258465D03*
X1613582D03*
X1617038Y1348187D03*
X1621398D03*
X1617038Y1360099D03*
X1621398D03*
X1617038Y1384297D03*
Y1372385D03*
X1621398D03*
Y1384297D03*
Y1396583D03*
Y1408495D03*
X1639763Y1075196D03*
X1632283D03*
X1643503Y1071455D03*
X1636022D03*
X1628542D03*
X1636023Y1090157D03*
X1643504Y1082677D03*
X1636023Y1086417D03*
X1643504Y1090157D03*
Y1086417D03*
X1639763Y1090157D03*
Y1078936D03*
X1632283D03*
X1628543Y1086417D03*
Y1090157D03*
X1632283D03*
X1628542Y1093897D03*
X1632283D03*
Y1097637D03*
X1639763Y1093897D03*
Y1097637D03*
X1628543Y1105117D03*
X1636023D03*
X1643504D03*
X1628542Y1097637D03*
X1641633Y1118208D03*
X1637893Y1121948D03*
X1634153D03*
X1630413D03*
X1641633D03*
X1643504Y1108858D03*
X1639763D03*
X1636023D03*
X1632283D03*
X1628543D03*
X1641633Y1136909D03*
X1630413Y1133169D03*
X1634153D03*
X1637893D03*
X1641633D03*
X1634153Y1140649D03*
X1637893D03*
X1641633Y1125688D03*
Y1129429D03*
X1630413Y1125688D03*
X1634153D03*
X1637893D03*
X1641633Y1140649D03*
X1630413D03*
Y1148129D03*
X1634153D03*
X1637893D03*
X1641633Y1144389D03*
Y1148129D03*
Y1151869D03*
X1634153Y1155610D03*
X1641633D03*
X1634153Y1166830D03*
X1630413Y1159350D03*
Y1170570D03*
X1634153Y1189271D03*
X1637893D03*
X1641633Y1178051D03*
X1634153Y1174310D03*
X1641633Y1185531D03*
X1630413Y1181791D03*
X1634153D03*
X1637893D03*
X1641633Y1189271D03*
X1630413D03*
X1641633Y1174310D03*
X1641653Y1196732D03*
X1641633Y1204232D03*
X1630413D03*
X1634153D03*
X1637893D03*
X1641633Y1200491D03*
X1630413Y1196751D03*
X1634153D03*
X1637893D03*
X1641633Y1193011D03*
Y1211712D03*
X1634153Y1207972D03*
X1630413D03*
X1634153Y1211712D03*
X1637893Y1207972D03*
Y1211712D03*
X1630413D03*
X1641633Y1207972D03*
X1628543Y1221062D03*
X1632283D03*
X1636023D03*
X1639763D03*
X1643504D03*
X1628543Y1228543D03*
Y1224803D03*
X1632283Y1232283D03*
Y1236023D03*
X1636023Y1228543D03*
Y1224803D03*
X1639763Y1232283D03*
Y1236023D03*
X1643504Y1228543D03*
Y1224803D03*
X1628543Y1239763D03*
X1639763D03*
X1632283Y1243503D03*
X1639763D03*
X1632283Y1247243D03*
X1639763D03*
X1643504Y1258465D03*
X1636023D03*
X1628543D03*
X1629278Y1348187D03*
X1641518D03*
X1633638D03*
X1629278Y1360099D03*
X1641518D03*
X1633638D03*
X1629278Y1384297D03*
Y1372385D03*
X1641518Y1384297D03*
Y1372385D03*
X1633638Y1384297D03*
Y1372385D03*
X1629278Y1396583D03*
X1641518D03*
X1633638D03*
Y1408495D03*
X1629278D03*
X1641518D03*
X1647244Y1075196D03*
X1654724D03*
X1658463Y1071455D03*
X1650983D03*
X1654724Y1078936D03*
Y1090157D03*
X1658464D03*
X1650984D03*
X1647244D03*
Y1093897D03*
X1658464Y1101377D03*
Y1105117D03*
X1650984D03*
X1645374Y1118208D03*
X1649114D03*
X1658464Y1108858D03*
X1654724D03*
X1650984D03*
X1647244D03*
X1649114Y1140649D03*
X1652854Y1136909D03*
X1645374Y1125688D03*
X1649114Y1136909D03*
X1652854Y1140649D03*
X1645374Y1155610D03*
Y1151869D03*
Y1148129D03*
X1652854D03*
X1649114Y1144389D03*
X1652854Y1155610D03*
X1649114Y1148129D03*
X1652854Y1151869D03*
X1656594D03*
X1660334D03*
Y1155610D03*
X1649114Y1151870D03*
X1645374Y1166830D03*
X1652854Y1159350D03*
X1660334Y1166830D03*
Y1170570D03*
X1645374Y1159350D03*
X1660334D03*
X1645374Y1170570D03*
X1652854D03*
Y1166830D03*
Y1185531D03*
X1656594Y1181791D03*
X1652854Y1178051D03*
Y1174310D03*
X1649114Y1181791D03*
X1656594Y1185531D03*
X1660334Y1174310D03*
Y1178051D03*
Y1185531D03*
X1645374Y1181791D03*
Y1174310D03*
X1649114Y1178051D03*
Y1189271D03*
X1652854D03*
X1649114Y1185531D03*
X1656594Y1193011D03*
X1652854Y1204232D03*
Y1196751D03*
Y1193011D03*
X1649114D03*
X1645374Y1196751D03*
X1649114Y1211712D03*
X1645374Y1207972D03*
X1660334Y1215452D03*
Y1211712D03*
X1654724Y1221062D03*
X1658464D03*
X1650984D03*
X1647244D03*
Y1232283D03*
Y1236023D03*
X1654724Y1232283D03*
X1658464Y1228543D03*
X1654724Y1236023D03*
X1658464Y1224803D03*
X1650984Y1228543D03*
Y1224803D03*
X1654724Y1239763D03*
Y1243503D03*
X1647244Y1247243D03*
X1654724D03*
X1647244Y1243503D03*
X1658464Y1258465D03*
X1650984D03*
X1645878Y1348187D03*
X1653758D03*
X1658118D03*
X1645878Y1360099D03*
X1653758D03*
X1658118D03*
X1645878Y1384297D03*
Y1372385D03*
X1653758D03*
Y1384297D03*
X1658118D03*
Y1372385D03*
X1645878Y1396583D03*
X1653758D03*
X1658118D03*
X1645878Y1408495D03*
X1653758D03*
X1658118D03*
X1662204Y1075196D03*
X1669685D03*
X1673425Y1071455D03*
X1665944D03*
X1662203Y1090157D03*
X1669686Y1078936D03*
X1669684Y1090157D03*
X1662204Y1093897D03*
X1669685D03*
X1673425Y1105117D03*
X1665945D03*
X1669685Y1108858D03*
X1673425Y1116338D03*
Y1123818D03*
X1665944Y1112598D03*
Y1120078D03*
X1665945Y1108858D03*
X1662204Y1123818D03*
Y1120078D03*
Y1116338D03*
Y1108858D03*
X1671555Y1140649D03*
X1673425Y1131299D03*
X1662204Y1135039D03*
Y1131299D03*
Y1127558D03*
Y1138779D03*
X1664074Y1151869D03*
X1671555Y1148129D03*
X1664074Y1144389D03*
Y1159350D03*
X1671555D03*
X1664074Y1166830D03*
X1671555D03*
X1664074Y1189271D03*
Y1174310D03*
X1671555Y1181791D03*
Y1174310D03*
X1664074Y1181791D03*
X1671555Y1189271D03*
X1665945Y1194881D03*
X1664074Y1204232D03*
X1669685Y1202362D03*
X1673425Y1221062D03*
X1669685Y1209842D03*
X1665945Y1221062D03*
Y1217322D03*
X1662204Y1221062D03*
Y1232283D03*
Y1236023D03*
X1673425Y1224803D03*
Y1228543D03*
X1669685Y1232283D03*
Y1236023D03*
X1665945Y1224803D03*
Y1228543D03*
X1662204Y1239763D03*
X1669685D03*
X1673425Y1258465D03*
X1665945D03*
X1665998Y1348187D03*
X1670358D03*
X1665998Y1360099D03*
X1670358D03*
X1665998Y1384297D03*
Y1372385D03*
X1670358D03*
Y1384297D03*
X1665998Y1396583D03*
X1670358D03*
X1665998Y1408495D03*
X1670358D03*
X1677166Y1075196D03*
X1684646D03*
X1692126D03*
X1688385Y1071455D03*
X1680905D03*
X1677166Y1078936D03*
X1692126D03*
X1684646D03*
X1684644Y1090157D03*
X1677165Y1093897D03*
X1684645D03*
X1680905Y1105117D03*
X1677164Y1108857D03*
X1684645Y1108858D03*
X1690256Y1140649D03*
Y1155610D03*
Y1148129D03*
X1682775Y1166830D03*
X1679035Y1170570D03*
X1690256D03*
Y1178051D03*
X1682775Y1174310D03*
X1679035Y1178051D03*
X1682775Y1181791D03*
X1679035Y1185531D03*
X1682775Y1189271D03*
X1690256Y1185531D03*
X1680905Y1194881D03*
X1690256Y1193011D03*
X1679035D03*
X1692126Y1202362D03*
X1680905D03*
Y1198621D03*
X1677165D03*
X1684645Y1221062D03*
X1692126Y1209842D03*
X1680905Y1221062D03*
Y1217322D03*
X1677165Y1221062D03*
Y1213582D03*
X1680905D03*
Y1209842D03*
Y1206102D03*
X1688385Y1224803D03*
Y1228543D03*
X1684645Y1236023D03*
Y1232283D03*
X1692126D03*
X1680905Y1224803D03*
Y1228543D03*
X1677165Y1232283D03*
Y1236023D03*
X1680905Y1239763D03*
X1688385Y1258465D03*
X1680905D03*
X1678238Y1348187D03*
X1690478D03*
X1682598D03*
X1678238Y1360099D03*
X1690478D03*
X1682598D03*
X1678238Y1372385D03*
Y1384297D03*
X1690478D03*
Y1372385D03*
X1682598Y1384297D03*
Y1372385D03*
X1678238Y1396583D03*
X1690478D03*
X1682598D03*
X1678238Y1408495D03*
X1690478D03*
X1682598D03*
X1695866Y1078936D03*
X1699607Y1090158D03*
Y1082677D03*
Y1101378D03*
Y1123819D03*
Y1116339D03*
Y1108859D03*
Y1131300D03*
X1693996Y1170570D03*
Y1178051D03*
Y1185531D03*
Y1193011D03*
X1697676D03*
X1695866Y1202362D03*
X1699607Y1198621D03*
Y1221062D03*
Y1213582D03*
Y1206102D03*
Y1228543D03*
X1695866Y1250984D03*
X1699607Y1247243D03*
Y1239762D03*
X1694838Y1348187D03*
X1702718D03*
X1707078D03*
X1702718Y1360099D03*
X1707078D03*
X1694838D03*
Y1384297D03*
Y1372385D03*
X1702718D03*
Y1384297D03*
X1707078D03*
Y1372385D03*
X1694838Y1396583D03*
X1702718D03*
X1707078D03*
X1694838Y1408495D03*
X1702718D03*
X1707078D03*
X1714958Y1348187D03*
X1719318D03*
X1714958Y1360099D03*
X1719318D03*
X1714958Y1384297D03*
Y1372385D03*
X1719318D03*
Y1384297D03*
X1714958Y1396583D03*
X1719318D03*
X1714958Y1408495D03*
X1719318D03*
X1727198Y1348187D03*
X1739438D03*
X1731558D03*
X1727198Y1360099D03*
X1739438D03*
X1731558D03*
X1739438Y1372385D03*
X1731558Y1384297D03*
Y1372385D03*
X1727198D03*
Y1384297D03*
X1739438D03*
X1727198Y1396583D03*
X1739438D03*
X1731558D03*
X1727198Y1408495D03*
X1739438D03*
X1731558D03*
G54D52*
X956448Y-30304D03*
Y-33204D03*
X953192Y-25085D03*
X956445Y-25099D03*
X950167Y-26405D03*
X953207Y-27600D03*
X956460Y-27614D03*
X978036Y-64265D03*
X975011Y-65585D03*
X978051Y-66780D03*
X981289Y-64279D03*
X981292Y-69484D03*
Y-72384D03*
X981304Y-66794D03*
X1231351Y-77080D03*
X1234592Y-79984D03*
X1234604Y-77094D03*
X1234592Y-82584D03*
Y-71970D03*
X1231336Y-74565D03*
X1234589Y-74579D03*
X1231336Y-64265D03*
X1234589D03*
X1234592Y-69470D03*
X1231351Y-66780D03*
X1234604D03*
X1228311Y-65585D03*
Y-75885D03*
X1236692Y-35515D03*
X1236707Y-38030D03*
X1233667Y-36835D03*
X1236692Y-25215D03*
X1236707Y-27730D03*
X1233667Y-26535D03*
X1239948Y-32920D03*
X1239945Y-35529D03*
X1239948Y-30420D03*
Y-40934D03*
X1239960Y-38044D03*
X1239948Y-43534D03*
X1239945Y-25215D03*
X1239960Y-27730D03*
X1487851Y-77080D03*
X1491092Y-79984D03*
X1491104Y-77094D03*
X1491092Y-82584D03*
Y-71970D03*
X1487836Y-74565D03*
X1491089Y-74579D03*
X1487836Y-64265D03*
X1491089D03*
X1491092Y-69470D03*
X1487851Y-66780D03*
X1491104D03*
X1484811Y-65585D03*
Y-75885D03*
X1526448Y-33050D03*
X1523192Y-35645D03*
X1526445Y-35659D03*
X1526448Y-30550D03*
X1523207Y-38160D03*
X1526448Y-41064D03*
X1526460Y-38174D03*
X1526448Y-43664D03*
X1520167Y-36965D03*
X1523192Y-25345D03*
X1526445D03*
X1523207Y-27860D03*
X1526460D03*
X1520167Y-26665D03*
X1742336Y-74565D03*
Y-64265D03*
X1739311Y-65585D03*
Y-75885D03*
X1742351Y-77080D03*
X1745592Y-79984D03*
X1745604Y-77094D03*
X1745592Y-82584D03*
Y-71970D03*
X1745589Y-74579D03*
Y-64265D03*
X1745592Y-69470D03*
X1742351Y-66780D03*
X1745604D03*
X1804667Y-37095D03*
Y-26795D03*
X1810948Y-33180D03*
X1807692Y-35775D03*
X1810945Y-35789D03*
X1810948Y-30680D03*
X1807707Y-38290D03*
X1810948Y-41194D03*
X1810960Y-38304D03*
X1810948Y-43794D03*
X1807692Y-25475D03*
X1810945D03*
X1807707Y-27990D03*
X1810960D03*
G54D24*
X46348Y1727941D03*
Y1737941D03*
Y1773941D03*
Y1783941D03*
X333112Y1751624D03*
Y1761624D03*
X333212Y1797624D03*
Y1807624D03*
X619861Y1751765D03*
Y1761765D03*
X619475Y1798845D03*
Y1808845D03*
X907163Y1752566D03*
Y1762566D03*
X907166Y1800435D03*
Y1810435D03*
G54D41*
X266841Y421555D03*
Y550020D03*
X295856Y421555D03*
Y550020D03*
X723927Y421555D03*
Y550020D03*
X752942Y421555D03*
Y550020D03*
X1181014Y421555D03*
Y550020D03*
X1210029Y421555D03*
Y550020D03*
X1638101Y421555D03*
Y550020D03*
X1667116Y421555D03*
Y550020D03*
G54D56*
X1236871Y1715189D03*
X1236864Y1773377D03*
X1235371Y1802909D03*
G54D57*
X1236871Y1744208D03*
%LPC*%
G75*
G54D64*
G01X-20602Y-468335D02*
Y-543335D01*
X479398D01*
Y-468335D01*
X-20602D01*
G01X-8602Y-533335D02*
Y-538335D01*
G01X-10059Y-533335D02*
X-7145D01*
G01X-2235Y-538335D02*
X-4769D01*
Y-533335D01*
X-2235D01*
G01X-3249Y-535752D02*
X-4769D01*
G01X331Y-533335D02*
Y-538335D01*
X2865D01*
G01X6698Y-538502D02*
X6571Y-538418D01*
Y-538252D01*
X6698Y-538168D01*
X6825Y-538252D01*
Y-538418D01*
X6698Y-538502D01*
G01Y-536252D02*
X6571Y-536168D01*
Y-536002D01*
X6698Y-535918D01*
X6825Y-536002D01*
Y-536168D01*
X6698Y-536252D01*
G01X11481Y-540002D02*
X10848Y-539168D01*
X10531Y-538335D01*
Y-535002D01*
X10848Y-534168D01*
X11481Y-533335D01*
G01X16898D02*
X16391Y-533502D01*
X16011Y-533918D01*
X15758Y-534418D01*
X15568Y-535085D01*
X15505Y-535835D01*
X15568Y-536585D01*
X15758Y-537252D01*
X16011Y-537752D01*
X16391Y-538168D01*
X16898Y-538335D01*
X17405Y-538168D01*
X17785Y-537752D01*
X18038Y-537252D01*
X18228Y-536585D01*
X18291Y-535835D01*
X18228Y-535085D01*
X18038Y-534418D01*
X17785Y-533918D01*
X17405Y-533502D01*
X16898Y-533335D01*
G01X20605Y-537335D02*
X20985Y-537918D01*
X21491Y-538252D01*
X22061Y-538335D01*
X22568Y-538252D01*
X23075Y-537835D01*
X23391Y-537335D01*
X23455Y-536835D01*
X23328Y-536252D01*
X22885Y-535835D01*
X22441Y-535668D01*
X21871D01*
G01X22441D02*
X22821Y-535418D01*
X23138Y-535002D01*
X23265Y-534502D01*
X23138Y-534002D01*
X22821Y-533585D01*
X22251Y-533335D01*
X21681Y-533418D01*
X21111Y-533752D01*
G01X27415Y-540002D02*
X28048Y-539168D01*
X28365Y-538335D01*
Y-535002D01*
X28048Y-534168D01*
X27415Y-533335D01*
G01X30805Y-537335D02*
X31185Y-537918D01*
X31691Y-538252D01*
X32261Y-538335D01*
X32768Y-538252D01*
X33275Y-537835D01*
X33591Y-537335D01*
X33655Y-536835D01*
X33528Y-536252D01*
X33085Y-535835D01*
X32641Y-535668D01*
X32071D01*
G01X32641D02*
X33021Y-535418D01*
X33338Y-535002D01*
X33465Y-534502D01*
X33338Y-534002D01*
X33021Y-533585D01*
X32451Y-533335D01*
X31881Y-533418D01*
X31311Y-533752D01*
G01X36095Y-534168D02*
X36475Y-533668D01*
X36918Y-533418D01*
X37425Y-533335D01*
X38058Y-533502D01*
X38501Y-533918D01*
X38628Y-534418D01*
X38565Y-534918D01*
X38311Y-535335D01*
X37045Y-536168D01*
X36475Y-536752D01*
X36095Y-537585D01*
X35968Y-538335D01*
X38628D01*
G01X42271D02*
X42398Y-537252D01*
X42588Y-536335D01*
X42841Y-535502D01*
X43158Y-534585D01*
X43665Y-533335D01*
X41131D01*
G01X46675Y-536668D02*
X48321D01*
G01X51395Y-534168D02*
X51775Y-533668D01*
X52218Y-533418D01*
X52725Y-533335D01*
X53358Y-533502D01*
X53801Y-533918D01*
X53928Y-534418D01*
X53865Y-534918D01*
X53611Y-535335D01*
X52345Y-536168D01*
X51775Y-536752D01*
X51395Y-537585D01*
X51268Y-538335D01*
X53928D01*
G01X56305Y-537335D02*
X56685Y-537918D01*
X57191Y-538252D01*
X57761Y-538335D01*
X58268Y-538252D01*
X58775Y-537835D01*
X59091Y-537335D01*
X59155Y-536835D01*
X59028Y-536252D01*
X58585Y-535835D01*
X58141Y-535668D01*
X57571D01*
G01X58141D02*
X58521Y-535418D01*
X58838Y-535002D01*
X58965Y-534502D01*
X58838Y-534002D01*
X58521Y-533585D01*
X57951Y-533335D01*
X57381Y-533418D01*
X56811Y-533752D01*
G01X63558Y-538335D02*
Y-533335D01*
X61215Y-536918D01*
X64381D01*
G01X66505Y-537585D02*
X66885Y-538002D01*
X67328Y-538252D01*
X67898Y-538335D01*
X68468Y-538168D01*
X68911Y-537835D01*
X69228Y-537252D01*
X69291Y-536585D01*
X69165Y-535918D01*
X68848Y-535502D01*
X68405Y-535168D01*
X67961Y-535085D01*
X67518Y-535168D01*
X66948Y-535502D01*
X67138Y-533335D01*
X68848D01*
G01X76895Y-538335D02*
Y-533335D01*
X79301D01*
G01X78415Y-535752D02*
X76895D01*
G01X81615Y-538335D02*
X83198Y-533335D01*
X84781Y-538335D01*
G01X84211Y-536585D02*
X82185D01*
G01X86968Y-538335D02*
X89628Y-533335D01*
G01X86968D02*
X89628Y-538335D01*
G01X93398Y-538502D02*
X93271Y-538418D01*
Y-538252D01*
X93398Y-538168D01*
X93525Y-538252D01*
Y-538418D01*
X93398Y-538502D01*
G01Y-536252D02*
X93271Y-536168D01*
Y-536002D01*
X93398Y-535918D01*
X93525Y-536002D01*
Y-536168D01*
X93398Y-536252D01*
G01X98181Y-540002D02*
X97548Y-539168D01*
X97231Y-538335D01*
Y-535002D01*
X97548Y-534168D01*
X98181Y-533335D01*
G01X103598D02*
X103091Y-533502D01*
X102711Y-533918D01*
X102458Y-534418D01*
X102268Y-535085D01*
X102205Y-535835D01*
X102268Y-536585D01*
X102458Y-537252D01*
X102711Y-537752D01*
X103091Y-538168D01*
X103598Y-538335D01*
X104105Y-538168D01*
X104485Y-537752D01*
X104738Y-537252D01*
X104928Y-536585D01*
X104991Y-535835D01*
X104928Y-535085D01*
X104738Y-534418D01*
X104485Y-533918D01*
X104105Y-533502D01*
X103598Y-533335D01*
G01X107305Y-537335D02*
X107685Y-537918D01*
X108191Y-538252D01*
X108761Y-538335D01*
X109268Y-538252D01*
X109775Y-537835D01*
X110091Y-537335D01*
X110155Y-536835D01*
X110028Y-536252D01*
X109585Y-535835D01*
X109141Y-535668D01*
X108571D01*
G01X109141D02*
X109521Y-535418D01*
X109838Y-535002D01*
X109965Y-534502D01*
X109838Y-534002D01*
X109521Y-533585D01*
X108951Y-533335D01*
X108381Y-533418D01*
X107811Y-533752D01*
G01X114115Y-540002D02*
X114748Y-539168D01*
X115065Y-538335D01*
Y-535002D01*
X114748Y-534168D01*
X114115Y-533335D01*
G01X117505Y-537335D02*
X117885Y-537918D01*
X118391Y-538252D01*
X118961Y-538335D01*
X119468Y-538252D01*
X119975Y-537835D01*
X120291Y-537335D01*
X120355Y-536835D01*
X120228Y-536252D01*
X119785Y-535835D01*
X119341Y-535668D01*
X118771D01*
G01X119341D02*
X119721Y-535418D01*
X120038Y-535002D01*
X120165Y-534502D01*
X120038Y-534002D01*
X119721Y-533585D01*
X119151Y-533335D01*
X118581Y-533418D01*
X118011Y-533752D01*
G01X122921Y-537752D02*
X123365Y-538168D01*
X123871Y-538335D01*
X124378Y-538168D01*
X124821Y-537668D01*
X125138Y-536918D01*
X125265Y-536168D01*
Y-535252D01*
X125138Y-534502D01*
X124821Y-533835D01*
X124441Y-533502D01*
X123998Y-533335D01*
X123491Y-533502D01*
X123111Y-533835D01*
X122858Y-534335D01*
X122731Y-535002D01*
X122858Y-535585D01*
X123175Y-536168D01*
X123555Y-536502D01*
X123998Y-536585D01*
X124505Y-536418D01*
X124885Y-536002D01*
X125265Y-535252D01*
G01X128971Y-538335D02*
X129098Y-537252D01*
X129288Y-536335D01*
X129541Y-535502D01*
X129858Y-534585D01*
X130365Y-533335D01*
X127831D01*
G01X133375Y-536668D02*
X135021D01*
G01X137905Y-537335D02*
X138285Y-537918D01*
X138791Y-538252D01*
X139361Y-538335D01*
X139868Y-538252D01*
X140375Y-537835D01*
X140691Y-537335D01*
X140755Y-536835D01*
X140628Y-536252D01*
X140185Y-535835D01*
X139741Y-535668D01*
X139171D01*
G01X139741D02*
X140121Y-535418D01*
X140438Y-535002D01*
X140565Y-534502D01*
X140438Y-534002D01*
X140121Y-533585D01*
X139551Y-533335D01*
X138981Y-533418D01*
X138411Y-533752D01*
G01X143195Y-536252D02*
X143638Y-535668D01*
X144018Y-535335D01*
X144525Y-535168D01*
X144968Y-535335D01*
X145285Y-535668D01*
X145538Y-536168D01*
X145601Y-536752D01*
X145538Y-537252D01*
X145285Y-537752D01*
X144905Y-538168D01*
X144461Y-538335D01*
X143955Y-538168D01*
X143511Y-537668D01*
X143258Y-536918D01*
X143195Y-536085D01*
X143321Y-535002D01*
X143511Y-534418D01*
X143828Y-533835D01*
X144271Y-533418D01*
X144715Y-533335D01*
X145158Y-533502D01*
X145475Y-533918D01*
G01X149498Y-538335D02*
Y-533335D01*
X148738Y-534335D01*
G01Y-538335D02*
X150258D01*
G01X155358D02*
Y-533335D01*
X153015Y-536918D01*
X156181D01*
G01X174398Y-468335D02*
Y-543335D01*
G01Y-518335D02*
X277398D01*
Y-493335D01*
G01X174398D02*
X277398D01*
G01Y-468335D02*
Y-543335D01*
G01X279398Y-468335D02*
Y-543335D01*
G01X284905Y-528335D02*
Y-523335D01*
X286171D01*
X286678Y-523585D01*
X287058Y-523918D01*
X287375Y-524418D01*
X287628Y-525002D01*
X287691Y-525835D01*
X287628Y-526668D01*
X287375Y-527252D01*
X287058Y-527752D01*
X286678Y-528085D01*
X286171Y-528335D01*
X284905D01*
G01X289815D02*
X291398Y-523335D01*
X292981Y-528335D01*
G01X292411Y-526585D02*
X290385D01*
G01X296498Y-523335D02*
Y-528335D01*
G01X295041Y-523335D02*
X297955D01*
G01X302865Y-528335D02*
X300331D01*
Y-523335D01*
X302865D01*
G01X301851Y-525752D02*
X300331D01*
G01X306698Y-528502D02*
X306571Y-528418D01*
Y-528252D01*
X306698Y-528168D01*
X306825Y-528252D01*
Y-528418D01*
X306698Y-528502D01*
G01Y-526252D02*
X306571Y-526168D01*
Y-526002D01*
X306698Y-525918D01*
X306825Y-526002D01*
Y-526168D01*
X306698Y-526252D01*
G01X279398Y-518335D02*
X479398D01*
G01X285031Y-503335D02*
Y-498335D01*
X286551D01*
X287058Y-498585D01*
X287438Y-499168D01*
X287565Y-499835D01*
X287438Y-500502D01*
X287121Y-501002D01*
X286551Y-501252D01*
X285031D01*
G01X290258Y-503502D02*
X292538Y-498335D01*
G01X295041Y-503335D02*
Y-498335D01*
X297955Y-503335D01*
Y-498335D01*
G01X301598Y-503502D02*
X301471Y-503418D01*
Y-503252D01*
X301598Y-503168D01*
X301725Y-503252D01*
Y-503418D01*
X301598Y-503502D01*
G01Y-501252D02*
X301471Y-501168D01*
Y-501002D01*
X301598Y-500918D01*
X301725Y-501002D01*
Y-501168D01*
X301598Y-501252D01*
G01X279398Y-493335D02*
X479398D01*
G01X285031Y-478335D02*
Y-473335D01*
X286551D01*
X287058Y-473585D01*
X287438Y-474168D01*
X287565Y-474835D01*
X287438Y-475502D01*
X287121Y-476002D01*
X286551Y-476252D01*
X285031D01*
G01X290131Y-478335D02*
Y-473335D01*
X291715D01*
X292221Y-473585D01*
X292538Y-473918D01*
X292665Y-474585D01*
X292538Y-475252D01*
X292158Y-475668D01*
X291715Y-475918D01*
X290131D01*
G01X291715D02*
X292665Y-478335D01*
G01X296498D02*
X295991Y-478252D01*
X295548Y-477918D01*
X295168Y-477418D01*
X294915Y-476835D01*
X294788Y-476168D01*
Y-475502D01*
X294915Y-474835D01*
X295168Y-474252D01*
X295548Y-473752D01*
X295991Y-473418D01*
X296498Y-473335D01*
X297005Y-473418D01*
X297448Y-473752D01*
X297828Y-474252D01*
X298081Y-474835D01*
X298208Y-475502D01*
Y-476168D01*
X298081Y-476835D01*
X297828Y-477418D01*
X297448Y-477918D01*
X297005Y-478252D01*
X296498Y-478335D01*
G01X300331Y-477335D02*
X300648Y-477835D01*
X301028Y-478168D01*
X301471Y-478335D01*
X301978Y-478168D01*
X302358Y-477835D01*
X302738Y-477335D01*
X302865Y-476668D01*
Y-473335D01*
G01X307965Y-478335D02*
X305431D01*
Y-473335D01*
X307965D01*
G01X306951Y-475752D02*
X305431D01*
G01X313191Y-473752D02*
X312811Y-473502D01*
X312368Y-473335D01*
X311861D01*
X311291Y-473585D01*
X310848Y-474002D01*
X310531Y-474502D01*
X310278Y-475335D01*
X310215Y-476085D01*
X310341Y-476835D01*
X310531Y-477335D01*
X310911Y-477835D01*
X311355Y-478168D01*
X311798Y-478335D01*
X312241D01*
X312685Y-478168D01*
X313065Y-477918D01*
X313381Y-477585D01*
G01X316898Y-473335D02*
Y-478335D01*
G01X315441Y-473335D02*
X318355D01*
G01X321998Y-478502D02*
X321871Y-478418D01*
Y-478252D01*
X321998Y-478168D01*
X322125Y-478252D01*
Y-478418D01*
X321998Y-478502D01*
G01Y-476252D02*
X321871Y-476168D01*
Y-476002D01*
X321998Y-475918D01*
X322125Y-476002D01*
Y-476168D01*
X321998Y-476252D01*
G01X394258Y-543563D02*
Y-518563D01*
G01X397031Y-520835D02*
Y-525835D01*
X399565D01*
G01X402638Y-520835D02*
X404158D01*
G01X403398D02*
Y-525835D01*
G01X402638D02*
X404158D01*
G01X409005Y-523168D02*
X409258Y-522918D01*
X409448Y-522502D01*
X409575Y-521918D01*
X409448Y-521418D01*
X409195Y-521085D01*
X408751Y-520835D01*
X407041D01*
Y-525835D01*
X409131D01*
X409575Y-525502D01*
X409828Y-525002D01*
X409955Y-524418D01*
X409828Y-523835D01*
X409448Y-523335D01*
X409005Y-523168D01*
X407041D01*
G01X413598Y-526002D02*
X413471Y-525918D01*
Y-525752D01*
X413598Y-525668D01*
X413725Y-525752D01*
Y-525918D01*
X413598Y-526002D01*
G01Y-523752D02*
X413471Y-523668D01*
Y-523502D01*
X413598Y-523418D01*
X413725Y-523502D01*
Y-523668D01*
X413598Y-523752D01*
G01X437258Y-518563D02*
Y-543563D01*
G01X437398Y-518335D02*
Y-543335D01*
G01X441298Y-520835D02*
Y-525835D01*
G01X439841Y-520835D02*
X442755D01*
G01X446398Y-525835D02*
X446018Y-525752D01*
X445638Y-525418D01*
X445385Y-524835D01*
X445258Y-524168D01*
X445385Y-523502D01*
X445638Y-522918D01*
X446018Y-522585D01*
X446398Y-522502D01*
X446778Y-522585D01*
X447158Y-522918D01*
X447411Y-523502D01*
X447475Y-524168D01*
X447411Y-524835D01*
X447158Y-525418D01*
X446778Y-525752D01*
X446398Y-525835D01*
G01X451498D02*
X451118Y-525752D01*
X450738Y-525418D01*
X450485Y-524835D01*
X450358Y-524168D01*
X450485Y-523502D01*
X450738Y-522918D01*
X451118Y-522585D01*
X451498Y-522502D01*
X451878Y-522585D01*
X452258Y-522918D01*
X452511Y-523502D01*
X452575Y-524168D01*
X452511Y-524835D01*
X452258Y-525418D01*
X451878Y-525752D01*
X451498Y-525835D01*
G01X456598D02*
Y-520835D01*
G01X461698Y-526002D02*
X461571Y-525918D01*
Y-525752D01*
X461698Y-525668D01*
X461825Y-525752D01*
Y-525918D01*
X461698Y-526002D01*
G01Y-523752D02*
X461571Y-523668D01*
Y-523502D01*
X461698Y-523418D01*
X461825Y-523502D01*
Y-523668D01*
X461698Y-523752D01*
G01X437398Y-493335D02*
Y-518335D01*
G01X440031Y-500835D02*
Y-495835D01*
X441615D01*
X442121Y-496085D01*
X442438Y-496418D01*
X442565Y-497085D01*
X442438Y-497752D01*
X442058Y-498168D01*
X441615Y-498418D01*
X440031D01*
G01X441615D02*
X442565Y-500835D01*
G01X447665D02*
X445131D01*
Y-495835D01*
X447665D01*
G01X446651Y-498252D02*
X445131D01*
G01X449915Y-495835D02*
X451498Y-500835D01*
X453081Y-495835D01*
G01X456598Y-501002D02*
X456471Y-500918D01*
Y-500752D01*
X456598Y-500668D01*
X456725Y-500752D01*
Y-500918D01*
X456598Y-501002D01*
G01Y-498752D02*
X456471Y-498668D01*
Y-498502D01*
X456598Y-498418D01*
X456725Y-498502D01*
Y-498668D01*
X456598Y-498752D01*
G01X445411Y-546502D02*
X445518Y-546377D01*
X445598Y-546168D01*
X445651Y-545877D01*
X445598Y-545627D01*
X445491Y-545460D01*
X445305Y-545335D01*
X444585D01*
Y-547835D01*
X445465D01*
X445651Y-547668D01*
X445758Y-547418D01*
X445811Y-547127D01*
X445758Y-546835D01*
X445598Y-546585D01*
X445411Y-546502D01*
X444585D01*
G01X447878Y-547835D02*
Y-546168D01*
G01Y-546460D02*
X447771Y-546293D01*
X447611Y-546210D01*
X447425Y-546168D01*
X447238Y-546252D01*
X447078Y-546418D01*
X446971Y-546668D01*
X446918Y-547002D01*
X446971Y-547335D01*
X447078Y-547585D01*
X447238Y-547752D01*
X447425Y-547835D01*
X447611Y-547793D01*
X447771Y-547668D01*
X447878Y-547502D01*
G01X449198Y-547543D02*
X449331Y-547710D01*
X449518Y-547835D01*
X449678D01*
X449838Y-547752D01*
X449945Y-547627D01*
X449998Y-547460D01*
X449971Y-547210D01*
X449865Y-547085D01*
X449385Y-546835D01*
X449278Y-546543D01*
X449331Y-546335D01*
X449438Y-546210D01*
X449598Y-546168D01*
X449758Y-546210D01*
X449918Y-546335D01*
G01X451398Y-546710D02*
X452251D01*
X452171Y-546418D01*
X452038Y-546252D01*
X451851Y-546168D01*
X451665Y-546210D01*
X451505Y-546335D01*
X451398Y-546627D01*
X451345Y-546877D01*
Y-547127D01*
X451398Y-547377D01*
X451531Y-547627D01*
X451691Y-547793D01*
X451878Y-547835D01*
X452065Y-547752D01*
X452251Y-547502D01*
G01X453518Y-547835D02*
Y-545335D01*
G01Y-546585D02*
X453651Y-546335D01*
X453811Y-546210D01*
X453971Y-546168D01*
X454211Y-546252D01*
X454371Y-546418D01*
X454478Y-546710D01*
Y-547043D01*
X454425Y-547377D01*
X454318Y-547627D01*
X454131Y-547793D01*
X453971Y-547835D01*
X453811Y-547793D01*
X453651Y-547668D01*
X453518Y-547460D01*
G01X456198Y-547835D02*
X456038Y-547793D01*
X455878Y-547627D01*
X455771Y-547335D01*
X455718Y-547002D01*
X455771Y-546668D01*
X455878Y-546377D01*
X456038Y-546210D01*
X456198Y-546168D01*
X456358Y-546210D01*
X456518Y-546377D01*
X456625Y-546668D01*
X456651Y-547002D01*
X456625Y-547335D01*
X456518Y-547627D01*
X456358Y-547793D01*
X456198Y-547835D01*
G01X458878D02*
Y-546168D01*
G01Y-546460D02*
X458771Y-546293D01*
X458611Y-546210D01*
X458425Y-546168D01*
X458238Y-546252D01*
X458078Y-546418D01*
X457971Y-546668D01*
X457918Y-547002D01*
X457971Y-547335D01*
X458078Y-547585D01*
X458238Y-547752D01*
X458425Y-547835D01*
X458611Y-547793D01*
X458771Y-547668D01*
X458878Y-547502D01*
G01X460225Y-547835D02*
Y-546168D01*
G01Y-546502D02*
X460358Y-546335D01*
X460491Y-546210D01*
X460678Y-546168D01*
X460811Y-546210D01*
X460971Y-546335D01*
G01X463278Y-545335D02*
Y-547835D01*
G01Y-547460D02*
X463171Y-547668D01*
X463011Y-547793D01*
X462825Y-547835D01*
X462611Y-547752D01*
X462451Y-547543D01*
X462345Y-547293D01*
X462318Y-547002D01*
X462345Y-546710D01*
X462451Y-546460D01*
X462611Y-546252D01*
X462825Y-546168D01*
X463011Y-546210D01*
X463145Y-546293D01*
X463278Y-546460D01*
G01X466665Y-547835D02*
Y-545335D01*
X467331D01*
X467545Y-545460D01*
X467678Y-545627D01*
X467731Y-545960D01*
X467678Y-546293D01*
X467518Y-546502D01*
X467331Y-546627D01*
X466665D01*
G01X467331D02*
X467731Y-547835D01*
G01X468998Y-546710D02*
X469851D01*
X469771Y-546418D01*
X469638Y-546252D01*
X469451Y-546168D01*
X469265Y-546210D01*
X469105Y-546335D01*
X468998Y-546627D01*
X468945Y-546877D01*
Y-547127D01*
X468998Y-547377D01*
X469131Y-547627D01*
X469291Y-547793D01*
X469478Y-547835D01*
X469665Y-547752D01*
X469851Y-547502D01*
G01X471118Y-546168D02*
X471598Y-547835D01*
X472078Y-546168D01*
G01X473798Y-547918D02*
X473745Y-547877D01*
Y-547793D01*
X473798Y-547752D01*
X473851Y-547793D01*
Y-547877D01*
X473798Y-547918D01*
G01X475545Y-547543D02*
X475731Y-547752D01*
X475945Y-547835D01*
X476158Y-547752D01*
X476345Y-547502D01*
X476478Y-547127D01*
X476531Y-546752D01*
Y-546293D01*
X476478Y-545918D01*
X476345Y-545585D01*
X476185Y-545418D01*
X475998Y-545335D01*
X475785Y-545418D01*
X475625Y-545585D01*
X475518Y-545835D01*
X475465Y-546168D01*
X475518Y-546460D01*
X475651Y-546752D01*
X475811Y-546918D01*
X475998Y-546960D01*
X476211Y-546877D01*
X476371Y-546668D01*
X476531Y-546293D01*
G01X478411Y-546502D02*
X478518Y-546377D01*
X478598Y-546168D01*
X478651Y-545877D01*
X478598Y-545627D01*
X478491Y-545460D01*
X478305Y-545335D01*
X477585D01*
Y-547835D01*
X478465D01*
X478651Y-547668D01*
X478758Y-547418D01*
X478811Y-547127D01*
X478758Y-546835D01*
X478598Y-546585D01*
X478411Y-546502D01*
X477585D01*
G01X-1490433Y-1677216D02*
Y3837819D01*
X4496476D01*
Y-1677216D01*
X-1490433D01*
G01X-7782Y-515685D02*
X-6215D01*
Y-517575D01*
X-6685Y-518205D01*
X-7234Y-518625D01*
X-8017Y-518835D01*
X-8800Y-518625D01*
X-9349Y-518205D01*
X-9819Y-517575D01*
X-10132Y-516840D01*
X-10289Y-516000D01*
Y-515265D01*
X-10132Y-514635D01*
X-9819Y-513900D01*
X-9349Y-513270D01*
X-8879Y-512850D01*
X-8252Y-512535D01*
X-7704D01*
X-7077Y-512745D01*
X-6607Y-513165D01*
G01X-3675Y-512535D02*
Y-517050D01*
X-3362Y-517995D01*
X-2735Y-518625D01*
X-1952Y-518835D01*
X-1169Y-518625D01*
X-542Y-517995D01*
X-229Y-517050D01*
Y-512535D01*
G01X3408D02*
X5288D01*
G01X4348D02*
Y-518835D01*
G01X3408D02*
X5288D01*
G01X9003Y-517995D02*
X9630Y-518520D01*
X10335Y-518835D01*
X10961D01*
X11588Y-518520D01*
X12058Y-517995D01*
X12293Y-517260D01*
X12136Y-516525D01*
X11745Y-515895D01*
X11040Y-515475D01*
X10100Y-515265D01*
X9551Y-514845D01*
X9316Y-514110D01*
X9473Y-513375D01*
X9865Y-512850D01*
X10413Y-512535D01*
X10961D01*
X11510Y-512745D01*
X11980Y-513270D01*
G01X15303Y-518835D02*
Y-512535D01*
G01X18593D02*
Y-518835D01*
G01Y-515685D02*
X15303D01*
G01X21290Y-518835D02*
X23248Y-512535D01*
X25206Y-518835D01*
G01X24501Y-516630D02*
X21995D01*
G01X27746Y-518835D02*
Y-512535D01*
X31350Y-518835D01*
Y-512535D01*
G01X40425Y-518835D02*
Y-512535D01*
X41991D01*
X42618Y-512850D01*
X43088Y-513270D01*
X43480Y-513900D01*
X43793Y-514635D01*
X43871Y-515685D01*
X43793Y-516735D01*
X43480Y-517470D01*
X43088Y-518100D01*
X42618Y-518520D01*
X41991Y-518835D01*
X40425D01*
G01X47508Y-512535D02*
X49388D01*
G01X48448D02*
Y-518835D01*
G01X47508D02*
X49388D01*
G01X53103Y-517995D02*
X53730Y-518520D01*
X54435Y-518835D01*
X55061D01*
X55688Y-518520D01*
X56158Y-517995D01*
X56393Y-517260D01*
X56236Y-516525D01*
X55845Y-515895D01*
X55140Y-515475D01*
X54200Y-515265D01*
X53651Y-514845D01*
X53416Y-514110D01*
X53573Y-513375D01*
X53965Y-512850D01*
X54513Y-512535D01*
X55061D01*
X55610Y-512745D01*
X56080Y-513270D01*
G01X61048Y-512535D02*
Y-518835D01*
G01X59246Y-512535D02*
X62850D01*
G01X67348Y-519045D02*
X67191Y-518940D01*
Y-518730D01*
X67348Y-518625D01*
X67505Y-518730D01*
Y-518940D01*
X67348Y-519045D01*
G01X73491Y-519990D02*
X73805Y-518625D01*
G01X79948Y-512535D02*
Y-518835D01*
G01X78146Y-512535D02*
X81750D01*
G01X84290Y-518835D02*
X86248Y-512535D01*
X88206Y-518835D01*
G01X87501Y-516630D02*
X84995D01*
G01X92548Y-518835D02*
X91921Y-518730D01*
X91373Y-518310D01*
X90903Y-517680D01*
X90590Y-516945D01*
X90433Y-516105D01*
Y-515265D01*
X90590Y-514425D01*
X90903Y-513690D01*
X91373Y-513060D01*
X91921Y-512640D01*
X92548Y-512535D01*
X93175Y-512640D01*
X93723Y-513060D01*
X94193Y-513690D01*
X94506Y-514425D01*
X94663Y-515265D01*
Y-516105D01*
X94506Y-516945D01*
X94193Y-517680D01*
X93723Y-518310D01*
X93175Y-518730D01*
X92548Y-518835D01*
G01X98848D02*
Y-516000D01*
X97281Y-512535D01*
G01X100415D02*
X98848Y-516000D01*
G01X103425Y-512535D02*
Y-517050D01*
X103738Y-517995D01*
X104365Y-518625D01*
X105148Y-518835D01*
X105931Y-518625D01*
X106558Y-517995D01*
X106871Y-517050D01*
Y-512535D01*
G01X109490Y-518835D02*
X111448Y-512535D01*
X113406Y-518835D01*
G01X112701Y-516630D02*
X110195D01*
G01X115946Y-518835D02*
Y-512535D01*
X119550Y-518835D01*
Y-512535D01*
G01X-6529Y-523060D02*
X-6999Y-522745D01*
X-7547Y-522535D01*
X-8174D01*
X-8879Y-522850D01*
X-9427Y-523375D01*
X-9819Y-524005D01*
X-10132Y-525055D01*
X-10210Y-526000D01*
X-10054Y-526945D01*
X-9819Y-527575D01*
X-9349Y-528205D01*
X-8800Y-528625D01*
X-8252Y-528835D01*
X-7704D01*
X-7155Y-528625D01*
X-6685Y-528310D01*
X-6294Y-527890D01*
G01X-2892Y-522535D02*
X-1012D01*
G01X-1952D02*
Y-528835D01*
G01X-2892D02*
X-1012D01*
G01X4348Y-522535D02*
Y-528835D01*
G01X2546Y-522535D02*
X6150D01*
G01X10648Y-528835D02*
Y-526000D01*
X9081Y-522535D01*
G01X12215D02*
X10648Y-526000D01*
G01X21525Y-527575D02*
X21995Y-528310D01*
X22621Y-528730D01*
X23326Y-528835D01*
X23953Y-528730D01*
X24580Y-528205D01*
X24971Y-527575D01*
X25050Y-526945D01*
X24893Y-526210D01*
X24345Y-525685D01*
X23796Y-525475D01*
X23091D01*
G01X23796D02*
X24266Y-525160D01*
X24658Y-524635D01*
X24815Y-524005D01*
X24658Y-523375D01*
X24266Y-522850D01*
X23561Y-522535D01*
X22856Y-522640D01*
X22151Y-523060D01*
G01X27825Y-527575D02*
X28295Y-528310D01*
X28921Y-528730D01*
X29626Y-528835D01*
X30253Y-528730D01*
X30880Y-528205D01*
X31271Y-527575D01*
X31350Y-526945D01*
X31193Y-526210D01*
X30645Y-525685D01*
X30096Y-525475D01*
X29391D01*
G01X30096D02*
X30566Y-525160D01*
X30958Y-524635D01*
X31115Y-524005D01*
X30958Y-523375D01*
X30566Y-522850D01*
X29861Y-522535D01*
X29156Y-522640D01*
X28451Y-523060D01*
G01X34125Y-527575D02*
X34595Y-528310D01*
X35221Y-528730D01*
X35926Y-528835D01*
X36553Y-528730D01*
X37180Y-528205D01*
X37571Y-527575D01*
X37650Y-526945D01*
X37493Y-526210D01*
X36945Y-525685D01*
X36396Y-525475D01*
X35691D01*
G01X36396D02*
X36866Y-525160D01*
X37258Y-524635D01*
X37415Y-524005D01*
X37258Y-523375D01*
X36866Y-522850D01*
X36161Y-522535D01*
X35456Y-522640D01*
X34751Y-523060D01*
G01X41991Y-528835D02*
X42148Y-527470D01*
X42383Y-526315D01*
X42696Y-525265D01*
X43088Y-524110D01*
X43715Y-522535D01*
X40581D01*
G01X48291Y-528835D02*
X48448Y-527470D01*
X48683Y-526315D01*
X48996Y-525265D01*
X49388Y-524110D01*
X50015Y-522535D01*
X46881D01*
G01X54591Y-529990D02*
X54905Y-528625D01*
G01X61048Y-522535D02*
Y-528835D01*
G01X59246Y-522535D02*
X62850D01*
G01X65390Y-528835D02*
X67348Y-522535D01*
X69306Y-528835D01*
G01X68601Y-526630D02*
X66095D01*
G01X72708Y-522535D02*
X74588D01*
G01X73648D02*
Y-528835D01*
G01X72708D02*
X74588D01*
G01X77598Y-522535D02*
X78695Y-528835D01*
X79948Y-522535D01*
X81201Y-528835D01*
X82298Y-522535D01*
G01X84290Y-528835D02*
X86248Y-522535D01*
X88206Y-528835D01*
G01X87501Y-526630D02*
X84995D01*
G01X90746Y-528835D02*
Y-522535D01*
X94350Y-528835D01*
Y-522535D01*
G01X104756Y-530935D02*
X103973Y-529885D01*
X103581Y-528835D01*
Y-524635D01*
X103973Y-523585D01*
X104756Y-522535D01*
G01X116181Y-528835D02*
Y-522535D01*
X118140D01*
X118766Y-522850D01*
X119158Y-523270D01*
X119315Y-524110D01*
X119158Y-524950D01*
X118688Y-525475D01*
X118140Y-525790D01*
X116181D01*
G01X118140D02*
X119315Y-528835D01*
G01X124048Y-529045D02*
X123891Y-528940D01*
Y-528730D01*
X124048Y-528625D01*
X124205Y-528730D01*
Y-528940D01*
X124048Y-529045D01*
G01X130348Y-528835D02*
X129721Y-528730D01*
X129173Y-528310D01*
X128703Y-527680D01*
X128390Y-526945D01*
X128233Y-526105D01*
Y-525265D01*
X128390Y-524425D01*
X128703Y-523690D01*
X129173Y-523060D01*
X129721Y-522640D01*
X130348Y-522535D01*
X130975Y-522640D01*
X131523Y-523060D01*
X131993Y-523690D01*
X132306Y-524425D01*
X132463Y-525265D01*
Y-526105D01*
X132306Y-526945D01*
X131993Y-527680D01*
X131523Y-528310D01*
X130975Y-528730D01*
X130348Y-528835D01*
G01X136648Y-529045D02*
X136491Y-528940D01*
Y-528730D01*
X136648Y-528625D01*
X136805Y-528730D01*
Y-528940D01*
X136648Y-529045D01*
G01X144671Y-523060D02*
X144201Y-522745D01*
X143653Y-522535D01*
X143026D01*
X142321Y-522850D01*
X141773Y-523375D01*
X141381Y-524005D01*
X141068Y-525055D01*
X140990Y-526000D01*
X141146Y-526945D01*
X141381Y-527575D01*
X141851Y-528205D01*
X142400Y-528625D01*
X142948Y-528835D01*
X143496D01*
X144045Y-528625D01*
X144515Y-528310D01*
X144906Y-527890D01*
G01X149248Y-529045D02*
X149091Y-528940D01*
Y-528730D01*
X149248Y-528625D01*
X149405Y-528730D01*
Y-528940D01*
X149248Y-529045D01*
G01X155940Y-530935D02*
X156723Y-529885D01*
X157115Y-528835D01*
Y-524635D01*
X156723Y-523585D01*
X155940Y-522535D01*
G01X-10054Y-508835D02*
Y-502535D01*
X-6450Y-508835D01*
Y-502535D01*
G01X-1952Y-508835D02*
X-2579Y-508730D01*
X-3127Y-508310D01*
X-3597Y-507680D01*
X-3910Y-506945D01*
X-4067Y-506105D01*
Y-505265D01*
X-3910Y-504425D01*
X-3597Y-503690D01*
X-3127Y-503060D01*
X-2579Y-502640D01*
X-1952Y-502535D01*
X-1325Y-502640D01*
X-777Y-503060D01*
X-307Y-503690D01*
X6Y-504425D01*
X163Y-505265D01*
Y-506105D01*
X6Y-506945D01*
X-307Y-507680D01*
X-777Y-508310D01*
X-1325Y-508730D01*
X-1952Y-508835D01*
G01X4348Y-509045D02*
X4191Y-508940D01*
Y-508730D01*
X4348Y-508625D01*
X4505Y-508730D01*
Y-508940D01*
X4348Y-509045D01*
G01X9160Y-503585D02*
X9630Y-502955D01*
X10178Y-502640D01*
X10805Y-502535D01*
X11588Y-502745D01*
X12136Y-503270D01*
X12293Y-503900D01*
X12215Y-504530D01*
X11901Y-505055D01*
X10335Y-506105D01*
X9630Y-506840D01*
X9160Y-507890D01*
X9003Y-508835D01*
X12293D01*
G01X16948D02*
Y-502535D01*
X16008Y-503795D01*
G01Y-508835D02*
X17888D01*
G01X23248D02*
Y-502535D01*
X22308Y-503795D01*
G01Y-508835D02*
X24188D01*
G01X29391Y-509990D02*
X29705Y-508625D01*
G01X33498Y-502535D02*
X34595Y-508835D01*
X35848Y-502535D01*
X37101Y-508835D01*
X38198Y-502535D01*
G01X43715Y-508835D02*
X40581D01*
Y-502535D01*
X43715D01*
G01X42461Y-505580D02*
X40581D01*
G01X46646Y-508835D02*
Y-502535D01*
X50250Y-508835D01*
Y-502535D01*
G01X53103Y-508835D02*
Y-502535D01*
G01X56393D02*
Y-508835D01*
G01Y-505685D02*
X53103D01*
G01X59325Y-502535D02*
Y-507050D01*
X59638Y-507995D01*
X60265Y-508625D01*
X61048Y-508835D01*
X61831Y-508625D01*
X62458Y-507995D01*
X62771Y-507050D01*
Y-502535D01*
G01X65390Y-508835D02*
X67348Y-502535D01*
X69306Y-508835D01*
G01X68601Y-506630D02*
X66095D01*
G01X78460Y-503585D02*
X78930Y-502955D01*
X79478Y-502640D01*
X80105Y-502535D01*
X80888Y-502745D01*
X81436Y-503270D01*
X81593Y-503900D01*
X81515Y-504530D01*
X81201Y-505055D01*
X79635Y-506105D01*
X78930Y-506840D01*
X78460Y-507890D01*
X78303Y-508835D01*
X81593D01*
G01X84446D02*
Y-502535D01*
X88050Y-508835D01*
Y-502535D01*
G01X90825Y-508835D02*
Y-502535D01*
X92391D01*
X93018Y-502850D01*
X93488Y-503270D01*
X93880Y-503900D01*
X94193Y-504635D01*
X94271Y-505685D01*
X94193Y-506735D01*
X93880Y-507470D01*
X93488Y-508100D01*
X93018Y-508520D01*
X92391Y-508835D01*
X90825D01*
G01X103581D02*
Y-502535D01*
X105540D01*
X106166Y-502850D01*
X106558Y-503270D01*
X106715Y-504110D01*
X106558Y-504950D01*
X106088Y-505475D01*
X105540Y-505790D01*
X103581D01*
G01X105540D02*
X106715Y-508835D01*
G01X109725D02*
Y-502535D01*
X111291D01*
X111918Y-502850D01*
X112388Y-503270D01*
X112780Y-503900D01*
X113093Y-504635D01*
X113171Y-505685D01*
X113093Y-506735D01*
X112780Y-507470D01*
X112388Y-508100D01*
X111918Y-508520D01*
X111291Y-508835D01*
X109725D01*
G01X117748Y-509045D02*
X117591Y-508940D01*
Y-508730D01*
X117748Y-508625D01*
X117905Y-508730D01*
Y-508940D01*
X117748Y-509045D01*
G01X14048Y-498135D02*
X11528Y-497718D01*
X9323Y-496052D01*
X7433Y-493552D01*
X6173Y-490635D01*
X5543Y-487302D01*
Y-483968D01*
X6173Y-480635D01*
X7433Y-477718D01*
X9323Y-475219D01*
X11528Y-473552D01*
X14048Y-473135D01*
X16568Y-473552D01*
X18773Y-475219D01*
X20663Y-477718D01*
X21923Y-480635D01*
X22553Y-483968D01*
Y-487302D01*
X21923Y-490635D01*
X20663Y-493552D01*
X18773Y-496052D01*
X16568Y-497718D01*
X14048Y-498135D01*
G01X16568Y-491468D02*
X20348Y-498135D01*
G01X33893Y-481469D02*
Y-493135D01*
X35153Y-496052D01*
X37043Y-497718D01*
X39248Y-498135D01*
X41453Y-497718D01*
X43343Y-496052D01*
X44603Y-493135D01*
G01Y-498135D02*
Y-481469D01*
G01X70118Y-498135D02*
Y-481469D01*
G01Y-484385D02*
X68858Y-482719D01*
X66968Y-481885D01*
X64763Y-481469D01*
X62558Y-482302D01*
X60668Y-483968D01*
X59408Y-486469D01*
X58778Y-489802D01*
X59408Y-493135D01*
X60668Y-495636D01*
X62558Y-497302D01*
X64763Y-498135D01*
X66968Y-497718D01*
X68858Y-496469D01*
X70118Y-494802D01*
G01X84293Y-498135D02*
Y-481469D01*
G01Y-485635D02*
X85553Y-483552D01*
X87443Y-481885D01*
X89963Y-481469D01*
X92168Y-481885D01*
X94058Y-483552D01*
X95003Y-486469D01*
Y-498135D01*
G01X114848Y-473135D02*
Y-498135D01*
G01X110438Y-481469D02*
X119258D01*
G01X145718Y-498135D02*
Y-481469D01*
G01Y-484385D02*
X144458Y-482719D01*
X142568Y-481885D01*
X140363Y-481469D01*
X138158Y-482302D01*
X136268Y-483968D01*
X135008Y-486469D01*
X134378Y-489802D01*
X135008Y-493135D01*
X136268Y-495636D01*
X138158Y-497302D01*
X140363Y-498135D01*
X142568Y-497718D01*
X144458Y-496469D01*
X145718Y-494802D01*
G01X185398Y-477835D02*
Y-485835D01*
X189398D01*
G01X197198D02*
Y-480502D01*
G01Y-481435D02*
X196798Y-480902D01*
X196198Y-480635D01*
X195498Y-480502D01*
X194798Y-480768D01*
X194198Y-481302D01*
X193798Y-482102D01*
X193598Y-483168D01*
X193798Y-484235D01*
X194198Y-485035D01*
X194798Y-485568D01*
X195498Y-485835D01*
X196198Y-485702D01*
X196798Y-485302D01*
X197198Y-484769D01*
G01X201298Y-488235D02*
X201898Y-488502D01*
X202698Y-488235D01*
X203198Y-487702D01*
X203598Y-487035D01*
X204198Y-484902D01*
X205498Y-480502D01*
G01X202298D02*
X204198Y-484902D01*
G01X209898Y-482235D02*
X213098D01*
X212798Y-481302D01*
X212298Y-480768D01*
X211598Y-480502D01*
X210898Y-480635D01*
X210298Y-481035D01*
X209898Y-481968D01*
X209698Y-482769D01*
Y-483568D01*
X209898Y-484368D01*
X210398Y-485168D01*
X210998Y-485702D01*
X211698Y-485835D01*
X212398Y-485568D01*
X213098Y-484769D01*
G01X217998Y-485835D02*
Y-480502D01*
G01Y-481568D02*
X218498Y-481035D01*
X218998Y-480635D01*
X219698Y-480502D01*
X220198Y-480635D01*
X220798Y-481035D01*
G01X211398Y-535835D02*
Y-532235D01*
X209398Y-527835D01*
G01X213398D02*
X211398Y-532235D01*
G01X217698Y-530502D02*
Y-534235D01*
X218098Y-535168D01*
X218698Y-535702D01*
X219398Y-535835D01*
X220098Y-535702D01*
X220698Y-535168D01*
X221098Y-534235D01*
G01Y-535835D02*
Y-530502D01*
G01X225698Y-535835D02*
Y-530502D01*
G01Y-531835D02*
X226098Y-531168D01*
X226698Y-530635D01*
X227498Y-530502D01*
X228198Y-530635D01*
X228798Y-531168D01*
X229098Y-532102D01*
Y-535835D01*
G01X237198D02*
Y-530502D01*
G01Y-531435D02*
X236798Y-530902D01*
X236198Y-530635D01*
X235498Y-530502D01*
X234798Y-530768D01*
X234198Y-531302D01*
X233798Y-532102D01*
X233598Y-533168D01*
X233798Y-534235D01*
X234198Y-535035D01*
X234798Y-535568D01*
X235498Y-535835D01*
X236198Y-535702D01*
X236798Y-535302D01*
X237198Y-534769D01*
G01X221998Y-504335D02*
X223998D01*
Y-506735D01*
X223398Y-507535D01*
X222698Y-508068D01*
X221698Y-508335D01*
X220698Y-508068D01*
X219998Y-507535D01*
X219398Y-506735D01*
X218998Y-505802D01*
X218798Y-504735D01*
Y-503802D01*
X218998Y-503002D01*
X219398Y-502068D01*
X219998Y-501268D01*
X220598Y-500735D01*
X221398Y-500335D01*
X222098D01*
X222898Y-500602D01*
X223498Y-501135D01*
G01X227098Y-508335D02*
Y-500335D01*
X231698Y-508335D01*
Y-500335D01*
G01X235198Y-508335D02*
Y-500335D01*
X237198D01*
X237998Y-500735D01*
X238598Y-501268D01*
X239098Y-502068D01*
X239498Y-503002D01*
X239598Y-504335D01*
X239498Y-505668D01*
X239098Y-506602D01*
X238598Y-507402D01*
X237998Y-507935D01*
X237198Y-508335D01*
X235198D01*
G01X243198Y-506735D02*
X243798Y-507668D01*
X244598Y-508202D01*
X245498Y-508335D01*
X246298Y-508202D01*
X247098Y-507535D01*
X247598Y-506735D01*
X247698Y-505935D01*
X247498Y-505002D01*
X246798Y-504335D01*
X246098Y-504068D01*
X245198D01*
G01X246098D02*
X246698Y-503668D01*
X247198Y-503002D01*
X247398Y-502202D01*
X247198Y-501402D01*
X246698Y-500735D01*
X245798Y-500335D01*
X244898Y-500468D01*
X243998Y-501002D01*
G01X239698Y-484902D02*
X240398Y-485568D01*
X241198Y-485835D01*
X241998Y-485568D01*
X242698Y-484769D01*
X243198Y-483568D01*
X243398Y-482368D01*
Y-480902D01*
X243198Y-479702D01*
X242698Y-478635D01*
X242098Y-478102D01*
X241398Y-477835D01*
X240598Y-478102D01*
X239998Y-478635D01*
X239598Y-479435D01*
X239398Y-480502D01*
X239598Y-481435D01*
X240098Y-482368D01*
X240698Y-482902D01*
X241398Y-483035D01*
X242198Y-482769D01*
X242798Y-482102D01*
X243398Y-480902D01*
G01X311998Y-529168D02*
X312598Y-528368D01*
X313298Y-527968D01*
X314098Y-527835D01*
X315098Y-528102D01*
X315798Y-528768D01*
X315998Y-529568D01*
X315898Y-530369D01*
X315498Y-531035D01*
X313498Y-532368D01*
X312598Y-533302D01*
X311998Y-534635D01*
X311798Y-535835D01*
X315998D01*
G01X321898Y-527835D02*
X321098Y-528102D01*
X320498Y-528768D01*
X320098Y-529568D01*
X319798Y-530635D01*
X319698Y-531835D01*
X319798Y-533035D01*
X320098Y-534102D01*
X320498Y-534902D01*
X321098Y-535568D01*
X321898Y-535835D01*
X322698Y-535568D01*
X323298Y-534902D01*
X323698Y-534102D01*
X323998Y-533035D01*
X324098Y-531835D01*
X323998Y-530635D01*
X323698Y-529568D01*
X323298Y-528768D01*
X322698Y-528102D01*
X321898Y-527835D01*
G01X327998Y-529168D02*
X328598Y-528368D01*
X329298Y-527968D01*
X330098Y-527835D01*
X331098Y-528102D01*
X331798Y-528768D01*
X331998Y-529568D01*
X331898Y-530369D01*
X331498Y-531035D01*
X329498Y-532368D01*
X328598Y-533302D01*
X327998Y-534635D01*
X327798Y-535835D01*
X331998D01*
G01X335698Y-534235D02*
X336298Y-535168D01*
X337098Y-535702D01*
X337998Y-535835D01*
X338798Y-535702D01*
X339598Y-535035D01*
X340098Y-534235D01*
X340198Y-533435D01*
X339998Y-532502D01*
X339298Y-531835D01*
X338598Y-531568D01*
X337698D01*
G01X338598D02*
X339198Y-531168D01*
X339698Y-530502D01*
X339898Y-529702D01*
X339698Y-528902D01*
X339198Y-528235D01*
X338298Y-527835D01*
X337398Y-527968D01*
X336498Y-528502D01*
G01X344098Y-536102D02*
X347698Y-527835D01*
G01X353898D02*
X353098Y-528102D01*
X352498Y-528768D01*
X352098Y-529568D01*
X351798Y-530635D01*
X351698Y-531835D01*
X351798Y-533035D01*
X352098Y-534102D01*
X352498Y-534902D01*
X353098Y-535568D01*
X353898Y-535835D01*
X354698Y-535568D01*
X355298Y-534902D01*
X355698Y-534102D01*
X355998Y-533035D01*
X356098Y-531835D01*
X355998Y-530635D01*
X355698Y-529568D01*
X355298Y-528768D01*
X354698Y-528102D01*
X353898Y-527835D01*
G01X361898Y-535835D02*
Y-527835D01*
X360698Y-529435D01*
G01Y-535835D02*
X363098D01*
G01X368098Y-536102D02*
X371698Y-527835D01*
G01X377898D02*
X377098Y-528102D01*
X376498Y-528768D01*
X376098Y-529568D01*
X375798Y-530635D01*
X375698Y-531835D01*
X375798Y-533035D01*
X376098Y-534102D01*
X376498Y-534902D01*
X377098Y-535568D01*
X377898Y-535835D01*
X378698Y-535568D01*
X379298Y-534902D01*
X379698Y-534102D01*
X379998Y-533035D01*
X380098Y-531835D01*
X379998Y-530635D01*
X379698Y-529568D01*
X379298Y-528768D01*
X378698Y-528102D01*
X377898Y-527835D01*
G01X384198Y-534902D02*
X384898Y-535568D01*
X385698Y-535835D01*
X386498Y-535568D01*
X387198Y-534769D01*
X387698Y-533568D01*
X387898Y-532368D01*
Y-530902D01*
X387698Y-529702D01*
X387198Y-528635D01*
X386598Y-528102D01*
X385898Y-527835D01*
X385098Y-528102D01*
X384498Y-528635D01*
X384098Y-529435D01*
X383898Y-530502D01*
X384098Y-531435D01*
X384598Y-532368D01*
X385198Y-532902D01*
X385898Y-533035D01*
X386698Y-532769D01*
X387298Y-532102D01*
X387898Y-530902D01*
G01X311698Y-510835D02*
Y-502835D01*
X313698D01*
X314498Y-503235D01*
X315098Y-503768D01*
X315598Y-504568D01*
X315998Y-505502D01*
X316098Y-506835D01*
X315998Y-508168D01*
X315598Y-509102D01*
X315098Y-509902D01*
X314498Y-510435D01*
X313698Y-510835D01*
X311698D01*
G01X319398D02*
X321898Y-502835D01*
X324398Y-510835D01*
G01X323498Y-508035D02*
X320298D01*
G01X329898Y-502835D02*
X329098Y-503102D01*
X328498Y-503768D01*
X328098Y-504568D01*
X327798Y-505635D01*
X327698Y-506835D01*
X327798Y-508035D01*
X328098Y-509102D01*
X328498Y-509902D01*
X329098Y-510568D01*
X329898Y-510835D01*
X330698Y-510568D01*
X331298Y-509902D01*
X331698Y-509102D01*
X331998Y-508035D01*
X332098Y-506835D01*
X331998Y-505635D01*
X331698Y-504568D01*
X331298Y-503768D01*
X330698Y-503102D01*
X329898Y-502835D01*
G01X335998Y-510835D02*
Y-502835D01*
X339798D01*
G01X338398Y-506702D02*
X335998D01*
G01X345898Y-502835D02*
X345098Y-503102D01*
X344498Y-503768D01*
X344098Y-504568D01*
X343798Y-505635D01*
X343698Y-506835D01*
X343798Y-508035D01*
X344098Y-509102D01*
X344498Y-509902D01*
X345098Y-510568D01*
X345898Y-510835D01*
X346698Y-510568D01*
X347298Y-509902D01*
X347698Y-509102D01*
X347998Y-508035D01*
X348098Y-506835D01*
X347998Y-505635D01*
X347698Y-504568D01*
X347298Y-503768D01*
X346698Y-503102D01*
X345898Y-502835D01*
G01X353898D02*
Y-510835D01*
G01X351598Y-502835D02*
X356198D01*
G01X363898Y-510835D02*
X359898D01*
Y-502835D01*
X363898D01*
G01X362298Y-506702D02*
X359898D01*
G01X370698Y-506568D02*
X371098Y-506168D01*
X371398Y-505502D01*
X371598Y-504568D01*
X371398Y-503768D01*
X370998Y-503235D01*
X370298Y-502835D01*
X367598D01*
Y-510835D01*
X370898D01*
X371598Y-510302D01*
X371998Y-509502D01*
X372198Y-508568D01*
X371998Y-507635D01*
X371398Y-506835D01*
X370698Y-506568D01*
X367598D01*
G01X376698Y-502835D02*
X379098D01*
G01X377898D02*
Y-510835D01*
G01X376698D02*
X379098D01*
G01X383998D02*
Y-502835D01*
X387798D01*
G01X386398Y-506702D02*
X383998D01*
G01X393898Y-502835D02*
X393098Y-503102D01*
X392498Y-503768D01*
X392098Y-504568D01*
X391798Y-505635D01*
X391698Y-506835D01*
X391798Y-508035D01*
X392098Y-509102D01*
X392498Y-509902D01*
X393098Y-510568D01*
X393898Y-510835D01*
X394698Y-510568D01*
X395298Y-509902D01*
X395698Y-509102D01*
X395998Y-508035D01*
X396098Y-506835D01*
X395998Y-505635D01*
X395698Y-504568D01*
X395298Y-503768D01*
X394698Y-503102D01*
X393898Y-502835D01*
G01X329498Y-485835D02*
Y-477835D01*
X333298D01*
G01X331898Y-481702D02*
X329498D01*
G01X339398Y-477835D02*
X338598Y-478102D01*
X337998Y-478768D01*
X337598Y-479568D01*
X337298Y-480635D01*
X337198Y-481835D01*
X337298Y-483035D01*
X337598Y-484102D01*
X337998Y-484902D01*
X338598Y-485568D01*
X339398Y-485835D01*
X340198Y-485568D01*
X340798Y-484902D01*
X341198Y-484102D01*
X341498Y-483035D01*
X341598Y-481835D01*
X341498Y-480635D01*
X341198Y-479568D01*
X340798Y-478768D01*
X340198Y-478102D01*
X339398Y-477835D01*
G01X347398D02*
Y-485835D01*
G01X345098Y-477835D02*
X349698D01*
G01X352398Y-488502D02*
X358398D01*
G01X361898Y-482235D02*
X365098D01*
X364798Y-481302D01*
X364298Y-480768D01*
X363598Y-480502D01*
X362898Y-480635D01*
X362298Y-481035D01*
X361898Y-481968D01*
X361698Y-482769D01*
Y-483568D01*
X361898Y-484368D01*
X362398Y-485168D01*
X362998Y-485702D01*
X363698Y-485835D01*
X364398Y-485568D01*
X365098Y-484769D01*
G01X369898Y-480502D02*
X372898Y-485835D01*
G01Y-480502D02*
X369898Y-485835D01*
G01X377598Y-488502D02*
Y-480502D01*
G01Y-481702D02*
X378098Y-481035D01*
X378598Y-480635D01*
X379398Y-480502D01*
X380098Y-480635D01*
X380798Y-481302D01*
X381098Y-482235D01*
X381198Y-483168D01*
X381098Y-484102D01*
X380798Y-485035D01*
X380198Y-485568D01*
X379398Y-485835D01*
X378698Y-485702D01*
X377998Y-485302D01*
X377598Y-484769D01*
G01X389198Y-485835D02*
Y-480502D01*
G01Y-481435D02*
X388798Y-480902D01*
X388198Y-480635D01*
X387498Y-480502D01*
X386798Y-480768D01*
X386198Y-481302D01*
X385798Y-482102D01*
X385598Y-483168D01*
X385798Y-484235D01*
X386198Y-485035D01*
X386798Y-485568D01*
X387498Y-485835D01*
X388198Y-485702D01*
X388798Y-485302D01*
X389198Y-484769D01*
G01X393698Y-485835D02*
Y-480502D01*
G01Y-481835D02*
X394098Y-481168D01*
X394698Y-480635D01*
X395498Y-480502D01*
X396198Y-480635D01*
X396798Y-481168D01*
X397098Y-482102D01*
Y-485835D01*
G01X405198Y-477835D02*
Y-485835D01*
G01Y-484635D02*
X404798Y-485302D01*
X404198Y-485702D01*
X403498Y-485835D01*
X402698Y-485568D01*
X402098Y-484902D01*
X401698Y-484102D01*
X401598Y-483168D01*
X401698Y-482235D01*
X402098Y-481435D01*
X402698Y-480768D01*
X403498Y-480502D01*
X404198Y-480635D01*
X404698Y-480902D01*
X405198Y-481435D01*
G01X409898Y-482235D02*
X413098D01*
X412798Y-481302D01*
X412298Y-480768D01*
X411598Y-480502D01*
X410898Y-480635D01*
X410298Y-481035D01*
X409898Y-481968D01*
X409698Y-482769D01*
Y-483568D01*
X409898Y-484368D01*
X410398Y-485168D01*
X410998Y-485702D01*
X411698Y-485835D01*
X412398Y-485568D01*
X413098Y-484769D01*
G01X417998Y-485835D02*
Y-480502D01*
G01Y-481568D02*
X418498Y-481035D01*
X418998Y-480635D01*
X419698Y-480502D01*
X420198Y-480635D01*
X420798Y-481035D01*
G01X424398Y-488502D02*
X430398D01*
G01X433598Y-485835D02*
Y-477835D01*
G01Y-481835D02*
X434098Y-481035D01*
X434698Y-480635D01*
X435298Y-480502D01*
X436198Y-480768D01*
X436798Y-481302D01*
X437198Y-482235D01*
Y-483302D01*
X436998Y-484368D01*
X436598Y-485168D01*
X435898Y-485702D01*
X435298Y-485835D01*
X434698Y-485702D01*
X434098Y-485302D01*
X433598Y-484635D01*
G01X445198Y-477835D02*
Y-485835D01*
G01Y-484635D02*
X444798Y-485302D01*
X444198Y-485702D01*
X443498Y-485835D01*
X442698Y-485568D01*
X442098Y-484902D01*
X441698Y-484102D01*
X441598Y-483168D01*
X441698Y-482235D01*
X442098Y-481435D01*
X442698Y-480768D01*
X443498Y-480502D01*
X444198Y-480635D01*
X444698Y-480902D01*
X445198Y-481435D01*
G01X400398Y-538835D02*
Y-530835D01*
X399198Y-532435D01*
G01Y-538835D02*
X401598D01*
G01X406498Y-535502D02*
X407198Y-534568D01*
X407798Y-534035D01*
X408598Y-533768D01*
X409298Y-534035D01*
X409798Y-534568D01*
X410198Y-535368D01*
X410298Y-536302D01*
X410198Y-537102D01*
X409798Y-537902D01*
X409198Y-538568D01*
X408498Y-538835D01*
X407698Y-538568D01*
X406998Y-537769D01*
X406598Y-536568D01*
X406498Y-535235D01*
X406698Y-533502D01*
X406998Y-532568D01*
X407498Y-531635D01*
X408198Y-530968D01*
X408898Y-530835D01*
X409598Y-531102D01*
X410098Y-531768D01*
G01X416398Y-539102D02*
X416198Y-538968D01*
Y-538702D01*
X416398Y-538568D01*
X416598Y-538702D01*
Y-538968D01*
X416398Y-539102D01*
G01X422498Y-535502D02*
X423198Y-534568D01*
X423798Y-534035D01*
X424598Y-533768D01*
X425298Y-534035D01*
X425798Y-534568D01*
X426198Y-535368D01*
X426298Y-536302D01*
X426198Y-537102D01*
X425798Y-537902D01*
X425198Y-538568D01*
X424498Y-538835D01*
X423698Y-538568D01*
X422998Y-537769D01*
X422598Y-536568D01*
X422498Y-535235D01*
X422698Y-533502D01*
X422998Y-532568D01*
X423498Y-531635D01*
X424198Y-530968D01*
X424898Y-530835D01*
X425598Y-531102D01*
X426098Y-531768D01*
G01X445398Y-538835D02*
Y-530835D01*
X444198Y-532435D01*
G01Y-538835D02*
X446598D01*
G01X453198D02*
X453398Y-537102D01*
X453698Y-535635D01*
X454098Y-534302D01*
X454598Y-532835D01*
X455398Y-530835D01*
X451398D01*
G01X461398Y-539102D02*
X461198Y-538968D01*
Y-538702D01*
X461398Y-538568D01*
X461598Y-538702D01*
Y-538968D01*
X461398Y-539102D01*
G01X467498Y-532168D02*
X468098Y-531368D01*
X468798Y-530968D01*
X469598Y-530835D01*
X470598Y-531102D01*
X471298Y-531768D01*
X471498Y-532568D01*
X471398Y-533369D01*
X470998Y-534035D01*
X468998Y-535368D01*
X468098Y-536302D01*
X467498Y-537635D01*
X467298Y-538835D01*
X471498D01*
G01X465498Y-513835D02*
Y-505835D01*
X469298D01*
G01X467898Y-509702D02*
X465498D01*
M02*
